(lib_symbols
	(symbol "antmicroB2BConnectors:Plug_Molex_SlimStack_2x25_529910508"
			(exclude_from_sim no)
			(in_bom yes)
			(on_board yes)
			(property "Reference" "J"
				(at 25.4 0 0)
				(effects
					(font
						(size 1.27 1.27)
						(thickness 0.15)
					)
					(justify left bottom)
				)
			)
			(property "Value" "Plug_Molex_SlimStack_2x25_529910508"
				(at 25.4 -5.08 0)
				(effects
					(font
						(size 1.27 1.27)
						(thickness 0.15)
					)
					(justify left bottom)
					(hide yes)
				)
			)
			(property "Footprint" "antmicro-footprints:Conn_Plug_Molex_SlimStack_2x25_529910508"
				(at 25.4 -7.62 0)
				(effects
					(font
						(size 1.27 1.27)
						(thickness 0.15)
					)
					(justify left bottom)
					(hide yes)
				)
			)
			(property "Datasheet" "https://www.molex.com/en-us/products/part-detail/529910508?display=pdf"
				(at 25.4 -10.16 0)
				(effects
					(font
						(size 1.27 1.27)
						(thickness 0.15)
					)
					(justify left bottom)
					(hide yes)
				)
			)
			(property "Description" "Mezzanine Connector, Receptacle, 0.5mm, 2Rows, 50Contacts, Surface Mount, Phosphor Bronze"
				(at 25.4 -22.86 0)
				(effects
					(font
						(size 1.27 1.27)
					)
					(justify left bottom)
					(hide yes)
				)
			)
			(property "MPN" "529910508"
				(at 25.4 -2.54 0)
				(effects
					(font
						(size 1.27 1.27)
						(thickness 0.15)
					)
					(justify left bottom)
				)
			)
			(property "Manufacturer" "Molex"
				(at 25.4 -12.7 0)
				(effects
					(font
						(size 1.27 1.27)
						(thickness 0.15)
					)
					(justify left bottom)
					(hide yes)
				)
			)
			(property "Author" "Antmicro"
				(at 25.4 -17.78 0)
				(effects
					(font
						(size 1.27 1.27)
						(thickness 0.15)
					)
					(justify left bottom)
					(hide yes)
				)
			)
			(property "License" "Apache-2.0"
				(at 25.4 -20.32 0)
				(effects
					(font
						(size 1.27 1.27)
						(thickness 0.15)
					)
					(justify left bottom)
					(hide yes)
				)
			)
			(property "Pitch " "0.5 mm"
				(at 25.4 -15.24 0)
				(effects
					(font
						(size 1.27 1.27)
					)
					(justify left bottom)
					(hide yes)
				)
			)
			(property "ki_keywords" "CONNECTOR, B2B, PLUG"
				(at 0 0 0)
				(effects
					(font
						(size 1.27 1.27)
					)
					(hide yes)
				)
			)
			(symbol "Plug_Molex_SlimStack_2x25_529910508_1_1"
				(rectangle
					(start 2.54 2.54)
					(end 8.89 -63.5)
					(stroke
						(width 0.254)
						(type default)
					)
					(fill
						(type background)
					)
				)
				(rectangle
					(start 3.81 1.27)
					(end 7.62 -62.23)
					(stroke
						(width 0.254)
						(type default)
					)
					(fill
						(type background)
					)
				)
				(pin passive line
					(at 0 0 0)
					(length 2.54)
					(name "~"
						(effects
							(font
								(size 1.27 1.27)
							)
						)
					)
					(number "1"
						(effects
							(font
								(size 1.27 1.27)
							)
						)
					)
				)
				(pin passive line
					(at 0 -2.54 0)
					(length 2.54)
					(name "~"
						(effects
							(font
								(size 1.27 1.27)
							)
						)
					)
					(number "3"
						(effects
							(font
								(size 1.27 1.27)
							)
						)
					)
				)
				(pin passive line
					(at 0 -5.08 0)
					(length 2.54)
					(name "~"
						(effects
							(font
								(size 1.27 1.27)
							)
						)
					)
					(number "5"
						(effects
							(font
								(size 1.27 1.27)
							)
						)
					)
				)
				(pin passive line
					(at 0 -7.62 0)
					(length 2.54)
					(name "~"
						(effects
							(font
								(size 1.27 1.27)
							)
						)
					)
					(number "7"
						(effects
							(font
								(size 1.27 1.27)
							)
						)
					)
				)
				(pin passive line
					(at 0 -10.16 0)
					(length 2.54)
					(name "~"
						(effects
							(font
								(size 1.27 1.27)
							)
						)
					)
					(number "9"
						(effects
							(font
								(size 1.27 1.27)
							)
						)
					)
				)
				(pin passive line
					(at 0 -12.7 0)
					(length 2.54)
					(name "~"
						(effects
							(font
								(size 1.27 1.27)
							)
						)
					)
					(number "11"
						(effects
							(font
								(size 1.27 1.27)
							)
						)
					)
				)
				(pin passive line
					(at 0 -15.24 0)
					(length 2.54)
					(name "~"
						(effects
							(font
								(size 1.27 1.27)
							)
						)
					)
					(number "13"
						(effects
							(font
								(size 1.27 1.27)
							)
						)
					)
				)
				(pin passive line
					(at 0 -17.78 0)
					(length 2.54)
					(name "~"
						(effects
							(font
								(size 1.27 1.27)
							)
						)
					)
					(number "15"
						(effects
							(font
								(size 1.27 1.27)
							)
						)
					)
				)
				(pin passive line
					(at 0 -20.32 0)
					(length 2.54)
					(name "~"
						(effects
							(font
								(size 1.27 1.27)
							)
						)
					)
					(number "17"
						(effects
							(font
								(size 1.27 1.27)
							)
						)
					)
				)
				(pin passive line
					(at 0 -22.86 0)
					(length 2.54)
					(name "~"
						(effects
							(font
								(size 1.27 1.27)
							)
						)
					)
					(number "19"
						(effects
							(font
								(size 1.27 1.27)
							)
						)
					)
				)
				(pin passive line
					(at 0 -25.4 0)
					(length 2.54)
					(name "~"
						(effects
							(font
								(size 1.27 1.27)
							)
						)
					)
					(number "21"
						(effects
							(font
								(size 1.27 1.27)
							)
						)
					)
				)
				(pin passive line
					(at 0 -27.94 0)
					(length 2.54)
					(name "~"
						(effects
							(font
								(size 1.27 1.27)
							)
						)
					)
					(number "23"
						(effects
							(font
								(size 1.27 1.27)
							)
						)
					)
				)
				(pin passive line
					(at 0 -30.48 0)
					(length 2.54)
					(name "~"
						(effects
							(font
								(size 1.27 1.27)
							)
						)
					)
					(number "25"
						(effects
							(font
								(size 1.27 1.27)
							)
						)
					)
				)
				(pin passive line
					(at 0 -33.02 0)
					(length 2.54)
					(name "~"
						(effects
							(font
								(size 1.27 1.27)
							)
						)
					)
					(number "27"
						(effects
							(font
								(size 1.27 1.27)
							)
						)
					)
				)
				(pin passive line
					(at 0 -35.56 0)
					(length 2.54)
					(name "~"
						(effects
							(font
								(size 1.27 1.27)
							)
						)
					)
					(number "29"
						(effects
							(font
								(size 1.27 1.27)
							)
						)
					)
				)
				(pin passive line
					(at 0 -38.1 0)
					(length 2.54)
					(name "~"
						(effects
							(font
								(size 1.27 1.27)
							)
						)
					)
					(number "31"
						(effects
							(font
								(size 1.27 1.27)
							)
						)
					)
				)
				(pin passive line
					(at 0 -40.64 0)
					(length 2.54)
					(name "~"
						(effects
							(font
								(size 1.27 1.27)
							)
						)
					)
					(number "33"
						(effects
							(font
								(size 1.27 1.27)
							)
						)
					)
				)
				(pin passive line
					(at 0 -43.18 0)
					(length 2.54)
					(name "~"
						(effects
							(font
								(size 1.27 1.27)
							)
						)
					)
					(number "35"
						(effects
							(font
								(size 1.27 1.27)
							)
						)
					)
				)
				(pin passive line
					(at 0 -45.72 0)
					(length 2.54)
					(name "~"
						(effects
							(font
								(size 1.27 1.27)
							)
						)
					)
					(number "37"
						(effects
							(font
								(size 1.27 1.27)
							)
						)
					)
				)
				(pin passive line
					(at 0 -48.26 0)
					(length 2.54)
					(name "~"
						(effects
							(font
								(size 1.27 1.27)
							)
						)
					)
					(number "39"
						(effects
							(font
								(size 1.27 1.27)
							)
						)
					)
				)
				(pin passive line
					(at 0 -50.8 0)
					(length 2.54)
					(name "~"
						(effects
							(font
								(size 1.27 1.27)
							)
						)
					)
					(number "41"
						(effects
							(font
								(size 1.27 1.27)
							)
						)
					)
				)
				(pin passive line
					(at 0 -53.34 0)
					(length 2.54)
					(name "~"
						(effects
							(font
								(size 1.27 1.27)
							)
						)
					)
					(number "43"
						(effects
							(font
								(size 1.27 1.27)
							)
						)
					)
				)
				(pin passive line
					(at 0 -55.88 0)
					(length 2.54)
					(name "~"
						(effects
							(font
								(size 1.27 1.27)
							)
						)
					)
					(number "45"
						(effects
							(font
								(size 1.27 1.27)
							)
						)
					)
				)
				(pin passive line
					(at 0 -58.42 0)
					(length 2.54)
					(name "~"
						(effects
							(font
								(size 1.27 1.27)
							)
						)
					)
					(number "47"
						(effects
							(font
								(size 1.27 1.27)
							)
						)
					)
				)
				(pin passive line
					(at 0 -60.96 0)
					(length 2.54)
					(name "~"
						(effects
							(font
								(size 1.27 1.27)
							)
						)
					)
					(number "49"
						(effects
							(font
								(size 1.27 1.27)
							)
						)
					)
				)
				(pin passive line
					(at 11.43 0 180)
					(length 2.54)
					(name "~"
						(effects
							(font
								(size 1.27 1.27)
							)
						)
					)
					(number "2"
						(effects
							(font
								(size 1.27 1.27)
							)
						)
					)
				)
				(pin passive line
					(at 11.43 -2.54 180)
					(length 2.54)
					(name "~"
						(effects
							(font
								(size 1.27 1.27)
							)
						)
					)
					(number "4"
						(effects
							(font
								(size 1.27 1.27)
							)
						)
					)
				)
				(pin passive line
					(at 11.43 -5.08 180)
					(length 2.54)
					(name "~"
						(effects
							(font
								(size 1.27 1.27)
							)
						)
					)
					(number "6"
						(effects
							(font
								(size 1.27 1.27)
							)
						)
					)
				)
				(pin passive line
					(at 11.43 -7.62 180)
					(length 2.54)
					(name "~"
						(effects
							(font
								(size 1.27 1.27)
							)
						)
					)
					(number "8"
						(effects
							(font
								(size 1.27 1.27)
							)
						)
					)
				)
				(pin passive line
					(at 11.43 -10.16 180)
					(length 2.54)
					(name "~"
						(effects
							(font
								(size 1.27 1.27)
							)
						)
					)
					(number "10"
						(effects
							(font
								(size 1.27 1.27)
							)
						)
					)
				)
				(pin passive line
					(at 11.43 -12.7 180)
					(length 2.54)
					(name "~"
						(effects
							(font
								(size 1.27 1.27)
							)
						)
					)
					(number "12"
						(effects
							(font
								(size 1.27 1.27)
							)
						)
					)
				)
				(pin passive line
					(at 11.43 -15.24 180)
					(length 2.54)
					(name "~"
						(effects
							(font
								(size 1.27 1.27)
							)
						)
					)
					(number "14"
						(effects
							(font
								(size 1.27 1.27)
							)
						)
					)
				)
				(pin passive line
					(at 11.43 -17.78 180)
					(length 2.54)
					(name "~"
						(effects
							(font
								(size 1.27 1.27)
							)
						)
					)
					(number "16"
						(effects
							(font
								(size 1.27 1.27)
							)
						)
					)
				)
				(pin passive line
					(at 11.43 -20.32 180)
					(length 2.54)
					(name "~"
						(effects
							(font
								(size 1.27 1.27)
							)
						)
					)
					(number "18"
						(effects
							(font
								(size 1.27 1.27)
							)
						)
					)
				)
				(pin passive line
					(at 11.43 -22.86 180)
					(length 2.54)
					(name "~"
						(effects
							(font
								(size 1.27 1.27)
							)
						)
					)
					(number "20"
						(effects
							(font
								(size 1.27 1.27)
							)
						)
					)
				)
				(pin passive line
					(at 11.43 -25.4 180)
					(length 2.54)
					(name "~"
						(effects
							(font
								(size 1.27 1.27)
							)
						)
					)
					(number "22"
						(effects
							(font
								(size 1.27 1.27)
							)
						)
					)
				)
				(pin passive line
					(at 11.43 -27.94 180)
					(length 2.54)
					(name "~"
						(effects
							(font
								(size 1.27 1.27)
							)
						)
					)
					(number "24"
						(effects
							(font
								(size 1.27 1.27)
							)
						)
					)
				)
				(pin passive line
					(at 11.43 -30.48 180)
					(length 2.54)
					(name "~"
						(effects
							(font
								(size 1.27 1.27)
							)
						)
					)
					(number "26"
						(effects
							(font
								(size 1.27 1.27)
							)
						)
					)
				)
				(pin passive line
					(at 11.43 -33.02 180)
					(length 2.54)
					(name "~"
						(effects
							(font
								(size 1.27 1.27)
							)
						)
					)
					(number "28"
						(effects
							(font
								(size 1.27 1.27)
							)
						)
					)
				)
				(pin passive line
					(at 11.43 -35.56 180)
					(length 2.54)
					(name "~"
						(effects
							(font
								(size 1.27 1.27)
							)
						)
					)
					(number "30"
						(effects
							(font
								(size 1.27 1.27)
							)
						)
					)
				)
				(pin passive line
					(at 11.43 -38.1 180)
					(length 2.54)
					(name "~"
						(effects
							(font
								(size 1.27 1.27)
							)
						)
					)
					(number "32"
						(effects
							(font
								(size 1.27 1.27)
							)
						)
					)
				)
				(pin passive line
					(at 11.43 -40.64 180)
					(length 2.54)
					(name "~"
						(effects
							(font
								(size 1.27 1.27)
							)
						)
					)
					(number "34"
						(effects
							(font
								(size 1.27 1.27)
							)
						)
					)
				)
				(pin passive line
					(at 11.43 -43.18 180)
					(length 2.54)
					(name "~"
						(effects
							(font
								(size 1.27 1.27)
							)
						)
					)
					(number "36"
						(effects
							(font
								(size 1.27 1.27)
							)
						)
					)
				)
				(pin passive line
					(at 11.43 -45.72 180)
					(length 2.54)
					(name "~"
						(effects
							(font
								(size 1.27 1.27)
							)
						)
					)
					(number "38"
						(effects
							(font
								(size 1.27 1.27)
							)
						)
					)
				)
				(pin passive line
					(at 11.43 -48.26 180)
					(length 2.54)
					(name "~"
						(effects
							(font
								(size 1.27 1.27)
							)
						)
					)
					(number "40"
						(effects
							(font
								(size 1.27 1.27)
							)
						)
					)
				)
				(pin passive line
					(at 11.43 -50.8 180)
					(length 2.54)
					(name "~"
						(effects
							(font
								(size 1.27 1.27)
							)
						)
					)
					(number "42"
						(effects
							(font
								(size 1.27 1.27)
							)
						)
					)
				)
				(pin passive line
					(at 11.43 -53.34 180)
					(length 2.54)
					(name "~"
						(effects
							(font
								(size 1.27 1.27)
							)
						)
					)
					(number "44"
						(effects
							(font
								(size 1.27 1.27)
							)
						)
					)
				)
				(pin passive line
					(at 11.43 -55.88 180)
					(length 2.54)
					(name "~"
						(effects
							(font
								(size 1.27 1.27)
							)
						)
					)
					(number "46"
						(effects
							(font
								(size 1.27 1.27)
							)
						)
					)
				)
				(pin passive line
					(at 11.43 -58.42 180)
					(length 2.54)
					(name "~"
						(effects
							(font
								(size 1.27 1.27)
							)
						)
					)
					(number "48"
						(effects
							(font
								(size 1.27 1.27)
							)
						)
					)
				)
				(pin passive line
					(at 11.43 -60.96 180)
					(length 2.54)
					(name "~"
						(effects
							(font
								(size 1.27 1.27)
							)
						)
					)
					(number "50"
						(effects
							(font
								(size 1.27 1.27)
							)
						)
					)
				)
			)
		)
	(symbol "antmicroCapacitors0402:C_100n_0402"
			(pin_numbers
				(hide yes)
			)
			(pin_names
				(hide yes)
			)
			(exclude_from_sim no)
			(in_bom yes)
			(on_board yes)
			(property "Reference" "C"
				(at 20.32 -5.08 0)
				(effects
					(font
						(size 1.27 1.27)
						(thickness 0.15)
					)
					(justify left bottom)
				)
			)
			(property "Value" "C_100n_0402"
				(at 20.32 -10.16 0)
				(effects
					(font
						(size 1.27 1.27)
						(thickness 0.15)
					)
					(justify left bottom)
					(hide yes)
				)
			)
			(property "Footprint" "antmicro-footprints:C_0402_1005Metric"
				(at 20.32 -12.7 0)
				(effects
					(font
						(size 1.27 1.27)
						(thickness 0.15)
					)
					(justify left bottom)
					(hide yes)
				)
			)
			(property "Datasheet" "https://www.murata.com/products/productdetail?partno=GRM155R61H104KE14%23"
				(at 20.32 -15.24 0)
				(effects
					(font
						(size 1.27 1.27)
						(thickness 0.15)
					)
					(justify left bottom)
					(hide yes)
				)
			)
			(property "Description" "SMD Multilayer Ceramic Capacitor, 0.1 µF, 50 V, 0402 [1005 Metric], ± 10%, X5R, GRM Series"
				(at 20.32 -33.02 0)
				(effects
					(font
						(size 1.27 1.27)
					)
					(justify left bottom)
					(hide yes)
				)
			)
			(property "MPN" "GRM155R61H104KE14D"
				(at 20.32 -17.78 0)
				(effects
					(font
						(size 1.27 1.27)
						(thickness 0.15)
					)
					(justify left bottom)
					(hide yes)
				)
			)
			(property "Manufacturer" "Murata"
				(at 20.32 -20.32 0)
				(effects
					(font
						(size 1.27 1.27)
						(thickness 0.15)
					)
					(justify left bottom)
					(hide yes)
				)
			)
			(property "License" "Apache-2.0"
				(at 20.32 -22.86 0)
				(effects
					(font
						(size 1.27 1.27)
						(thickness 0.15)
					)
					(justify left bottom)
					(hide yes)
				)
			)
			(property "Author" "Antmicro"
				(at 20.32 -25.4 0)
				(effects
					(font
						(size 1.27 1.27)
						(thickness 0.15)
					)
					(justify left bottom)
					(hide yes)
				)
			)
			(property "Val" "100n"
				(at 20.32 -7.62 0)
				(effects
					(font
						(size 1.27 1.27)
						(thickness 0.15)
					)
					(justify left bottom)
				)
			)
			(property "Voltage" "50V"
				(at 20.32 -27.94 0)
				(effects
					(font
						(size 1.27 1.27)
					)
					(justify left bottom)
					(hide yes)
				)
			)
			(property "Dielectric" "X5R"
				(at 20.32 -30.48 0)
				(effects
					(font
						(size 1.27 1.27)
					)
					(justify left bottom)
					(hide yes)
				)
			)
			(property "ki_keywords" "0402, SMT, CAPACITOR, PASSIVE, CERAMIC, MLCC"
				(at 0 0 0)
				(effects
					(font
						(size 1.27 1.27)
					)
					(hide yes)
				)
			)
			(symbol "C_100n_0402_0_1"
				(polyline
					(pts
						(xy 2.032 -1.524) (xy 2.032 1.524)
					)
					(stroke
						(width 0.3048)
						(type default)
					)
					(fill
						(type none)
					)
				)
				(polyline
					(pts
						(xy 3.048 -1.524) (xy 3.048 1.524)
					)
					(stroke
						(width 0.3302)
						(type default)
					)
					(fill
						(type none)
					)
				)
			)
			(symbol "C_100n_0402_1_1"
				(pin passive line
					(at 0 0 0)
					(length 2.032)
					(name "~"
						(effects
							(font
								(size 1.27 1.27)
							)
						)
					)
					(number "1"
						(effects
							(font
								(size 1.27 1.27)
							)
						)
					)
				)
				(pin passive line
					(at 5.08 0 180)
					(length 2.032)
					(name "~"
						(effects
							(font
								(size 1.27 1.27)
							)
						)
					)
					(number "2"
						(effects
							(font
								(size 1.27 1.27)
							)
						)
					)
				)
			)
		)
	(symbol "antmicroCapacitors0402:C_10n_0402"
			(pin_numbers
				(hide yes)
			)
			(pin_names
				(hide yes)
			)
			(exclude_from_sim no)
			(in_bom yes)
			(on_board yes)
			(property "Reference" "C"
				(at 20.32 -5.08 0)
				(effects
					(font
						(size 1.27 1.27)
						(thickness 0.15)
					)
					(justify left bottom)
				)
			)
			(property "Value" "C_10n_0402"
				(at 20.32 -10.16 0)
				(effects
					(font
						(size 1.27 1.27)
						(thickness 0.15)
					)
					(justify left bottom)
					(hide yes)
				)
			)
			(property "Footprint" "antmicro-footprints:C_0402_1005Metric"
				(at 20.32 -12.7 0)
				(effects
					(font
						(size 1.27 1.27)
						(thickness 0.15)
					)
					(justify left bottom)
					(hide yes)
				)
			)
			(property "Datasheet" "https://www.murata.com/products/productdetail?partno=GRM155R71H103KA88%23"
				(at 20.32 -15.24 0)
				(effects
					(font
						(size 1.27 1.27)
						(thickness 0.15)
					)
					(justify left bottom)
					(hide yes)
				)
			)
			(property "Description" "SMD Multilayer Ceramic Capacitor, 10000 pF, 50 V, 0402 [1005 Metric], ± 10%, X7R, GRM Series"
				(at 20.32 -33.02 0)
				(effects
					(font
						(size 1.27 1.27)
					)
					(justify left bottom)
					(hide yes)
				)
			)
			(property "MPN" "GRM155R71H103KA88D"
				(at 20.32 -17.78 0)
				(effects
					(font
						(size 1.27 1.27)
						(thickness 0.15)
					)
					(justify left bottom)
					(hide yes)
				)
			)
			(property "Manufacturer" "Murata"
				(at 20.32 -20.32 0)
				(effects
					(font
						(size 1.27 1.27)
						(thickness 0.15)
					)
					(justify left bottom)
					(hide yes)
				)
			)
			(property "License" "Apache-2.0"
				(at 20.32 -22.86 0)
				(effects
					(font
						(size 1.27 1.27)
						(thickness 0.15)
					)
					(justify left bottom)
					(hide yes)
				)
			)
			(property "Author" "Antmicro"
				(at 20.32 -25.4 0)
				(effects
					(font
						(size 1.27 1.27)
						(thickness 0.15)
					)
					(justify left bottom)
					(hide yes)
				)
			)
			(property "Val" "10n"
				(at 20.32 -7.62 0)
				(effects
					(font
						(size 1.27 1.27)
						(thickness 0.15)
					)
					(justify left bottom)
				)
			)
			(property "Voltage" "50V"
				(at 20.32 -27.94 0)
				(effects
					(font
						(size 1.27 1.27)
					)
					(justify left bottom)
					(hide yes)
				)
			)
			(property "Dielectric" "X7R"
				(at 20.32 -30.48 0)
				(effects
					(font
						(size 1.27 1.27)
					)
					(justify left bottom)
					(hide yes)
				)
			)
			(property "ki_keywords" "0402, SMT, CAPACITOR, PASSIVE"
				(at 0 0 0)
				(effects
					(font
						(size 1.27 1.27)
					)
					(hide yes)
				)
			)
			(symbol "C_10n_0402_0_1"
				(polyline
					(pts
						(xy 2.032 -1.524) (xy 2.032 1.524)
					)
					(stroke
						(width 0.3048)
						(type default)
					)
					(fill
						(type none)
					)
				)
				(polyline
					(pts
						(xy 3.048 -1.524) (xy 3.048 1.524)
					)
					(stroke
						(width 0.3302)
						(type default)
					)
					(fill
						(type none)
					)
				)
			)
			(symbol "C_10n_0402_1_1"
				(pin passive line
					(at 0 0 0)
					(length 2.032)
					(name "~"
						(effects
							(font
								(size 1.27 1.27)
							)
						)
					)
					(number "1"
						(effects
							(font
								(size 1.27 1.27)
							)
						)
					)
				)
				(pin passive line
					(at 5.08 0 180)
					(length 2.032)
					(name "~"
						(effects
							(font
								(size 1.27 1.27)
							)
						)
					)
					(number "2"
						(effects
							(font
								(size 1.27 1.27)
							)
						)
					)
				)
			)
		)
	(symbol "antmicroCapacitors0402:C_10u_0402"
			(pin_numbers
				(hide yes)
			)
			(pin_names
				(hide yes)
			)
			(exclude_from_sim no)
			(in_bom yes)
			(on_board yes)
			(property "Reference" "C"
				(at 20.32 -5.08 0)
				(effects
					(font
						(size 1.27 1.27)
						(thickness 0.15)
					)
					(justify left bottom)
				)
			)
			(property "Value" "C_10u_0402"
				(at 20.32 -10.16 0)
				(effects
					(font
						(size 1.27 1.27)
						(thickness 0.15)
					)
					(justify left bottom)
					(hide yes)
				)
			)
			(property "Footprint" "antmicro-footprints:C_0402_1005Metric"
				(at 20.32 -12.7 0)
				(effects
					(font
						(size 1.27 1.27)
						(thickness 0.15)
					)
					(justify left bottom)
					(hide yes)
				)
			)
			(property "Datasheet" "https://www.yageo.com/en/Chart/Download/pdf/CC0402MRX5R5BB106"
				(at 20.32 -15.24 0)
				(effects
					(font
						(size 1.27 1.27)
						(thickness 0.15)
					)
					(justify left bottom)
					(hide yes)
				)
			)
			(property "Description" "SMD Multilayer Ceramic Capacitor, 10 µF, 6.3 V, 0402 [1005 Metric], ± 20%, X5R, CC Series"
				(at 20.32 -33.02 0)
				(effects
					(font
						(size 1.27 1.27)
					)
					(justify left bottom)
					(hide yes)
				)
			)
			(property "MPN" "CC0402MRX5R5BB106"
				(at 20.32 -17.78 0)
				(effects
					(font
						(size 1.27 1.27)
						(thickness 0.15)
					)
					(justify left bottom)
					(hide yes)
				)
			)
			(property "Manufacturer" "YAGEO"
				(at 20.32 -20.32 0)
				(effects
					(font
						(size 1.27 1.27)
						(thickness 0.15)
					)
					(justify left bottom)
					(hide yes)
				)
			)
			(property "License" "Apache-2.0"
				(at 20.32 -22.86 0)
				(effects
					(font
						(size 1.27 1.27)
						(thickness 0.15)
					)
					(justify left bottom)
					(hide yes)
				)
			)
			(property "Author" "Antmicro"
				(at 20.32 -25.4 0)
				(effects
					(font
						(size 1.27 1.27)
						(thickness 0.15)
					)
					(justify left bottom)
					(hide yes)
				)
			)
			(property "Val" "10u"
				(at 20.32 -7.62 0)
				(effects
					(font
						(size 1.27 1.27)
						(thickness 0.15)
					)
					(justify left bottom)
				)
			)
			(property "Voltage" ""
				(at 20.32 -27.94 0)
				(effects
					(font
						(size 1.27 1.27)
					)
					(justify left bottom)
					(hide yes)
				)
			)
			(property "Dielectric" ""
				(at 20.32 -30.48 0)
				(effects
					(font
						(size 1.27 1.27)
					)
					(justify left bottom)
					(hide yes)
				)
			)
			(property "ki_keywords" "0402, SMT, CAPACITOR, PASSIVE, MLCC, CERAMIC"
				(at 0 0 0)
				(effects
					(font
						(size 1.27 1.27)
					)
					(hide yes)
				)
			)
			(symbol "C_10u_0402_0_1"
				(polyline
					(pts
						(xy 2.032 -1.524) (xy 2.032 1.524)
					)
					(stroke
						(width 0.3048)
						(type default)
					)
					(fill
						(type none)
					)
				)
				(polyline
					(pts
						(xy 3.048 -1.524) (xy 3.048 1.524)
					)
					(stroke
						(width 0.3302)
						(type default)
					)
					(fill
						(type none)
					)
				)
			)
			(symbol "C_10u_0402_1_1"
				(pin passive line
					(at 0 0 0)
					(length 2.032)
					(name "~"
						(effects
							(font
								(size 1.27 1.27)
							)
						)
					)
					(number "1"
						(effects
							(font
								(size 1.27 1.27)
							)
						)
					)
				)
				(pin passive line
					(at 5.08 0 180)
					(length 2.032)
					(name "~"
						(effects
							(font
								(size 1.27 1.27)
							)
						)
					)
					(number "2"
						(effects
							(font
								(size 1.27 1.27)
							)
						)
					)
				)
			)
		)
	(symbol "antmicroCapacitors0402:C_120p_100V_0402"
			(pin_numbers
				(hide yes)
			)
			(pin_names
				(hide yes)
			)
			(exclude_from_sim no)
			(in_bom yes)
			(on_board yes)
			(property "Reference" "C"
				(at 20.32 -5.08 0)
				(effects
					(font
						(size 1.27 1.27)
						(thickness 0.15)
					)
					(justify left bottom)
				)
			)
			(property "Value" "C_120p_100V_0402"
				(at 20.32 -10.16 0)
				(effects
					(font
						(size 1.27 1.27)
						(thickness 0.15)
					)
					(justify left bottom)
					(hide yes)
				)
			)
			(property "Footprint" "antmicro-footprints:C_0402_1005Metric"
				(at 20.32 -12.7 0)
				(effects
					(font
						(size 1.27 1.27)
						(thickness 0.15)
					)
					(justify left bottom)
					(hide yes)
				)
			)
			(property "Datasheet" "https://www.kemet.com/en/us/capacitors/product/C0402C121J5GACTU.html"
				(at 20.32 -15.24 0)
				(effects
					(font
						(size 1.27 1.27)
						(thickness 0.15)
					)
					(justify left bottom)
					(hide yes)
				)
			)
			(property "Description" "120 pF ±2% 100V Ceramic Capacitor C0G, NP0 0402 (1005 Metric)"
				(at 20.32 -33.02 0)
				(effects
					(font
						(size 1.27 1.27)
					)
					(justify left bottom)
					(hide yes)
				)
			)
			(property "MPN" "C0402C121J5GACTU"
				(at 20.32 -17.78 0)
				(effects
					(font
						(size 1.27 1.27)
						(thickness 0.15)
					)
					(justify left bottom)
					(hide yes)
				)
			)
			(property "Manufacturer" "KEMET"
				(at 20.32 -20.32 0)
				(effects
					(font
						(size 1.27 1.27)
						(thickness 0.15)
					)
					(justify left bottom)
					(hide yes)
				)
			)
			(property "License" "Apache-2.0"
				(at 20.32 -22.86 0)
				(effects
					(font
						(size 1.27 1.27)
						(thickness 0.15)
					)
					(justify left bottom)
					(hide yes)
				)
			)
			(property "Author" "Antmicro"
				(at 20.32 -25.4 0)
				(effects
					(font
						(size 1.27 1.27)
						(thickness 0.15)
					)
					(justify left bottom)
					(hide yes)
				)
			)
			(property "Val" "120p"
				(at 20.32 -7.62 0)
				(effects
					(font
						(size 1.27 1.27)
						(thickness 0.15)
					)
					(justify left bottom)
				)
			)
			(property "Voltage" "100V"
				(at 20.32 -27.94 0)
				(effects
					(font
						(size 1.27 1.27)
					)
					(justify left bottom)
					(hide yes)
				)
			)
			(property "Dielectric" "C0G"
				(at 20.32 -30.48 0)
				(effects
					(font
						(size 1.27 1.27)
					)
					(justify left bottom)
					(hide yes)
				)
			)
			(property "ki_keywords" "0402, SMT, CAPACITOR, PASSIVE, CERAMIC, MLCC"
				(at 0 0 0)
				(effects
					(font
						(size 1.27 1.27)
					)
					(hide yes)
				)
			)
			(symbol "C_120p_100V_0402_0_1"
				(polyline
					(pts
						(xy 2.032 -1.524) (xy 2.032 1.524)
					)
					(stroke
						(width 0.3048)
						(type default)
					)
					(fill
						(type none)
					)
				)
				(polyline
					(pts
						(xy 3.048 -1.524) (xy 3.048 1.524)
					)
					(stroke
						(width 0.3302)
						(type default)
					)
					(fill
						(type none)
					)
				)
			)
			(symbol "C_120p_100V_0402_1_1"
				(pin passive line
					(at 0 0 0)
					(length 2.032)
					(name "~"
						(effects
							(font
								(size 1.27 1.27)
							)
						)
					)
					(number "1"
						(effects
							(font
								(size 1.27 1.27)
							)
						)
					)
				)
				(pin passive line
					(at 5.08 0 180)
					(length 2.032)
					(name "~"
						(effects
							(font
								(size 1.27 1.27)
							)
						)
					)
					(number "2"
						(effects
							(font
								(size 1.27 1.27)
							)
						)
					)
				)
			)
		)
	(symbol "antmicroCapacitors0402:C_18p_0402"
			(pin_numbers
				(hide yes)
			)
			(pin_names
				(hide yes)
			)
			(exclude_from_sim no)
			(in_bom yes)
			(on_board yes)
			(property "Reference" "C"
				(at 20.32 -5.08 0)
				(effects
					(font
						(size 1.27 1.27)
						(thickness 0.15)
					)
					(justify left bottom)
				)
			)
			(property "Value" "C_18p_0402"
				(at 20.32 -10.16 0)
				(effects
					(font
						(size 1.27 1.27)
						(thickness 0.15)
					)
					(justify left bottom)
					(hide yes)
				)
			)
			(property "Footprint" "antmicro-footprints:C_0402_1005Metric"
				(at 20.32 -12.7 0)
				(effects
					(font
						(size 1.27 1.27)
						(thickness 0.15)
					)
					(justify left bottom)
					(hide yes)
				)
			)
			(property "Datasheet" "https://product.samsungsem.com/mlcc/CL05C180JB51PN.do"
				(at 20.32 -15.24 0)
				(effects
					(font
						(size 1.27 1.27)
						(thickness 0.15)
					)
					(justify left bottom)
					(hide yes)
				)
			)
			(property "Description" "SMD Multilayer Ceramic Capacitor, 18 pF, 50 V, 0402 [1005 Metric], ± 5%, C0G / NP0, MC"
				(at 20.32 -33.02 0)
				(effects
					(font
						(size 1.27 1.27)
					)
					(justify left bottom)
					(hide yes)
				)
			)
			(property "MPN" "CL05C180JB51PNC"
				(at 20.32 -17.78 0)
				(effects
					(font
						(size 1.27 1.27)
						(thickness 0.15)
					)
					(justify left bottom)
					(hide yes)
				)
			)
			(property "Manufacturer" "Samsung Electro-Mechanics"
				(at 20.32 -20.32 0)
				(effects
					(font
						(size 1.27 1.27)
						(thickness 0.15)
					)
					(justify left bottom)
					(hide yes)
				)
			)
			(property "License" "Apache-2.0"
				(at 20.32 -22.86 0)
				(effects
					(font
						(size 1.27 1.27)
						(thickness 0.15)
					)
					(justify left bottom)
					(hide yes)
				)
			)
			(property "Author" "Antmicro"
				(at 20.32 -25.4 0)
				(effects
					(font
						(size 1.27 1.27)
						(thickness 0.15)
					)
					(justify left bottom)
					(hide yes)
				)
			)
			(property "Val" "18p"
				(at 20.32 -7.62 0)
				(effects
					(font
						(size 1.27 1.27)
						(thickness 0.15)
					)
					(justify left bottom)
				)
			)
			(property "Voltage" ""
				(at 20.32 -27.94 0)
				(effects
					(font
						(size 1.27 1.27)
					)
					(justify left bottom)
					(hide yes)
				)
			)
			(property "Dielectric" ""
				(at 20.32 -30.48 0)
				(effects
					(font
						(size 1.27 1.27)
					)
					(justify left bottom)
					(hide yes)
				)
			)
			(property "ki_keywords" "0402, SMT, CAPACITOR, PASSIVE"
				(at 0 0 0)
				(effects
					(font
						(size 1.27 1.27)
					)
					(hide yes)
				)
			)
			(symbol "C_18p_0402_0_1"
				(polyline
					(pts
						(xy 2.032 -1.524) (xy 2.032 1.524)
					)
					(stroke
						(width 0.3048)
						(type default)
					)
					(fill
						(type none)
					)
				)
				(polyline
					(pts
						(xy 3.048 -1.524) (xy 3.048 1.524)
					)
					(stroke
						(width 0.3302)
						(type default)
					)
					(fill
						(type none)
					)
				)
			)
			(symbol "C_18p_0402_1_1"
				(pin passive line
					(at 0 0 0)
					(length 2.032)
					(name "~"
						(effects
							(font
								(size 1.27 1.27)
							)
						)
					)
					(number "1"
						(effects
							(font
								(size 1.27 1.27)
							)
						)
					)
				)
				(pin passive line
					(at 5.08 0 180)
					(length 2.032)
					(name "~"
						(effects
							(font
								(size 1.27 1.27)
							)
						)
					)
					(number "2"
						(effects
							(font
								(size 1.27 1.27)
							)
						)
					)
				)
			)
		)
	(symbol "antmicroCapacitors0402:C_1n_0402"
			(pin_numbers
				(hide yes)
			)
			(pin_names
				(hide yes)
			)
			(exclude_from_sim no)
			(in_bom yes)
			(on_board yes)
			(property "Reference" "C"
				(at 20.32 -5.08 0)
				(effects
					(font
						(size 1.27 1.27)
						(thickness 0.15)
					)
					(justify left bottom)
				)
			)
			(property "Value" "C_1n_0402"
				(at 20.32 -10.16 0)
				(effects
					(font
						(size 1.27 1.27)
						(thickness 0.15)
					)
					(justify left bottom)
					(hide yes)
				)
			)
			(property "Footprint" "antmicro-footprints:C_0402_1005Metric"
				(at 20.32 -12.7 0)
				(effects
					(font
						(size 1.27 1.27)
						(thickness 0.15)
					)
					(justify left bottom)
					(hide yes)
				)
			)
			(property "Datasheet" "https://www.murata.com/products/productdetail?partno=GRM1555C1H102JA01%23"
				(at 20.32 -15.24 0)
				(effects
					(font
						(size 1.27 1.27)
						(thickness 0.15)
					)
					(justify left bottom)
					(hide yes)
				)
			)
			(property "Description" "SMD Multilayer Ceramic Capacitor, 1000 pF, 50 V, 0402 [1005 Metric], ± 5%, C0G / NP0, GRM Series"
				(at 20.32 -33.02 0)
				(effects
					(font
						(size 1.27 1.27)
					)
					(justify left bottom)
					(hide yes)
				)
			)
			(property "MPN" "GRM1555C1H102JA01D"
				(at 20.32 -17.78 0)
				(effects
					(font
						(size 1.27 1.27)
						(thickness 0.15)
					)
					(justify left bottom)
					(hide yes)
				)
			)
			(property "Manufacturer" "Murata"
				(at 20.32 -20.32 0)
				(effects
					(font
						(size 1.27 1.27)
						(thickness 0.15)
					)
					(justify left bottom)
					(hide yes)
				)
			)
			(property "License" "Apache-2.0"
				(at 20.32 -22.86 0)
				(effects
					(font
						(size 1.27 1.27)
						(thickness 0.15)
					)
					(justify left bottom)
					(hide yes)
				)
			)
			(property "Author" "Antmicro"
				(at 20.32 -25.4 0)
				(effects
					(font
						(size 1.27 1.27)
						(thickness 0.15)
					)
					(justify left bottom)
					(hide yes)
				)
			)
			(property "Val" "1n"
				(at 20.32 -7.62 0)
				(effects
					(font
						(size 1.27 1.27)
						(thickness 0.15)
					)
					(justify left bottom)
				)
			)
			(property "Voltage" "50V"
				(at 20.32 -27.94 0)
				(effects
					(font
						(size 1.27 1.27)
					)
					(justify left bottom)
					(hide yes)
				)
			)
			(property "Dielectric" "C0G"
				(at 20.32 -30.48 0)
				(effects
					(font
						(size 1.27 1.27)
					)
					(justify left bottom)
					(hide yes)
				)
			)
			(property "ki_keywords" "0402, SMT, CAPACITOR, PASSIVE, CERAMIC, MLCC"
				(at 0 0 0)
				(effects
					(font
						(size 1.27 1.27)
					)
					(hide yes)
				)
			)
			(symbol "C_1n_0402_0_1"
				(polyline
					(pts
						(xy 2.032 -1.524) (xy 2.032 1.524)
					)
					(stroke
						(width 0.3048)
						(type default)
					)
					(fill
						(type none)
					)
				)
				(polyline
					(pts
						(xy 3.048 -1.524) (xy 3.048 1.524)
					)
					(stroke
						(width 0.3302)
						(type default)
					)
					(fill
						(type none)
					)
				)
			)
			(symbol "C_1n_0402_1_1"
				(pin passive line
					(at 0 0 0)
					(length 2.032)
					(name "~"
						(effects
							(font
								(size 1.27 1.27)
							)
						)
					)
					(number "1"
						(effects
							(font
								(size 1.27 1.27)
							)
						)
					)
				)
				(pin passive line
					(at 5.08 0 180)
					(length 2.032)
					(name "~"
						(effects
							(font
								(size 1.27 1.27)
							)
						)
					)
					(number "2"
						(effects
							(font
								(size 1.27 1.27)
							)
						)
					)
				)
			)
		)
	(symbol "antmicroCapacitors0402:C_22p_0402"
			(pin_numbers
				(hide yes)
			)
			(pin_names
				(hide yes)
			)
			(exclude_from_sim no)
			(in_bom yes)
			(on_board yes)
			(property "Reference" "C"
				(at 20.32 -5.08 0)
				(effects
					(font
						(size 1.27 1.27)
						(thickness 0.15)
					)
					(justify left bottom)
				)
			)
			(property "Value" "C_22p_0402"
				(at 20.32 -10.16 0)
				(effects
					(font
						(size 1.27 1.27)
						(thickness 0.15)
					)
					(justify left bottom)
					(hide yes)
				)
			)
			(property "Footprint" "antmicro-footprints:C_0402_1005Metric"
				(at 20.32 -12.7 0)
				(effects
					(font
						(size 1.27 1.27)
						(thickness 0.15)
					)
					(justify left bottom)
					(hide yes)
				)
			)
			(property "Datasheet" "https://www.yageo.com/en/Chart/Download/pdf/CC0402JRNPO9BN220"
				(at 20.32 -15.24 0)
				(effects
					(font
						(size 1.27 1.27)
						(thickness 0.15)
					)
					(justify left bottom)
					(hide yes)
				)
			)
			(property "Description" "SMD Multilayer Ceramic Capacitor, 22 pF, 50 V, 0402 [1005 Metric], ± 5%, C0G / NP0, CC Series"
				(at 20.32 -33.02 0)
				(effects
					(font
						(size 1.27 1.27)
					)
					(justify left bottom)
					(hide yes)
				)
			)
			(property "MPN" "CC0402JRNPO9BN220"
				(at 20.32 -17.78 0)
				(effects
					(font
						(size 1.27 1.27)
						(thickness 0.15)
					)
					(justify left bottom)
					(hide yes)
				)
			)
			(property "Manufacturer" "YAGEO"
				(at 20.32 -20.32 0)
				(effects
					(font
						(size 1.27 1.27)
						(thickness 0.15)
					)
					(justify left bottom)
					(hide yes)
				)
			)
			(property "License" "Apache-2.0"
				(at 20.32 -22.86 0)
				(effects
					(font
						(size 1.27 1.27)
						(thickness 0.15)
					)
					(justify left bottom)
					(hide yes)
				)
			)
			(property "Author" "Antmicro"
				(at 20.32 -25.4 0)
				(effects
					(font
						(size 1.27 1.27)
						(thickness 0.15)
					)
					(justify left bottom)
					(hide yes)
				)
			)
			(property "Val" "22p"
				(at 20.32 -7.62 0)
				(effects
					(font
						(size 1.27 1.27)
						(thickness 0.15)
					)
					(justify left bottom)
				)
			)
			(property "Voltage" ""
				(at 20.32 -27.94 0)
				(effects
					(font
						(size 1.27 1.27)
					)
					(justify left bottom)
					(hide yes)
				)
			)
			(property "Dielectric" ""
				(at 20.32 -30.48 0)
				(effects
					(font
						(size 1.27 1.27)
					)
					(justify left bottom)
					(hide yes)
				)
			)
			(property "ki_keywords" "0402, SMT, CAPACITOR, PASSIVE, MLCC, CERAMIC"
				(at 0 0 0)
				(effects
					(font
						(size 1.27 1.27)
					)
					(hide yes)
				)
			)
			(symbol "C_22p_0402_0_1"
				(polyline
					(pts
						(xy 2.032 -1.524) (xy 2.032 1.524)
					)
					(stroke
						(width 0.3048)
						(type default)
					)
					(fill
						(type none)
					)
				)
				(polyline
					(pts
						(xy 3.048 -1.524) (xy 3.048 1.524)
					)
					(stroke
						(width 0.3302)
						(type default)
					)
					(fill
						(type none)
					)
				)
			)
			(symbol "C_22p_0402_1_1"
				(pin passive line
					(at 0 0 0)
					(length 2.032)
					(name "~"
						(effects
							(font
								(size 1.27 1.27)
							)
						)
					)
					(number "1"
						(effects
							(font
								(size 1.27 1.27)
							)
						)
					)
				)
				(pin passive line
					(at 5.08 0 180)
					(length 2.032)
					(name "~"
						(effects
							(font
								(size 1.27 1.27)
							)
						)
					)
					(number "2"
						(effects
							(font
								(size 1.27 1.27)
							)
						)
					)
				)
			)
		)
	(symbol "antmicroCapacitors0402:C_2u2_0402"
			(pin_numbers
				(hide yes)
			)
			(pin_names
				(hide yes)
			)
			(exclude_from_sim no)
			(in_bom yes)
			(on_board yes)
			(property "Reference" "C"
				(at 20.32 -5.08 0)
				(effects
					(font
						(size 1.27 1.27)
						(thickness 0.15)
					)
					(justify left bottom)
				)
			)
			(property "Value" "C_2u2_0402"
				(at 20.32 -10.16 0)
				(effects
					(font
						(size 1.27 1.27)
						(thickness 0.15)
					)
					(justify left bottom)
					(hide yes)
				)
			)
			(property "Footprint" "antmicro-footprints:C_0402_1005Metric"
				(at 20.32 -12.7 0)
				(effects
					(font
						(size 1.27 1.27)
						(thickness 0.15)
					)
					(justify left bottom)
					(hide yes)
				)
			)
			(property "Datasheet" "https://product.tdk.com/en/search/capacitor/ceramic/mlcc/info?part_no=C1005X5R1A225K050BC"
				(at 20.32 -15.24 0)
				(effects
					(font
						(size 1.27 1.27)
						(thickness 0.15)
					)
					(justify left bottom)
					(hide yes)
				)
			)
			(property "Description" "SMD Multilayer Ceramic Capacitor, 2.2 µF, 10 V, 0402 [1005 Metric], ± 10%, X5R, C"
				(at 20.32 -33.02 0)
				(effects
					(font
						(size 1.27 1.27)
					)
					(justify left bottom)
					(hide yes)
				)
			)
			(property "MPN" "C1005X5R1A225K050BC"
				(at 20.32 -17.78 0)
				(effects
					(font
						(size 1.27 1.27)
						(thickness 0.15)
					)
					(justify left bottom)
					(hide yes)
				)
			)
			(property "Manufacturer" "TDK"
				(at 20.32 -20.32 0)
				(effects
					(font
						(size 1.27 1.27)
						(thickness 0.15)
					)
					(justify left bottom)
					(hide yes)
				)
			)
			(property "License" "Apache-2.0"
				(at 20.32 -22.86 0)
				(effects
					(font
						(size 1.27 1.27)
						(thickness 0.15)
					)
					(justify left bottom)
					(hide yes)
				)
			)
			(property "Author" "Antmicro"
				(at 20.32 -25.4 0)
				(effects
					(font
						(size 1.27 1.27)
						(thickness 0.15)
					)
					(justify left bottom)
					(hide yes)
				)
			)
			(property "Val" "2u2"
				(at 20.32 -7.62 0)
				(effects
					(font
						(size 1.27 1.27)
						(thickness 0.15)
					)
					(justify left bottom)
				)
			)
			(property "Voltage" ""
				(at 20.32 -27.94 0)
				(effects
					(font
						(size 1.27 1.27)
					)
					(justify left bottom)
					(hide yes)
				)
			)
			(property "Dielectric" ""
				(at 20.32 -30.48 0)
				(effects
					(font
						(size 1.27 1.27)
					)
					(justify left bottom)
					(hide yes)
				)
			)
			(property "ki_keywords" "0402, SMT, CAPACITOR, PASSIVE, CERAMIC, MLCC"
				(at 0 0 0)
				(effects
					(font
						(size 1.27 1.27)
					)
					(hide yes)
				)
			)
			(symbol "C_2u2_0402_0_1"
				(polyline
					(pts
						(xy 2.032 -1.524) (xy 2.032 1.524)
					)
					(stroke
						(width 0.3048)
						(type default)
					)
					(fill
						(type none)
					)
				)
				(polyline
					(pts
						(xy 3.048 -1.524) (xy 3.048 1.524)
					)
					(stroke
						(width 0.3302)
						(type default)
					)
					(fill
						(type none)
					)
				)
			)
			(symbol "C_2u2_0402_1_1"
				(pin passive line
					(at 0 0 0)
					(length 2.032)
					(name "~"
						(effects
							(font
								(size 1.27 1.27)
							)
						)
					)
					(number "1"
						(effects
							(font
								(size 1.27 1.27)
							)
						)
					)
				)
				(pin passive line
					(at 5.08 0 180)
					(length 2.032)
					(name "~"
						(effects
							(font
								(size 1.27 1.27)
							)
						)
					)
					(number "2"
						(effects
							(font
								(size 1.27 1.27)
							)
						)
					)
				)
			)
		)
	(symbol "antmicroCapacitors0402:C_470n_0402"
			(pin_numbers
				(hide yes)
			)
			(pin_names
				(hide yes)
			)
			(exclude_from_sim no)
			(in_bom yes)
			(on_board yes)
			(property "Reference" "C"
				(at 20.32 -5.08 0)
				(effects
					(font
						(size 1.27 1.27)
						(thickness 0.15)
					)
					(justify left bottom)
				)
			)
			(property "Value" "C_470n_0402"
				(at 20.32 -10.16 0)
				(effects
					(font
						(size 1.27 1.27)
						(thickness 0.15)
					)
					(justify left bottom)
					(hide yes)
				)
			)
			(property "Footprint" "antmicro-footprints:C_0402_1005Metric"
				(at 20.32 -12.7 0)
				(effects
					(font
						(size 1.27 1.27)
						(thickness 0.15)
					)
					(justify left bottom)
					(hide yes)
				)
			)
			(property "Datasheet" "https://product.tdk.com/en/search/capacitor/ceramic/mlcc/info?part_no=C1005X5R1E474M050BB"
				(at 20.32 -15.24 0)
				(effects
					(font
						(size 1.27 1.27)
						(thickness 0.15)
					)
					(justify left bottom)
					(hide yes)
				)
			)
			(property "Description" "SMD Multilayer Ceramic Capacitor, 0.47 µF, 25 V, 0402 [1005 Metric], ± 20%, X5R, C"
				(at 20.32 -33.02 0)
				(effects
					(font
						(size 1.27 1.27)
					)
					(justify left bottom)
					(hide yes)
				)
			)
			(property "MPN" "C1005X5R1E474M050BB"
				(at 20.32 -17.78 0)
				(effects
					(font
						(size 1.27 1.27)
						(thickness 0.15)
					)
					(justify left bottom)
					(hide yes)
				)
			)
			(property "Manufacturer" "TDK"
				(at 20.32 -20.32 0)
				(effects
					(font
						(size 1.27 1.27)
						(thickness 0.15)
					)
					(justify left bottom)
					(hide yes)
				)
			)
			(property "License" "Apache-2.0"
				(at 20.32 -22.86 0)
				(effects
					(font
						(size 1.27 1.27)
						(thickness 0.15)
					)
					(justify left bottom)
					(hide yes)
				)
			)
			(property "Author" "Antmicro"
				(at 20.32 -25.4 0)
				(effects
					(font
						(size 1.27 1.27)
						(thickness 0.15)
					)
					(justify left bottom)
					(hide yes)
				)
			)
			(property "Val" "470n"
				(at 20.32 -7.62 0)
				(effects
					(font
						(size 1.27 1.27)
						(thickness 0.15)
					)
					(justify left bottom)
				)
			)
			(property "Voltage" ""
				(at 20.32 -27.94 0)
				(effects
					(font
						(size 1.27 1.27)
					)
					(justify left bottom)
					(hide yes)
				)
			)
			(property "Dielectric" ""
				(at 20.32 -30.48 0)
				(effects
					(font
						(size 1.27 1.27)
					)
					(justify left bottom)
					(hide yes)
				)
			)
			(property "ki_keywords" "0402, SMT, CAPACITOR, PASSIVE, CERAMIC, MLCC"
				(at 0 0 0)
				(effects
					(font
						(size 1.27 1.27)
					)
					(hide yes)
				)
			)
			(symbol "C_470n_0402_0_1"
				(polyline
					(pts
						(xy 2.032 -1.524) (xy 2.032 1.524)
					)
					(stroke
						(width 0.3048)
						(type default)
					)
					(fill
						(type none)
					)
				)
				(polyline
					(pts
						(xy 3.048 -1.524) (xy 3.048 1.524)
					)
					(stroke
						(width 0.3302)
						(type default)
					)
					(fill
						(type none)
					)
				)
			)
			(symbol "C_470n_0402_1_1"
				(pin passive line
					(at 0 0 0)
					(length 2.032)
					(name "~"
						(effects
							(font
								(size 1.27 1.27)
							)
						)
					)
					(number "1"
						(effects
							(font
								(size 1.27 1.27)
							)
						)
					)
				)
				(pin passive line
					(at 5.08 0 180)
					(length 2.032)
					(name "~"
						(effects
							(font
								(size 1.27 1.27)
							)
						)
					)
					(number "2"
						(effects
							(font
								(size 1.27 1.27)
							)
						)
					)
				)
			)
		)
	(symbol "antmicroCapacitors0402:C_47p_0402"
			(pin_numbers
				(hide yes)
			)
			(pin_names
				(hide yes)
			)
			(exclude_from_sim no)
			(in_bom yes)
			(on_board yes)
			(property "Reference" "C"
				(at 20.32 -5.08 0)
				(effects
					(font
						(size 1.27 1.27)
						(thickness 0.15)
					)
					(justify left bottom)
				)
			)
			(property "Value" "C_47p_0402"
				(at 20.32 -10.16 0)
				(effects
					(font
						(size 1.27 1.27)
						(thickness 0.15)
					)
					(justify left bottom)
					(hide yes)
				)
			)
			(property "Footprint" "antmicro-footprints:C_0402_1005Metric"
				(at 20.32 -12.7 0)
				(effects
					(font
						(size 1.27 1.27)
						(thickness 0.15)
					)
					(justify left bottom)
					(hide yes)
				)
			)
			(property "Datasheet" "https://www.kemet.com/en/us/capacitors/product/C0402C470J5GACTU.html"
				(at 20.32 -15.24 0)
				(effects
					(font
						(size 1.27 1.27)
						(thickness 0.15)
					)
					(justify left bottom)
					(hide yes)
				)
			)
			(property "Description" "SMD Multilayer Ceramic Capacitor, 47 pF, 50 V, 0402 [1005 Metric], ± 5%, C0G / NP0, C Series KEMET"
				(at 20.32 -33.02 0)
				(effects
					(font
						(size 1.27 1.27)
					)
					(justify left bottom)
					(hide yes)
				)
			)
			(property "MPN" "C0402C470J5GACTU"
				(at 20.32 -17.78 0)
				(effects
					(font
						(size 1.27 1.27)
						(thickness 0.15)
					)
					(justify left bottom)
					(hide yes)
				)
			)
			(property "Manufacturer" "KEMET"
				(at 20.32 -20.32 0)
				(effects
					(font
						(size 1.27 1.27)
						(thickness 0.15)
					)
					(justify left bottom)
					(hide yes)
				)
			)
			(property "License" "Apache-2.0"
				(at 20.32 -22.86 0)
				(effects
					(font
						(size 1.27 1.27)
						(thickness 0.15)
					)
					(justify left bottom)
					(hide yes)
				)
			)
			(property "Author" "Antmicro"
				(at 20.32 -25.4 0)
				(effects
					(font
						(size 1.27 1.27)
						(thickness 0.15)
					)
					(justify left bottom)
					(hide yes)
				)
			)
			(property "Val" "47p"
				(at 20.32 -7.62 0)
				(effects
					(font
						(size 1.27 1.27)
						(thickness 0.15)
					)
					(justify left bottom)
				)
			)
			(property "Voltage" ""
				(at 20.32 -27.94 0)
				(effects
					(font
						(size 1.27 1.27)
					)
					(justify left bottom)
					(hide yes)
				)
			)
			(property "Dielectric" "C0G"
				(at 20.32 -30.48 0)
				(effects
					(font
						(size 1.27 1.27)
					)
					(justify left bottom)
					(hide yes)
				)
			)
			(property "ki_keywords" "0402, SMT, CAPACITOR, PASSIVE, CERAMIC, MLCC"
				(at 0 0 0)
				(effects
					(font
						(size 1.27 1.27)
					)
					(hide yes)
				)
			)
			(symbol "C_47p_0402_0_1"
				(polyline
					(pts
						(xy 2.032 -1.524) (xy 2.032 1.524)
					)
					(stroke
						(width 0.3048)
						(type default)
					)
					(fill
						(type none)
					)
				)
				(polyline
					(pts
						(xy 3.048 -1.524) (xy 3.048 1.524)
					)
					(stroke
						(width 0.3302)
						(type default)
					)
					(fill
						(type none)
					)
				)
			)
			(symbol "C_47p_0402_1_1"
				(pin passive line
					(at 0 0 0)
					(length 2.032)
					(name "~"
						(effects
							(font
								(size 1.27 1.27)
							)
						)
					)
					(number "1"
						(effects
							(font
								(size 1.27 1.27)
							)
						)
					)
				)
				(pin passive line
					(at 5.08 0 180)
					(length 2.032)
					(name "~"
						(effects
							(font
								(size 1.27 1.27)
							)
						)
					)
					(number "2"
						(effects
							(font
								(size 1.27 1.27)
							)
						)
					)
				)
			)
		)
	(symbol "antmicroCapacitors0402:C_4n7_0402"
			(pin_numbers
				(hide yes)
			)
			(pin_names
				(hide yes)
			)
			(exclude_from_sim no)
			(in_bom yes)
			(on_board yes)
			(property "Reference" "C"
				(at 20.32 -5.08 0)
				(effects
					(font
						(size 1.27 1.27)
						(thickness 0.15)
					)
					(justify left bottom)
				)
			)
			(property "Value" "C_4n7_0402"
				(at 20.32 -10.16 0)
				(effects
					(font
						(size 1.27 1.27)
						(thickness 0.15)
					)
					(justify left bottom)
					(hide yes)
				)
			)
			(property "Footprint" "antmicro-footprints:C_0402_1005Metric"
				(at 20.32 -12.7 0)
				(effects
					(font
						(size 1.27 1.27)
						(thickness 0.15)
					)
					(justify left bottom)
					(hide yes)
				)
			)
			(property "Datasheet" "https://product.tdk.com/en/search/capacitor/ceramic/mlcc/info?part_no=CGA2B3X7S2A472K050BB"
				(at 20.32 -15.24 0)
				(effects
					(font
						(size 1.27 1.27)
						(thickness 0.15)
					)
					(justify left bottom)
					(hide yes)
				)
			)
			(property "Description" "SMD Multilayer Ceramic Capacitor, 4700 pF, 100 V, 0402 [1005 Metric], ± 10%, X7S, CGA"
				(at 20.32 -33.02 0)
				(effects
					(font
						(size 1.27 1.27)
					)
					(justify left bottom)
					(hide yes)
				)
			)
			(property "MPN" "CGA2B3X7S2A472K050BB"
				(at 20.32 -17.78 0)
				(effects
					(font
						(size 1.27 1.27)
						(thickness 0.15)
					)
					(justify left bottom)
					(hide yes)
				)
			)
			(property "Manufacturer" "TDK"
				(at 20.32 -20.32 0)
				(effects
					(font
						(size 1.27 1.27)
						(thickness 0.15)
					)
					(justify left bottom)
					(hide yes)
				)
			)
			(property "License" "Apache-2.0"
				(at 20.32 -22.86 0)
				(effects
					(font
						(size 1.27 1.27)
						(thickness 0.15)
					)
					(justify left bottom)
					(hide yes)
				)
			)
			(property "Author" "Antmicro"
				(at 20.32 -25.4 0)
				(effects
					(font
						(size 1.27 1.27)
						(thickness 0.15)
					)
					(justify left bottom)
					(hide yes)
				)
			)
			(property "Val" "4n7"
				(at 20.32 -7.62 0)
				(effects
					(font
						(size 1.27 1.27)
						(thickness 0.15)
					)
					(justify left bottom)
				)
			)
			(property "Voltage" ""
				(at 20.32 -27.94 0)
				(effects
					(font
						(size 1.27 1.27)
					)
					(justify left bottom)
					(hide yes)
				)
			)
			(property "Dielectric" ""
				(at 20.32 -30.48 0)
				(effects
					(font
						(size 1.27 1.27)
					)
					(justify left bottom)
					(hide yes)
				)
			)
			(property "ki_keywords" "0402, SMT, CAPACITOR, PASSIVE, CERAMIC, MLCC"
				(at 0 0 0)
				(effects
					(font
						(size 1.27 1.27)
					)
					(hide yes)
				)
			)
			(symbol "C_4n7_0402_0_1"
				(polyline
					(pts
						(xy 2.032 -1.524) (xy 2.032 1.524)
					)
					(stroke
						(width 0.3048)
						(type default)
					)
					(fill
						(type none)
					)
				)
				(polyline
					(pts
						(xy 3.048 -1.524) (xy 3.048 1.524)
					)
					(stroke
						(width 0.3302)
						(type default)
					)
					(fill
						(type none)
					)
				)
			)
			(symbol "C_4n7_0402_1_1"
				(pin passive line
					(at 0 0 0)
					(length 2.032)
					(name "~"
						(effects
							(font
								(size 1.27 1.27)
							)
						)
					)
					(number "1"
						(effects
							(font
								(size 1.27 1.27)
							)
						)
					)
				)
				(pin passive line
					(at 5.08 0 180)
					(length 2.032)
					(name "~"
						(effects
							(font
								(size 1.27 1.27)
							)
						)
					)
					(number "2"
						(effects
							(font
								(size 1.27 1.27)
							)
						)
					)
				)
			)
		)
	(symbol "antmicroCapacitors0402:C_4u7_0402"
			(pin_numbers
				(hide yes)
			)
			(pin_names
				(hide yes)
			)
			(exclude_from_sim no)
			(in_bom yes)
			(on_board yes)
			(property "Reference" "C"
				(at 20.32 -5.08 0)
				(effects
					(font
						(size 1.27 1.27)
						(thickness 0.15)
					)
					(justify left bottom)
				)
			)
			(property "Value" "C_4u7_0402"
				(at 20.32 -10.16 0)
				(effects
					(font
						(size 1.27 1.27)
						(thickness 0.15)
					)
					(justify left bottom)
					(hide yes)
				)
			)
			(property "Footprint" "antmicro-footprints:C_0402_1005Metric"
				(at 20.32 -12.7 0)
				(effects
					(font
						(size 1.27 1.27)
						(thickness 0.15)
					)
					(justify left bottom)
					(hide yes)
				)
			)
			(property "Datasheet" "https://www.murata.com/products/productdetail?partno=GRM155R61A475MEAA%23"
				(at 20.32 -15.24 0)
				(effects
					(font
						(size 1.27 1.27)
						(thickness 0.15)
					)
					(justify left bottom)
					(hide yes)
				)
			)
			(property "Description" "SMD Multilayer Ceramic Capacitor, 4.7 µF, 10 V, 0402 [1005 Metric], ± 20%, X5R, GRM Series"
				(at 20.32 -33.02 0)
				(effects
					(font
						(size 1.27 1.27)
					)
					(justify left bottom)
					(hide yes)
				)
			)
			(property "MPN" "GRM155R61A475MEAAD"
				(at 20.32 -17.78 0)
				(effects
					(font
						(size 1.27 1.27)
						(thickness 0.15)
					)
					(justify left bottom)
					(hide yes)
				)
			)
			(property "Manufacturer" "Murata"
				(at 20.32 -20.32 0)
				(effects
					(font
						(size 1.27 1.27)
						(thickness 0.15)
					)
					(justify left bottom)
					(hide yes)
				)
			)
			(property "License" "Apache-2.0"
				(at 20.32 -22.86 0)
				(effects
					(font
						(size 1.27 1.27)
						(thickness 0.15)
					)
					(justify left bottom)
					(hide yes)
				)
			)
			(property "Author" "Antmicro"
				(at 20.32 -25.4 0)
				(effects
					(font
						(size 1.27 1.27)
						(thickness 0.15)
					)
					(justify left bottom)
					(hide yes)
				)
			)
			(property "Val" "4u7"
				(at 20.32 -7.62 0)
				(effects
					(font
						(size 1.27 1.27)
						(thickness 0.15)
					)
					(justify left bottom)
				)
			)
			(property "Voltage" ""
				(at 20.32 -27.94 0)
				(effects
					(font
						(size 1.27 1.27)
					)
					(justify left bottom)
					(hide yes)
				)
			)
			(property "Dielectric" ""
				(at 20.32 -30.48 0)
				(effects
					(font
						(size 1.27 1.27)
					)
					(justify left bottom)
					(hide yes)
				)
			)
			(property "ki_keywords" "0402, SMT, CAPACITOR, PASSIVE"
				(at 0 0 0)
				(effects
					(font
						(size 1.27 1.27)
					)
					(hide yes)
				)
			)
			(symbol "C_4u7_0402_0_1"
				(polyline
					(pts
						(xy 2.032 -1.524) (xy 2.032 1.524)
					)
					(stroke
						(width 0.3048)
						(type default)
					)
					(fill
						(type none)
					)
				)
				(polyline
					(pts
						(xy 3.048 -1.524) (xy 3.048 1.524)
					)
					(stroke
						(width 0.3302)
						(type default)
					)
					(fill
						(type none)
					)
				)
			)
			(symbol "C_4u7_0402_1_1"
				(pin passive line
					(at 0 0 0)
					(length 2.032)
					(name "~"
						(effects
							(font
								(size 1.27 1.27)
							)
						)
					)
					(number "1"
						(effects
							(font
								(size 1.27 1.27)
							)
						)
					)
				)
				(pin passive line
					(at 5.08 0 180)
					(length 2.032)
					(name "~"
						(effects
							(font
								(size 1.27 1.27)
							)
						)
					)
					(number "2"
						(effects
							(font
								(size 1.27 1.27)
							)
						)
					)
				)
			)
		)
	(symbol "antmicroCapacitors0603:C_10u_0603"
			(pin_numbers
				(hide yes)
			)
			(pin_names
				(hide yes)
			)
			(exclude_from_sim no)
			(in_bom yes)
			(on_board yes)
			(property "Reference" "C"
				(at 20.32 -5.08 0)
				(effects
					(font
						(size 1.27 1.27)
						(thickness 0.15)
					)
					(justify left bottom)
				)
			)
			(property "Value" "C_10u_0603"
				(at 20.32 -10.16 0)
				(effects
					(font
						(size 1.27 1.27)
						(thickness 0.15)
					)
					(justify left bottom)
					(hide yes)
				)
			)
			(property "Footprint" "antmicro-footprints:C_0603_1608Metric"
				(at 20.32 -12.7 0)
				(effects
					(font
						(size 1.27 1.27)
						(thickness 0.15)
					)
					(justify left bottom)
					(hide yes)
				)
			)
			(property "Datasheet" "https://www.murata.com/products/productdetail?partno=GRM188R61A106KE69%23"
				(at 20.32 -15.24 0)
				(effects
					(font
						(size 1.27 1.27)
						(thickness 0.15)
					)
					(justify left bottom)
					(hide yes)
				)
			)
			(property "Description" "SMD Multilayer Ceramic Capacitor, 10 µF, 10 V, 0603 [1608 Metric], ± 10%, X5R, GRM Series"
				(at 20.32 -30.48 0)
				(effects
					(font
						(size 1.27 1.27)
					)
					(justify left bottom)
					(hide yes)
				)
			)
			(property "MPN" "GRM188R61A106KE69D"
				(at 20.32 -17.78 0)
				(effects
					(font
						(size 1.27 1.27)
						(thickness 0.15)
					)
					(justify left bottom)
					(hide yes)
				)
			)
			(property "Manufacturer" "Murata"
				(at 20.32 -20.32 0)
				(effects
					(font
						(size 1.27 1.27)
						(thickness 0.15)
					)
					(justify left bottom)
					(hide yes)
				)
			)
			(property "License" "Apache-2.0"
				(at 20.32 -22.86 0)
				(effects
					(font
						(size 1.27 1.27)
						(thickness 0.15)
					)
					(justify left bottom)
					(hide yes)
				)
			)
			(property "Author" "Antmicro"
				(at 20.32 -25.4 0)
				(effects
					(font
						(size 1.27 1.27)
						(thickness 0.15)
					)
					(justify left bottom)
					(hide yes)
				)
			)
			(property "Val" "10u"
				(at 20.32 -7.62 0)
				(effects
					(font
						(size 1.27 1.27)
						(thickness 0.15)
					)
					(justify left bottom)
				)
			)
			(property "Voltage" ""
				(at 20.32 -27.94 0)
				(effects
					(font
						(size 1.27 1.27)
					)
					(justify left bottom)
					(hide yes)
				)
			)
			(property "Dielectric" "template_dielectric"
				(at 20.32 -30.48 0)
				(effects
					(font
						(size 1.27 1.27)
					)
					(justify left bottom)
					(hide yes)
				)
			)
			(property "ki_keywords" "0603, SMT, CAPACITOR, PASSIVE, CERAMIC, MLCC"
				(at 0 0 0)
				(effects
					(font
						(size 1.27 1.27)
					)
					(hide yes)
				)
			)
			(symbol "C_10u_0603_0_1"
				(polyline
					(pts
						(xy 2.032 -1.524) (xy 2.032 1.524)
					)
					(stroke
						(width 0.3048)
						(type default)
					)
					(fill
						(type none)
					)
				)
				(polyline
					(pts
						(xy 3.048 -1.524) (xy 3.048 1.524)
					)
					(stroke
						(width 0.3302)
						(type default)
					)
					(fill
						(type none)
					)
				)
			)
			(symbol "C_10u_0603_1_1"
				(pin passive line
					(at 0 0 0)
					(length 2.032)
					(name "~"
						(effects
							(font
								(size 1.27 1.27)
							)
						)
					)
					(number "1"
						(effects
							(font
								(size 1.27 1.27)
							)
						)
					)
				)
				(pin passive line
					(at 5.08 0 180)
					(length 2.032)
					(name "~"
						(effects
							(font
								(size 1.27 1.27)
							)
						)
					)
					(number "2"
						(effects
							(font
								(size 1.27 1.27)
							)
						)
					)
				)
			)
		)
	(symbol "antmicroCapacitors0603:C_10u_25V_0603"
			(pin_numbers
				(hide yes)
			)
			(pin_names
				(hide yes)
			)
			(exclude_from_sim no)
			(in_bom yes)
			(on_board yes)
			(property "Reference" "C"
				(at 20.32 -5.08 0)
				(effects
					(font
						(size 1.27 1.27)
						(thickness 0.15)
					)
					(justify left bottom)
				)
			)
			(property "Value" "C_10u_25V_0603"
				(at 20.32 -10.16 0)
				(effects
					(font
						(size 1.27 1.27)
						(thickness 0.15)
					)
					(justify left bottom)
					(hide yes)
				)
			)
			(property "Footprint" "antmicro-footprints:C_0603_1608Metric"
				(at 20.32 -12.7 0)
				(effects
					(font
						(size 1.27 1.27)
						(thickness 0.15)
					)
					(justify left bottom)
					(hide yes)
				)
			)
			(property "Datasheet" "https://product.tdk.com/en/search/capacitor/ceramic/mlcc/info?part_no=C1608X5R1E106M080AC"
				(at 20.32 -15.24 0)
				(effects
					(font
						(size 1.27 1.27)
						(thickness 0.15)
					)
					(justify left bottom)
					(hide yes)
				)
			)
			(property "Description" "SMD Multilayer Ceramic Capacitor, 10 µF, 25 V, 0603 [1608 Metric], ± 20%, X5R, C"
				(at 20.32 -33.02 0)
				(effects
					(font
						(size 1.27 1.27)
					)
					(justify left bottom)
					(hide yes)
				)
			)
			(property "MPN" "C1608X5R1E106M080AC"
				(at 20.32 -17.78 0)
				(effects
					(font
						(size 1.27 1.27)
						(thickness 0.15)
					)
					(justify left bottom)
					(hide yes)
				)
			)
			(property "Manufacturer" "TDK"
				(at 20.32 -20.32 0)
				(effects
					(font
						(size 1.27 1.27)
						(thickness 0.15)
					)
					(justify left bottom)
					(hide yes)
				)
			)
			(property "License" "Apache-2.0"
				(at 20.32 -22.86 0)
				(effects
					(font
						(size 1.27 1.27)
						(thickness 0.15)
					)
					(justify left bottom)
					(hide yes)
				)
			)
			(property "Author" "Antmicro"
				(at 20.32 -25.4 0)
				(effects
					(font
						(size 1.27 1.27)
						(thickness 0.15)
					)
					(justify left bottom)
					(hide yes)
				)
			)
			(property "Val" "10u"
				(at 20.32 -7.62 0)
				(effects
					(font
						(size 1.27 1.27)
						(thickness 0.15)
					)
					(justify left bottom)
				)
			)
			(property "Voltage" "25V"
				(at 20.32 -27.94 0)
				(effects
					(font
						(size 1.27 1.27)
					)
					(justify left bottom)
					(hide yes)
				)
			)
			(property "Dielectric" ""
				(at 20.32 -30.48 0)
				(effects
					(font
						(size 1.27 1.27)
					)
					(justify left bottom)
					(hide yes)
				)
			)
			(property "ki_keywords" "0603, SMT, CAPACITOR, PASSIVE, CERAMIC, MLCC"
				(at 0 0 0)
				(effects
					(font
						(size 1.27 1.27)
					)
					(hide yes)
				)
			)
			(symbol "C_10u_25V_0603_0_1"
				(polyline
					(pts
						(xy 2.032 -1.524) (xy 2.032 1.524)
					)
					(stroke
						(width 0.3048)
						(type default)
					)
					(fill
						(type none)
					)
				)
				(polyline
					(pts
						(xy 3.048 -1.524) (xy 3.048 1.524)
					)
					(stroke
						(width 0.3302)
						(type default)
					)
					(fill
						(type none)
					)
				)
			)
			(symbol "C_10u_25V_0603_1_1"
				(pin passive line
					(at 0 0 0)
					(length 2.032)
					(name "~"
						(effects
							(font
								(size 1.27 1.27)
							)
						)
					)
					(number "1"
						(effects
							(font
								(size 1.27 1.27)
							)
						)
					)
				)
				(pin passive line
					(at 5.08 0 180)
					(length 2.032)
					(name "~"
						(effects
							(font
								(size 1.27 1.27)
							)
						)
					)
					(number "2"
						(effects
							(font
								(size 1.27 1.27)
							)
						)
					)
				)
			)
		)
	(symbol "antmicroCapacitors0603:C_47u_0603"
			(pin_numbers
				(hide yes)
			)
			(pin_names
				(hide yes)
			)
			(exclude_from_sim no)
			(in_bom yes)
			(on_board yes)
			(property "Reference" "C"
				(at 20.32 -5.08 0)
				(effects
					(font
						(size 1.27 1.27)
						(thickness 0.15)
					)
					(justify left bottom)
				)
			)
			(property "Value" "C_47u_0603"
				(at 20.32 -10.16 0)
				(effects
					(font
						(size 1.27 1.27)
						(thickness 0.15)
					)
					(justify left bottom)
					(hide yes)
				)
			)
			(property "Footprint" "antmicro-footprints:C_0603_1608Metric"
				(at 20.32 -12.7 0)
				(effects
					(font
						(size 1.27 1.27)
						(thickness 0.15)
					)
					(justify left bottom)
					(hide yes)
				)
			)
			(property "Datasheet" "https://www.murata.com/products/productdetail?partno=GRM188R60J476ME15%23"
				(at 20.32 -15.24 0)
				(effects
					(font
						(size 1.27 1.27)
						(thickness 0.15)
					)
					(justify left bottom)
					(hide yes)
				)
			)
			(property "Description" "SMD Multilayer Ceramic Capacitor, 47 µF, 6.3 V, 0603 [1608 Metric], ± 20%, X5R, GRM Series"
				(at 20.32 -33.02 0)
				(effects
					(font
						(size 1.27 1.27)
					)
					(justify left bottom)
					(hide yes)
				)
			)
			(property "MPN" "GRM188R60J476ME15D"
				(at 20.32 -17.78 0)
				(effects
					(font
						(size 1.27 1.27)
						(thickness 0.15)
					)
					(justify left bottom)
					(hide yes)
				)
			)
			(property "Manufacturer" "Murata"
				(at 20.32 -20.32 0)
				(effects
					(font
						(size 1.27 1.27)
						(thickness 0.15)
					)
					(justify left bottom)
					(hide yes)
				)
			)
			(property "License" "Apache-2.0"
				(at 20.32 -22.86 0)
				(effects
					(font
						(size 1.27 1.27)
						(thickness 0.15)
					)
					(justify left bottom)
					(hide yes)
				)
			)
			(property "Author" "Antmicro"
				(at 20.32 -25.4 0)
				(effects
					(font
						(size 1.27 1.27)
						(thickness 0.15)
					)
					(justify left bottom)
					(hide yes)
				)
			)
			(property "Val" "47u"
				(at 20.32 -7.62 0)
				(effects
					(font
						(size 1.27 1.27)
						(thickness 0.15)
					)
					(justify left bottom)
				)
			)
			(property "Voltage" ""
				(at 20.32 -27.94 0)
				(effects
					(font
						(size 1.27 1.27)
					)
					(justify left bottom)
					(hide yes)
				)
			)
			(property "Dielectric" ""
				(at 20.32 -30.48 0)
				(effects
					(font
						(size 1.27 1.27)
					)
					(justify left bottom)
					(hide yes)
				)
			)
			(property "ki_keywords" "0603, SMT, CAPACITOR, PASSIVE, CERAMIC, MLCC"
				(at 0 0 0)
				(effects
					(font
						(size 1.27 1.27)
					)
					(hide yes)
				)
			)
			(symbol "C_47u_0603_0_1"
				(polyline
					(pts
						(xy 2.032 -1.524) (xy 2.032 1.524)
					)
					(stroke
						(width 0.3048)
						(type default)
					)
					(fill
						(type none)
					)
				)
				(polyline
					(pts
						(xy 3.048 -1.524) (xy 3.048 1.524)
					)
					(stroke
						(width 0.3302)
						(type default)
					)
					(fill
						(type none)
					)
				)
			)
			(symbol "C_47u_0603_1_1"
				(pin passive line
					(at 0 0 0)
					(length 2.032)
					(name "~"
						(effects
							(font
								(size 1.27 1.27)
							)
						)
					)
					(number "1"
						(effects
							(font
								(size 1.27 1.27)
							)
						)
					)
				)
				(pin passive line
					(at 5.08 0 180)
					(length 2.032)
					(name "~"
						(effects
							(font
								(size 1.27 1.27)
							)
						)
					)
					(number "2"
						(effects
							(font
								(size 1.27 1.27)
							)
						)
					)
				)
			)
		)
	(symbol "antmicroCapacitors0603:C_4u7_0603"
			(pin_numbers
				(hide yes)
			)
			(pin_names
				(hide yes)
			)
			(exclude_from_sim no)
			(in_bom yes)
			(on_board yes)
			(property "Reference" "C"
				(at 20.32 -5.08 0)
				(effects
					(font
						(size 1.27 1.27)
						(thickness 0.15)
					)
					(justify left bottom)
				)
			)
			(property "Value" "C_4u7_0603"
				(at 20.32 -10.16 0)
				(effects
					(font
						(size 1.27 1.27)
						(thickness 0.15)
					)
					(justify left bottom)
					(hide yes)
				)
			)
			(property "Footprint" "antmicro-footprints:C_0603_1608Metric"
				(at 20.32 -12.7 0)
				(effects
					(font
						(size 1.27 1.27)
						(thickness 0.15)
					)
					(justify left bottom)
					(hide yes)
				)
			)
			(property "Datasheet" "https://product.tdk.com/en/search/capacitor/ceramic/mlcc/info?part_no=C1608X5R1V475M080AC"
				(at 20.32 -15.24 0)
				(effects
					(font
						(size 1.27 1.27)
						(thickness 0.15)
					)
					(justify left bottom)
					(hide yes)
				)
			)
			(property "Description" "SMD Multilayer Ceramic Capacitor, 4.7 µF, 35 V, 0603 [1608 Metric], ± 20%, X5R, C"
				(at 20.32 -33.02 0)
				(effects
					(font
						(size 1.27 1.27)
					)
					(justify left bottom)
					(hide yes)
				)
			)
			(property "MPN" "C1608X5R1V475M080AC"
				(at 20.32 -17.78 0)
				(effects
					(font
						(size 1.27 1.27)
						(thickness 0.15)
					)
					(justify left bottom)
					(hide yes)
				)
			)
			(property "Manufacturer" "TDK"
				(at 20.32 -20.32 0)
				(effects
					(font
						(size 1.27 1.27)
						(thickness 0.15)
					)
					(justify left bottom)
					(hide yes)
				)
			)
			(property "License" "Apache-2.0"
				(at 20.32 -22.86 0)
				(effects
					(font
						(size 1.27 1.27)
						(thickness 0.15)
					)
					(justify left bottom)
					(hide yes)
				)
			)
			(property "Author" "Antmicro"
				(at 20.32 -25.4 0)
				(effects
					(font
						(size 1.27 1.27)
						(thickness 0.15)
					)
					(justify left bottom)
					(hide yes)
				)
			)
			(property "Val" "4u7"
				(at 20.32 -7.62 0)
				(effects
					(font
						(size 1.27 1.27)
						(thickness 0.15)
					)
					(justify left bottom)
				)
			)
			(property "Voltage" ""
				(at 20.32 -27.94 0)
				(effects
					(font
						(size 1.27 1.27)
					)
					(justify left bottom)
					(hide yes)
				)
			)
			(property "Dielectric" ""
				(at 20.32 -30.48 0)
				(effects
					(font
						(size 1.27 1.27)
					)
					(justify left bottom)
					(hide yes)
				)
			)
			(property "ki_keywords" "0603, SMT, CAPACITOR, PASSIVE, CERAMIC, MLCC"
				(at 0 0 0)
				(effects
					(font
						(size 1.27 1.27)
					)
					(hide yes)
				)
			)
			(symbol "C_4u7_0603_0_1"
				(polyline
					(pts
						(xy 2.032 -1.524) (xy 2.032 1.524)
					)
					(stroke
						(width 0.3048)
						(type default)
					)
					(fill
						(type none)
					)
				)
				(polyline
					(pts
						(xy 3.048 -1.524) (xy 3.048 1.524)
					)
					(stroke
						(width 0.3302)
						(type default)
					)
					(fill
						(type none)
					)
				)
			)
			(symbol "C_4u7_0603_1_1"
				(pin passive line
					(at 0 0 0)
					(length 2.032)
					(name "~"
						(effects
							(font
								(size 1.27 1.27)
							)
						)
					)
					(number "1"
						(effects
							(font
								(size 1.27 1.27)
							)
						)
					)
				)
				(pin passive line
					(at 5.08 0 180)
					(length 2.032)
					(name "~"
						(effects
							(font
								(size 1.27 1.27)
							)
						)
					)
					(number "2"
						(effects
							(font
								(size 1.27 1.27)
							)
						)
					)
				)
			)
		)
	(symbol "antmicroCapacitorsmisc:C_100n_6V3_0402"
			(pin_numbers
				(hide yes)
			)
			(pin_names
				(hide yes)
			)
			(exclude_from_sim no)
			(in_bom yes)
			(on_board yes)
			(property "Reference" "C"
				(at 20.32 -5.08 0)
				(effects
					(font
						(size 1.27 1.27)
						(thickness 0.15)
					)
					(justify left bottom)
				)
			)
			(property "Value" "C_100n_6V3_0402"
				(at 20.32 -10.16 0)
				(effects
					(font
						(size 1.27 1.27)
						(thickness 0.15)
					)
					(justify left bottom)
					(hide yes)
				)
			)
			(property "Footprint" "antmicro-footprints:C_0402_1005Metric"
				(at 20.32 -12.7 0)
				(effects
					(font
						(size 1.27 1.27)
						(thickness 0.15)
					)
					(justify left bottom)
					(hide yes)
				)
			)
			(property "Datasheet" "https://www.passivecomponent.com/wp-content/uploads/datasheet/WTC_MLCC_General_Purpose.pdf"
				(at 20.32 -15.24 0)
				(effects
					(font
						(size 1.27 1.27)
						(thickness 0.15)
					)
					(justify left bottom)
					(hide yes)
				)
			)
			(property "Description" "SMT Multilayer Ceramic Capacitor, 0.1 µF, 6.3 V, 0402 [1005 Metric], ± 10%, X5R, Walsin MLCC"
				(at 20.32 -33.02 0)
				(effects
					(font
						(size 1.27 1.27)
					)
					(justify left bottom)
					(hide yes)
				)
			)
			(property "MPN" "0402X104K6R3CT"
				(at 20.32 -17.78 0)
				(effects
					(font
						(size 1.27 1.27)
						(thickness 0.15)
					)
					(justify left bottom)
					(hide yes)
				)
			)
			(property "Manufacturer" "Walsin"
				(at 20.32 -20.32 0)
				(effects
					(font
						(size 1.27 1.27)
						(thickness 0.15)
					)
					(justify left bottom)
					(hide yes)
				)
			)
			(property "License" "Apache-2.0"
				(at 20.32 -22.86 0)
				(effects
					(font
						(size 1.27 1.27)
						(thickness 0.15)
					)
					(justify left bottom)
					(hide yes)
				)
			)
			(property "Author" "Antmicro"
				(at 20.32 -25.4 0)
				(effects
					(font
						(size 1.27 1.27)
						(thickness 0.15)
					)
					(justify left bottom)
					(hide yes)
				)
			)
			(property "Val" "100n"
				(at 20.32 -7.62 0)
				(effects
					(font
						(size 1.27 1.27)
						(thickness 0.15)
					)
					(justify left bottom)
				)
			)
			(property "Voltage" ""
				(at 20.32 -27.94 0)
				(effects
					(font
						(size 1.27 1.27)
					)
					(justify left bottom)
					(hide yes)
				)
			)
			(property "Dielectric" ""
				(at 20.32 -30.48 0)
				(effects
					(font
						(size 1.27 1.27)
					)
					(justify left bottom)
					(hide yes)
				)
			)
			(property "Public" "False"
				(at 20.32 -33.02 0)
				(effects
					(font
						(size 1.27 1.27)
					)
					(justify left bottom)
					(hide yes)
				)
			)
			(property "ki_keywords" "0402, SMT, CAPACITOR, PASSIVE"
				(at 0 0 0)
				(effects
					(font
						(size 1.27 1.27)
					)
					(hide yes)
				)
			)
			(symbol "C_100n_6V3_0402_0_1"
				(polyline
					(pts
						(xy 2.032 -1.524) (xy 2.032 1.524)
					)
					(stroke
						(width 0.3048)
						(type default)
					)
					(fill
						(type none)
					)
				)
				(polyline
					(pts
						(xy 3.048 -1.524) (xy 3.048 1.524)
					)
					(stroke
						(width 0.3302)
						(type default)
					)
					(fill
						(type none)
					)
				)
			)
			(symbol "C_100n_6V3_0402_1_1"
				(pin passive line
					(at 0 0 0)
					(length 2.032)
					(name "~"
						(effects
							(font
								(size 1.27 1.27)
							)
						)
					)
					(number "1"
						(effects
							(font
								(size 1.27 1.27)
							)
						)
					)
				)
				(pin passive line
					(at 5.08 0 180)
					(length 2.032)
					(name "~"
						(effects
							(font
								(size 1.27 1.27)
							)
						)
					)
					(number "2"
						(effects
							(font
								(size 1.27 1.27)
							)
						)
					)
				)
			)
		)
	(symbol "antmicroCapacitorsmisc:C_100u_1210"
			(pin_numbers
				(hide yes)
			)
			(pin_names
				(hide yes)
			)
			(exclude_from_sim no)
			(in_bom yes)
			(on_board yes)
			(property "Reference" "C"
				(at 20.32 -5.08 0)
				(effects
					(font
						(size 1.27 1.27)
						(thickness 0.15)
					)
					(justify left bottom)
				)
			)
			(property "Value" "C_100u_1210"
				(at 20.32 -10.16 0)
				(effects
					(font
						(size 1.27 1.27)
						(thickness 0.15)
					)
					(justify left bottom)
					(hide yes)
				)
			)
			(property "Footprint" "antmicro-footprints:C_1210_3225Metric"
				(at 20.32 -12.7 0)
				(effects
					(font
						(size 1.27 1.27)
						(thickness 0.15)
					)
					(justify left bottom)
					(hide yes)
				)
			)
			(property "Datasheet" "https://product.samsungsem.com/mlcc/CL32A107MQVNNN.do"
				(at 20.32 -15.24 0)
				(effects
					(font
						(size 1.27 1.27)
						(thickness 0.15)
					)
					(justify left bottom)
					(hide yes)
				)
			)
			(property "Description" "SMD Multilayer Ceramic Capacitor, 100 µF, 6.3 V, 1210 [3225 Metric], ± 20%, X5R, CL"
				(at 20.32 -33.02 0)
				(effects
					(font
						(size 1.27 1.27)
					)
					(justify left bottom)
					(hide yes)
				)
			)
			(property "MPN" "CL32A107MQVNNNE"
				(at 20.32 -17.78 0)
				(effects
					(font
						(size 1.27 1.27)
						(thickness 0.15)
					)
					(justify left bottom)
					(hide yes)
				)
			)
			(property "Manufacturer" "Samsung Electro-Mechanics"
				(at 20.32 -20.32 0)
				(effects
					(font
						(size 1.27 1.27)
						(thickness 0.15)
					)
					(justify left bottom)
					(hide yes)
				)
			)
			(property "License" "Apache-2.0"
				(at 20.32 -22.86 0)
				(effects
					(font
						(size 1.27 1.27)
						(thickness 0.15)
					)
					(justify left bottom)
					(hide yes)
				)
			)
			(property "Author" "Antmicro"
				(at 20.32 -25.4 0)
				(effects
					(font
						(size 1.27 1.27)
						(thickness 0.15)
					)
					(justify left bottom)
					(hide yes)
				)
			)
			(property "Val" "100u"
				(at 20.32 -7.62 0)
				(effects
					(font
						(size 1.27 1.27)
						(thickness 0.15)
					)
					(justify left bottom)
				)
			)
			(property "Voltage" ""
				(at 20.32 -27.94 0)
				(effects
					(font
						(size 1.27 1.27)
					)
					(justify left bottom)
					(hide yes)
				)
			)
			(property "Dielectric" ""
				(at 20.32 -30.48 0)
				(effects
					(font
						(size 1.27 1.27)
					)
					(justify left bottom)
					(hide yes)
				)
			)
			(property "Public" "False"
				(at 20.32 -33.02 0)
				(effects
					(font
						(size 1.27 1.27)
					)
					(justify left bottom)
					(hide yes)
				)
			)
			(property "ki_keywords" "1210, SMT, CAPACITOR, PASSIVE"
				(at 0 0 0)
				(effects
					(font
						(size 1.27 1.27)
					)
					(hide yes)
				)
			)
			(symbol "C_100u_1210_0_1"
				(polyline
					(pts
						(xy 2.032 -1.524) (xy 2.032 1.524)
					)
					(stroke
						(width 0.3048)
						(type default)
					)
					(fill
						(type none)
					)
				)
				(polyline
					(pts
						(xy 3.048 -1.524) (xy 3.048 1.524)
					)
					(stroke
						(width 0.3302)
						(type default)
					)
					(fill
						(type none)
					)
				)
			)
			(symbol "C_100u_1210_1_1"
				(pin passive line
					(at 0 0 0)
					(length 2.032)
					(name "~"
						(effects
							(font
								(size 1.27 1.27)
							)
						)
					)
					(number "1"
						(effects
							(font
								(size 1.27 1.27)
							)
						)
					)
				)
				(pin passive line
					(at 5.08 0 180)
					(length 2.032)
					(name "~"
						(effects
							(font
								(size 1.27 1.27)
							)
						)
					)
					(number "2"
						(effects
							(font
								(size 1.27 1.27)
							)
						)
					)
				)
			)
		)
	(symbol "antmicroCapacitorsmisc:C_2u2_0603_25V"
			(pin_numbers
				(hide yes)
			)
			(pin_names
				(hide yes)
			)
			(exclude_from_sim no)
			(in_bom yes)
			(on_board yes)
			(property "Reference" "C"
				(at 20.32 -5.08 0)
				(effects
					(font
						(size 1.27 1.27)
						(thickness 0.15)
					)
					(justify left bottom)
				)
			)
			(property "Value" "C_2u2_0603_25V"
				(at 20.32 -10.16 0)
				(effects
					(font
						(size 1.27 1.27)
						(thickness 0.15)
					)
					(justify left bottom)
					(hide yes)
				)
			)
			(property "Footprint" "antmicro-footprints:C_0603_1608Metric"
				(at 20.32 -12.7 0)
				(effects
					(font
						(size 1.27 1.27)
						(thickness 0.15)
					)
					(justify left bottom)
					(hide yes)
				)
			)
			(property "Datasheet" "https://www.murata.com/products/productdetail?partno=GRM188R61E225KA12%23"
				(at 20.32 -15.24 0)
				(effects
					(font
						(size 1.27 1.27)
						(thickness 0.15)
					)
					(justify left bottom)
					(hide yes)
				)
			)
			(property "Description" "SMD Multilayer Ceramic Capacitor, 2.2 µF, 25 V, 0603 [1608 Metric], ± 10%, X5R, GRM Series"
				(at 20.32 -33.02 0)
				(effects
					(font
						(size 1.27 1.27)
					)
					(justify left bottom)
					(hide yes)
				)
			)
			(property "MPN" "GRM188R61E225KA12D"
				(at 20.32 -17.78 0)
				(effects
					(font
						(size 1.27 1.27)
						(thickness 0.15)
					)
					(justify left bottom)
					(hide yes)
				)
			)
			(property "Manufacturer" "Murata"
				(at 20.32 -20.32 0)
				(effects
					(font
						(size 1.27 1.27)
						(thickness 0.15)
					)
					(justify left bottom)
					(hide yes)
				)
			)
			(property "License" "Apache-2.0"
				(at 20.32 -22.86 0)
				(effects
					(font
						(size 1.27 1.27)
						(thickness 0.15)
					)
					(justify left bottom)
					(hide yes)
				)
			)
			(property "Author" "Antmicro"
				(at 20.32 -25.4 0)
				(effects
					(font
						(size 1.27 1.27)
						(thickness 0.15)
					)
					(justify left bottom)
					(hide yes)
				)
			)
			(property "Val" "2u2"
				(at 20.32 -7.62 0)
				(effects
					(font
						(size 1.27 1.27)
						(thickness 0.15)
					)
					(justify left bottom)
				)
			)
			(property "Voltage" ""
				(at 20.32 -27.94 0)
				(effects
					(font
						(size 1.27 1.27)
					)
					(justify left bottom)
					(hide yes)
				)
			)
			(property "Dielectric" ""
				(at 20.32 -30.48 0)
				(effects
					(font
						(size 1.27 1.27)
					)
					(justify left bottom)
					(hide yes)
				)
			)
			(property "Public" "False"
				(at 20.32 -33.02 0)
				(effects
					(font
						(size 1.27 1.27)
					)
					(justify left bottom)
					(hide yes)
				)
			)
			(property "ki_keywords" "0603, SMT, CAPACITOR, PASSIVE"
				(at 0 0 0)
				(effects
					(font
						(size 1.27 1.27)
					)
					(hide yes)
				)
			)
			(symbol "C_2u2_0603_25V_0_1"
				(polyline
					(pts
						(xy 2.032 -1.524) (xy 2.032 1.524)
					)
					(stroke
						(width 0.3048)
						(type default)
					)
					(fill
						(type none)
					)
				)
				(polyline
					(pts
						(xy 3.048 -1.524) (xy 3.048 1.524)
					)
					(stroke
						(width 0.3302)
						(type default)
					)
					(fill
						(type none)
					)
				)
			)
			(symbol "C_2u2_0603_25V_1_1"
				(pin passive line
					(at 0 0 0)
					(length 2.032)
					(name "~"
						(effects
							(font
								(size 1.27 1.27)
							)
						)
					)
					(number "1"
						(effects
							(font
								(size 1.27 1.27)
							)
						)
					)
				)
				(pin passive line
					(at 5.08 0 180)
					(length 2.032)
					(name "~"
						(effects
							(font
								(size 1.27 1.27)
							)
						)
					)
					(number "2"
						(effects
							(font
								(size 1.27 1.27)
							)
						)
					)
				)
			)
		)
	(symbol "antmicroCapacitorsmisc:C_470n_0201"
			(pin_numbers
				(hide yes)
			)
			(pin_names
				(hide yes)
			)
			(exclude_from_sim no)
			(in_bom yes)
			(on_board yes)
			(property "Reference" "C"
				(at 20.32 -5.08 0)
				(effects
					(font
						(size 1.27 1.27)
						(thickness 0.15)
					)
					(justify left bottom)
				)
			)
			(property "Value" "C_470n_0201"
				(at 20.32 -10.16 0)
				(effects
					(font
						(size 1.27 1.27)
						(thickness 0.15)
					)
					(justify left bottom)
					(hide yes)
				)
			)
			(property "Footprint" "antmicro-footprints:C_0201"
				(at 20.32 -12.7 0)
				(effects
					(font
						(size 1.27 1.27)
						(thickness 0.15)
					)
					(justify left bottom)
					(hide yes)
				)
			)
			(property "Datasheet" "https://product.tdk.com/en/search/capacitor/ceramic/mlcc/info?part_no=C0603X5R1A474M030BC"
				(at 20.32 -15.24 0)
				(effects
					(font
						(size 1.27 1.27)
						(thickness 0.15)
					)
					(justify left bottom)
					(hide yes)
				)
			)
			(property "Description" "SMD Multilayer Ceramic Capacitor, 0.47 µF, 10 V, 0201 [0603 Metric], ± 20%, X5R, C"
				(at 20.32 -33.02 0)
				(effects
					(font
						(size 1.27 1.27)
					)
					(justify left bottom)
					(hide yes)
				)
			)
			(property "MPN" "C0603X5R1A474M030BC"
				(at 20.32 -17.78 0)
				(effects
					(font
						(size 1.27 1.27)
						(thickness 0.15)
					)
					(justify left bottom)
					(hide yes)
				)
			)
			(property "Manufacturer" "TDK"
				(at 20.32 -20.32 0)
				(effects
					(font
						(size 1.27 1.27)
						(thickness 0.15)
					)
					(justify left bottom)
					(hide yes)
				)
			)
			(property "License" "Apache-2.0"
				(at 20.32 -22.86 0)
				(effects
					(font
						(size 1.27 1.27)
						(thickness 0.15)
					)
					(justify left bottom)
					(hide yes)
				)
			)
			(property "Author" "Antmicro"
				(at 20.32 -25.4 0)
				(effects
					(font
						(size 1.27 1.27)
						(thickness 0.15)
					)
					(justify left bottom)
					(hide yes)
				)
			)
			(property "Val" "470n"
				(at 20.32 -7.62 0)
				(effects
					(font
						(size 1.27 1.27)
						(thickness 0.15)
					)
					(justify left bottom)
				)
			)
			(property "Voltage" ""
				(at 20.32 -27.94 0)
				(effects
					(font
						(size 1.27 1.27)
					)
					(justify left bottom)
					(hide yes)
				)
			)
			(property "Dielectric" ""
				(at 20.32 -30.48 0)
				(effects
					(font
						(size 1.27 1.27)
					)
					(justify left bottom)
					(hide yes)
				)
			)
			(property "Public" "False"
				(at 20.32 -33.02 0)
				(effects
					(font
						(size 1.27 1.27)
					)
					(justify left bottom)
					(hide yes)
				)
			)
			(property "ki_keywords" "0201, SMT, CAPACITOR, PASSIVE"
				(at 0 0 0)
				(effects
					(font
						(size 1.27 1.27)
					)
					(hide yes)
				)
			)
			(symbol "C_470n_0201_0_1"
				(polyline
					(pts
						(xy 2.032 -1.524) (xy 2.032 1.524)
					)
					(stroke
						(width 0.3048)
						(type default)
					)
					(fill
						(type none)
					)
				)
				(polyline
					(pts
						(xy 3.048 -1.524) (xy 3.048 1.524)
					)
					(stroke
						(width 0.3302)
						(type default)
					)
					(fill
						(type none)
					)
				)
			)
			(symbol "C_470n_0201_1_1"
				(pin passive line
					(at 0 0 0)
					(length 2.032)
					(name "~"
						(effects
							(font
								(size 1.27 1.27)
							)
						)
					)
					(number "1"
						(effects
							(font
								(size 1.27 1.27)
							)
						)
					)
				)
				(pin passive line
					(at 5.08 0 180)
					(length 2.032)
					(name "~"
						(effects
							(font
								(size 1.27 1.27)
							)
						)
					)
					(number "2"
						(effects
							(font
								(size 1.27 1.27)
							)
						)
					)
				)
			)
		)
	(symbol "antmicroCapacitorsmisc:C_47u_1210"
			(pin_numbers
				(hide yes)
			)
			(pin_names
				(hide yes)
			)
			(exclude_from_sim no)
			(in_bom yes)
			(on_board yes)
			(property "Reference" "C"
				(at 20.32 -5.08 0)
				(effects
					(font
						(size 1.27 1.27)
						(thickness 0.15)
					)
					(justify left bottom)
				)
			)
			(property "Value" "C_47u_1210"
				(at 20.32 -10.16 0)
				(effects
					(font
						(size 1.27 1.27)
						(thickness 0.15)
					)
					(justify left bottom)
					(hide yes)
				)
			)
			(property "Footprint" "antmicro-footprints:C_1210_3225Metric"
				(at 20.32 -12.7 0)
				(effects
					(font
						(size 1.27 1.27)
						(thickness 0.15)
					)
					(justify left bottom)
					(hide yes)
				)
			)
			(property "Datasheet" "https://www.kemet.com/en/us/capacitors/product/C1210C476K8RACTU.html"
				(at 20.32 -15.24 0)
				(effects
					(font
						(size 1.27 1.27)
						(thickness 0.15)
					)
					(justify left bottom)
					(hide yes)
				)
			)
			(property "Description" "SMD Multilayer Ceramic Capacitor, 47 µF, 10 V, 1210 [3225 Metric], ± 10%, X7R, C Series KEMET"
				(at 20.32 -33.02 0)
				(effects
					(font
						(size 1.27 1.27)
					)
					(justify left bottom)
					(hide yes)
				)
			)
			(property "MPN" "C1210C476K8RACTU"
				(at 20.32 -17.78 0)
				(effects
					(font
						(size 1.27 1.27)
						(thickness 0.15)
					)
					(justify left bottom)
					(hide yes)
				)
			)
			(property "Manufacturer" "KEMET"
				(at 20.32 -20.32 0)
				(effects
					(font
						(size 1.27 1.27)
						(thickness 0.15)
					)
					(justify left bottom)
					(hide yes)
				)
			)
			(property "License" "Apache-2.0"
				(at 20.32 -22.86 0)
				(effects
					(font
						(size 1.27 1.27)
						(thickness 0.15)
					)
					(justify left bottom)
					(hide yes)
				)
			)
			(property "Author" "Antmicro"
				(at 20.32 -25.4 0)
				(effects
					(font
						(size 1.27 1.27)
						(thickness 0.15)
					)
					(justify left bottom)
					(hide yes)
				)
			)
			(property "Val" "47u"
				(at 20.32 -7.62 0)
				(effects
					(font
						(size 1.27 1.27)
						(thickness 0.15)
					)
					(justify left bottom)
				)
			)
			(property "Voltage" ""
				(at 20.32 -27.94 0)
				(effects
					(font
						(size 1.27 1.27)
					)
					(justify left bottom)
					(hide yes)
				)
			)
			(property "Dielectric" ""
				(at 20.32 -30.48 0)
				(effects
					(font
						(size 1.27 1.27)
					)
					(justify left bottom)
					(hide yes)
				)
			)
			(property "Public" "False"
				(at 20.32 -33.02 0)
				(effects
					(font
						(size 1.27 1.27)
					)
					(justify left bottom)
					(hide yes)
				)
			)
			(property "ki_keywords" "1210, SMT, CAPACITOR, PASSIVE"
				(at 0 0 0)
				(effects
					(font
						(size 1.27 1.27)
					)
					(hide yes)
				)
			)
			(symbol "C_47u_1210_0_1"
				(polyline
					(pts
						(xy 2.032 -1.524) (xy 2.032 1.524)
					)
					(stroke
						(width 0.3048)
						(type default)
					)
					(fill
						(type none)
					)
				)
				(polyline
					(pts
						(xy 3.048 -1.524) (xy 3.048 1.524)
					)
					(stroke
						(width 0.3302)
						(type default)
					)
					(fill
						(type none)
					)
				)
			)
			(symbol "C_47u_1210_1_1"
				(pin passive line
					(at 0 0 0)
					(length 2.032)
					(name "~"
						(effects
							(font
								(size 1.27 1.27)
							)
						)
					)
					(number "1"
						(effects
							(font
								(size 1.27 1.27)
							)
						)
					)
				)
				(pin passive line
					(at 5.08 0 180)
					(length 2.032)
					(name "~"
						(effects
							(font
								(size 1.27 1.27)
							)
						)
					)
					(number "2"
						(effects
							(font
								(size 1.27 1.27)
							)
						)
					)
				)
			)
		)
	(symbol "antmicroCapacitorspol:C_Pol_330u_6.3V_KEMET-T520-D"
			(pin_numbers
				(hide yes)
			)
			(pin_names
				(hide yes)
			)
			(exclude_from_sim no)
			(in_bom yes)
			(on_board yes)
			(property "Reference" "C"
				(at 13.97 0 0)
				(effects
					(font
						(size 1.27 1.27)
						(thickness 0.15)
					)
					(justify left bottom)
				)
			)
			(property "Value" "C_Pol_330u_6.3V_KEMET-T520-D"
				(at 13.97 -2.54 0)
				(effects
					(font
						(size 1.27 1.27)
						(thickness 0.15)
					)
					(justify left bottom)
					(hide yes)
				)
			)
			(property "Footprint" "antmicro-footprints:C_Pol_EIA-D"
				(at 13.97 -7.62 0)
				(effects
					(font
						(size 1.27 1.27)
						(thickness 0.15)
					)
					(justify left bottom)
					(hide yes)
				)
			)
			(property "Datasheet" "https://www.kemet.com/en/us/capacitors/product/T520D337M006ATE045.html"
				(at 13.97 -10.16 0)
				(effects
					(font
						(size 1.27 1.27)
						(thickness 0.15)
					)
					(justify left bottom)
					(hide yes)
				)
			)
			(property "Description" "Tantalum Polymer Capacitor, KO-CAP®, 330 µF, ± 20%, 6.3 V, D, 0.045 ohm, 2917 [7343 Metric]"
				(at 13.97 -25.4 0)
				(effects
					(font
						(size 1.27 1.27)
					)
					(justify left bottom)
					(hide yes)
				)
			)
			(property "MPN" "T520D337M006ATE045"
				(at 13.97 -12.7 0)
				(effects
					(font
						(size 1.27 1.27)
						(thickness 0.15)
					)
					(justify left bottom)
					(hide yes)
				)
			)
			(property "Manufacturer" "KEMET"
				(at 13.97 -15.24 0)
				(effects
					(font
						(size 1.27 1.27)
						(thickness 0.15)
					)
					(justify left bottom)
					(hide yes)
				)
			)
			(property "License" "Apache-2.0"
				(at 13.97 -17.78 0)
				(effects
					(font
						(size 1.27 1.27)
						(thickness 0.15)
					)
					(justify left bottom)
					(hide yes)
				)
			)
			(property "Author" "Antmicro"
				(at 13.97 -20.32 0)
				(effects
					(font
						(size 1.27 1.27)
						(thickness 0.15)
					)
					(justify left bottom)
					(hide yes)
				)
			)
			(property "Val" "330u"
				(at 13.97 -5.08 0)
				(effects
					(font
						(size 1.27 1.27)
						(thickness 0.15)
					)
					(justify left bottom)
				)
			)
			(property "Voltage" "6.3V"
				(at 13.97 -22.86 0)
				(effects
					(font
						(size 1.27 1.27)
					)
					(justify left bottom)
					(hide yes)
				)
			)
			(property "Dielectric" "template_dielectric"
				(at 13.97 -25.4 0)
				(effects
					(font
						(size 1.27 1.27)
					)
					(justify left bottom)
					(hide yes)
				)
			)
			(property "ki_keywords" "SMT, CAPACITOR, PASSIVE, POLARIZED, TANTALUM"
				(at 0 0 0)
				(effects
					(font
						(size 1.27 1.27)
					)
					(hide yes)
				)
			)
			(symbol "C_Pol_330u_6.3V_KEMET-T520-D_0_1"
				(polyline
					(pts
						(xy 0.9652 1.27) (xy 0.9652 1.778)
					)
					(stroke
						(width 0)
						(type default)
					)
					(fill
						(type none)
					)
				)
				(polyline
					(pts
						(xy 1.2192 1.524) (xy 0.7112 1.524)
					)
					(stroke
						(width 0)
						(type default)
					)
					(fill
						(type none)
					)
				)
				(rectangle
					(start 1.905 -1.524)
					(end 2.286 1.524)
					(stroke
						(width 0)
						(type default)
					)
					(fill
						(type none)
					)
				)
				(rectangle
					(start 2.921 -1.524)
					(end 3.302 1.524)
					(stroke
						(width 0)
						(type default)
					)
					(fill
						(type outline)
					)
				)
			)
			(symbol "C_Pol_330u_6.3V_KEMET-T520-D_1_1"
				(pin passive line
					(at 0 0 0)
					(length 1.8542)
					(name "~"
						(effects
							(font
								(size 1.27 1.27)
							)
						)
					)
					(number "1"
						(effects
							(font
								(size 1.27 1.27)
							)
						)
					)
				)
				(pin passive line
					(at 5.08 0 180)
					(length 1.8542)
					(name "~"
						(effects
							(font
								(size 1.27 1.27)
							)
						)
					)
					(number "2"
						(effects
							(font
								(size 1.27 1.27)
							)
						)
					)
				)
			)
		)
	(symbol "antmicroDCDCConverters:TPS62823DLCT"
			(pin_names
				(offset 1.016)
			)
			(exclude_from_sim no)
			(in_bom yes)
			(on_board yes)
			(property "Reference" "U"
				(at 34.29 1.27 0)
				(effects
					(font
						(size 1.27 1.27)
						(thickness 0.15)
					)
					(justify left bottom)
				)
			)
			(property "Value" "TPS62823DLCT"
				(at 34.29 -1.27 0)
				(effects
					(font
						(size 1.27 1.27)
						(thickness 0.15)
					)
					(justify left bottom)
					(hide yes)
				)
			)
			(property "Footprint" "antmicro-footprints:QFN-8_2x1.5mm"
				(at 34.29 -3.81 0)
				(effects
					(font
						(size 1.27 1.27)
						(thickness 0.15)
					)
					(justify left bottom)
					(hide yes)
				)
			)
			(property "Datasheet" "https://www.ti.com/lit/ds/symlink/tps62823.pdf?ts=1685970309606&ref_url=https%253A%252F%252Fwww.ti.com%252Fproduct%252FTPS62823%252Fpart-details%252FTPS62823DLCT"
				(at 34.29 -6.35 0)
				(effects
					(font
						(size 1.27 1.27)
						(thickness 0.15)
					)
					(justify left bottom)
					(hide yes)
				)
			)
			(property "Description" "DC/DC converter"
				(at 34.29 -19.05 0)
				(effects
					(font
						(size 1.27 1.27)
					)
					(justify left bottom)
					(hide yes)
				)
			)
			(property "MPN" "TPS62823DLCT"
				(at 34.29 -8.89 0)
				(effects
					(font
						(size 1.27 1.27)
						(thickness 0.15)
					)
					(justify left bottom)
				)
			)
			(property "Manufacturer" "Texas Instruments"
				(at 34.29 -11.43 0)
				(effects
					(font
						(size 1.27 1.27)
						(thickness 0.15)
					)
					(justify left bottom)
					(hide yes)
				)
			)
			(property "Author" "Antmicro"
				(at 34.29 -13.97 0)
				(effects
					(font
						(size 1.27 1.27)
						(thickness 0.15)
					)
					(justify left bottom)
					(hide yes)
				)
			)
			(property "License" "Apache-2.0"
				(at 34.29 -16.51 0)
				(effects
					(font
						(size 1.27 1.27)
						(thickness 0.15)
					)
					(justify left bottom)
					(hide yes)
				)
			)
			(property "ki_keywords" "SMT, PMIC, IC, SWITCHING, VOLTAGE, REGULATOR, DC-DC"
				(at 0 0 0)
				(effects
					(font
						(size 1.27 1.27)
					)
					(hide yes)
				)
			)
			(symbol "TPS62823DLCT_0_0"
				(pin no_connect line
					(at 17.78 -2.54 180)
					(length 2.54)
					(hide yes)
					(name "NC"
						(effects
							(font
								(size 1.27 1.27)
							)
						)
					)
					(number "4"
						(effects
							(font
								(size 1.27 1.27)
							)
						)
					)
				)
			)
			(symbol "TPS62823DLCT_0_1"
				(rectangle
					(start 2.54 2.54)
					(end 17.78 -15.24)
					(stroke
						(width 0)
						(type default)
					)
					(fill
						(type background)
					)
				)
			)
			(symbol "TPS62823DLCT_1_1"
				(pin power_in line
					(at 0 0 0)
					(length 2.54)
					(name "VIN"
						(effects
							(font
								(size 1.27 1.27)
							)
						)
					)
					(number "7"
						(effects
							(font
								(size 1.27 1.27)
							)
						)
					)
				)
				(pin input line
					(at 0 -6.35 0)
					(length 2.54)
					(name "EN"
						(effects
							(font
								(size 1.27 1.27)
							)
						)
					)
					(number "1"
						(effects
							(font
								(size 1.27 1.27)
							)
						)
					)
				)
				(pin output line
					(at 0 -12.7 0)
					(length 2.54)
					(name "PG"
						(effects
							(font
								(size 1.27 1.27)
							)
						)
					)
					(number "8"
						(effects
							(font
								(size 1.27 1.27)
							)
						)
					)
				)
				(pin bidirectional line
					(at 20.32 0 180)
					(length 2.54)
					(name "SW"
						(effects
							(font
								(size 1.27 1.27)
							)
						)
					)
					(number "6"
						(effects
							(font
								(size 1.27 1.27)
							)
						)
					)
				)
				(pin bidirectional line
					(at 20.32 -6.35 180)
					(length 2.54)
					(name "FB"
						(effects
							(font
								(size 1.27 1.27)
							)
						)
					)
					(number "2"
						(effects
							(font
								(size 1.27 1.27)
							)
						)
					)
				)
				(pin power_in line
					(at 20.32 -10.16 180)
					(length 2.54)
					(name "AGND"
						(effects
							(font
								(size 1.27 1.27)
							)
						)
					)
					(number "3"
						(effects
							(font
								(size 1.27 1.27)
							)
						)
					)
				)
				(pin power_in line
					(at 20.32 -12.7 180)
					(length 2.54)
					(name "PGND"
						(effects
							(font
								(size 1.27 1.27)
							)
						)
					)
					(number "5"
						(effects
							(font
								(size 1.27 1.27)
							)
						)
					)
				)
			)
		)
	(symbol "antmicroDiodesRectifiersSingle:PDS760"
			(pin_numbers
				(hide yes)
			)
			(pin_names
				(hide yes)
			)
			(exclude_from_sim no)
			(in_bom yes)
			(on_board yes)
			(property "Reference" "D"
				(at 22.86 -5.08 0)
				(effects
					(font
						(size 1.27 1.27)
						(thickness 0.15)
					)
					(justify left bottom)
				)
			)
			(property "Value" "PDS760"
				(at 22.86 -17.78 0)
				(effects
					(font
						(size 1.27 1.27)
						(thickness 0.15)
					)
					(justify left bottom)
					(hide yes)
				)
			)
			(property "Footprint" "antmicro-footprints:PowerDI5"
				(at 22.86 -10.16 0)
				(effects
					(font
						(size 1.27 1.27)
						(thickness 0.15)
					)
					(justify left bottom)
					(hide yes)
				)
			)
			(property "Datasheet" "https://www.diodes.com/assets/Datasheets/ds30470.pdf"
				(at 22.86 -12.7 0)
				(effects
					(font
						(size 1.27 1.27)
						(thickness 0.15)
					)
					(justify left bottom)
					(hide yes)
				)
			)
			(property "Description" "Schottky Rectifier, POWERDI®, 60 V, 7 A, Single, PowerDI 5, 2 Pins, 620 mV"
				(at 22.86 -25.4 0)
				(effects
					(font
						(size 1.27 1.27)
					)
					(justify left bottom)
					(hide yes)
				)
			)
			(property "Manufacturer" "Diodes Incorporated"
				(at 22.86 -15.24 0)
				(effects
					(font
						(size 1.27 1.27)
						(thickness 0.15)
					)
					(justify left bottom)
					(hide yes)
				)
			)
			(property "MPN" "PDS760-13"
				(at 22.86 -7.62 0)
				(effects
					(font
						(size 1.27 1.27)
						(thickness 0.15)
					)
					(justify left bottom)
				)
			)
			(property "Author" "Antmicro"
				(at 22.86 -20.32 0)
				(effects
					(font
						(size 1.27 1.27)
						(thickness 0.15)
					)
					(justify left bottom)
					(hide yes)
				)
			)
			(property "License" "Apache-2.0"
				(at 22.86 -22.86 0)
				(effects
					(font
						(size 1.27 1.27)
						(thickness 0.15)
					)
					(justify left bottom)
					(hide yes)
				)
			)
			(property "ki_keywords" "SMT, RECTIFIER, SEMICONDUCTOR, DIODE, SCHOTTKY"
				(at 0 0 0)
				(effects
					(font
						(size 1.27 1.27)
					)
					(hide yes)
				)
			)
			(symbol "PDS760_0_1"
				(polyline
					(pts
						(xy 1.905 0) (xy 0.635 0)
					)
					(stroke
						(width 0)
						(type default)
					)
					(fill
						(type none)
					)
				)
				(polyline
					(pts
						(xy 4.445 0) (xy 3.175 0)
					)
					(stroke
						(width 0)
						(type default)
					)
					(fill
						(type none)
					)
				)
			)
			(symbol "PDS760_1_1"
				(polyline
					(pts
						(xy 1.778 1.016) (xy 1.778 -1.016)
					)
					(stroke
						(width 0.254)
						(type default)
					)
					(fill
						(type none)
					)
				)
				(polyline
					(pts
						(xy 1.778 1.016) (xy 1.397 1.016) (xy 1.397 0.762)
					)
					(stroke
						(width 0.254)
						(type default)
					)
					(fill
						(type none)
					)
				)
				(polyline
					(pts
						(xy 1.778 -1.016) (xy 2.159 -1.016) (xy 2.159 -0.762)
					)
					(stroke
						(width 0.254)
						(type default)
					)
					(fill
						(type none)
					)
				)
				(polyline
					(pts
						(xy 3.302 1.016) (xy 3.302 -1.016) (xy 1.778 0) (xy 3.302 1.016)
					)
					(stroke
						(width 0.254)
						(type default)
					)
					(fill
						(type outline)
					)
				)
				(pin passive line
					(at 0 0 0)
					(length 0.635)
					(name "C"
						(effects
							(font
								(size 1.27 1.27)
							)
						)
					)
					(number "1"
						(effects
							(font
								(size 1.27 1.27)
							)
						)
					)
				)
				(pin passive line
					(at 5.08 0 180)
					(length 0.635)
					(name "A"
						(effects
							(font
								(size 1.27 1.27)
							)
						)
					)
					(number "2"
						(effects
							(font
								(size 1.27 1.27)
							)
						)
					)
				)
			)
		)
	(symbol "antmicroFPGAChips:XC7A100T-FGG484"
			(pin_names
				(offset 1.016)
			)
			(exclude_from_sim no)
			(in_bom yes)
			(on_board yes)
			(property "Reference" "U"
				(at 76.2 -2.54 0)
				(effects
					(font
						(size 1.27 1.27)
						(thickness 0.15)
					)
					(justify left bottom)
				)
			)
			(property "Value" "XC7A100T-FGG484"
				(at 76.2 -7.62 0)
				(effects
					(font
						(size 1.27 1.27)
						(thickness 0.15)
					)
					(justify left bottom)
					(hide yes)
				)
			)
			(property "Footprint" "antmicro-footprints:BGA-484_23x23mm_Layout22x22_P1mm_FGG484"
				(at 76.2 -10.16 0)
				(effects
					(font
						(size 1.27 1.27)
						(thickness 0.15)
					)
					(justify left bottom)
					(hide yes)
				)
			)
			(property "Datasheet" "https://docs.xilinx.com/v/u/en-US/ds181_Artix_7_Data_Sheet"
				(at 76.2 -12.7 0)
				(effects
					(font
						(size 1.27 1.27)
						(thickness 0.15)
					)
					(justify left bottom)
					(hide yes)
				)
			)
			(property "Description" "Artix-7 Field Programmable Gate Array IC 210 324-LFBGA, CSPBGA"
				(at 76.2 -22.86 0)
				(effects
					(font
						(size 1.27 1.27)
					)
					(justify left bottom)
					(hide yes)
				)
			)
			(property "MPN" "XC7A100T-FGG484"
				(at 76.2 -5.08 0)
				(effects
					(font
						(size 1.27 1.27)
						(thickness 0.15)
					)
					(justify left bottom)
				)
			)
			(property "Manufacturer" "AMD-Xilinx"
				(at 76.2 -15.24 0)
				(effects
					(font
						(size 1.27 1.27)
						(thickness 0.15)
					)
					(justify left bottom)
					(hide yes)
				)
			)
			(property "Author" "Antmicro"
				(at 76.2 -17.78 0)
				(effects
					(font
						(size 1.27 1.27)
						(thickness 0.15)
					)
					(justify left bottom)
					(hide yes)
				)
			)
			(property "License" "Apache-2.0"
				(at 76.2 -20.32 0)
				(effects
					(font
						(size 1.27 1.27)
						(thickness 0.15)
					)
					(justify left bottom)
					(hide yes)
				)
			)
			(property "ki_locked" ""
				(at 0 0 0)
				(effects
					(font
						(size 1.27 1.27)
					)
				)
			)
			(property "ki_keywords" "SMT, IC, FPGA"
				(at 0 0 0)
				(effects
					(font
						(size 1.27 1.27)
					)
					(hide yes)
				)
			)
			(symbol "XC7A100T-FGG484_1_1"
				(rectangle
					(start 5.08 5.08)
					(end 58.42 -130.81)
					(stroke
						(width 0.254)
						(type default)
					)
					(fill
						(type background)
					)
				)
				(text "BANK 13"
					(at 11.43 2.54 0)
					(effects
						(font
							(size 1.27 1.27)
							(thickness 0.15)
						)
						(justify left bottom)
					)
				)
				(text "BANK 14"
					(at 43.18 2.54 0)
					(effects
						(font
							(size 1.27 1.27)
							(thickness 0.15)
						)
						(justify left bottom)
					)
				)
				(pin passive line
					(at 0 0 0)
					(length 5.08)
					(hide yes)
					(name "VCCO_13"
						(effects
							(font
								(size 1.27 1.27)
							)
						)
					)
					(number "AA17"
						(effects
							(font
								(size 1.27 1.27)
							)
						)
					)
				)
				(pin passive line
					(at 0 0 0)
					(length 5.08)
					(hide yes)
					(name "VCCO_13"
						(effects
							(font
								(size 1.27 1.27)
							)
						)
					)
					(number "AB14"
						(effects
							(font
								(size 1.27 1.27)
							)
						)
					)
				)
				(pin passive line
					(at 0 0 0)
					(length 5.08)
					(hide yes)
					(name "VCCO_13"
						(effects
							(font
								(size 1.27 1.27)
							)
						)
					)
					(number "V16"
						(effects
							(font
								(size 1.27 1.27)
							)
						)
					)
				)
				(pin passive line
					(at 0 0 0)
					(length 5.08)
					(hide yes)
					(name "VCCO_13"
						(effects
							(font
								(size 1.27 1.27)
							)
						)
					)
					(number "W13"
						(effects
							(font
								(size 1.27 1.27)
							)
						)
					)
				)
				(pin power_in line
					(at 0 0 0)
					(length 5.08)
					(name "VCCO_13"
						(effects
							(font
								(size 1.27 1.27)
							)
						)
					)
					(number "Y10"
						(effects
							(font
								(size 1.27 1.27)
							)
						)
					)
				)
				(pin bidirectional line
					(at 0 -3.81 0)
					(length 5.08)
					(name "IO_0_13"
						(effects
							(font
								(size 1.27 1.27)
							)
						)
					)
					(number "Y17"
						(effects
							(font
								(size 1.27 1.27)
							)
						)
					)
				)
				(pin bidirectional line
					(at 0 -6.35 0)
					(length 5.08)
					(name "IO_L1P_T0_13"
						(effects
							(font
								(size 1.27 1.27)
							)
						)
					)
					(number "Y16"
						(effects
							(font
								(size 1.27 1.27)
							)
						)
					)
				)
				(pin bidirectional line
					(at 0 -8.89 0)
					(length 5.08)
					(name "IO_L1N_T0_13"
						(effects
							(font
								(size 1.27 1.27)
							)
						)
					)
					(number "AA16"
						(effects
							(font
								(size 1.27 1.27)
							)
						)
					)
				)
				(pin bidirectional line
					(at 0 -11.43 0)
					(length 5.08)
					(name "IO_L2P_T0_13"
						(effects
							(font
								(size 1.27 1.27)
							)
						)
					)
					(number "AB16"
						(effects
							(font
								(size 1.27 1.27)
							)
						)
					)
				)
				(pin bidirectional line
					(at 0 -13.97 0)
					(length 5.08)
					(name "IO_L2N_T0_13"
						(effects
							(font
								(size 1.27 1.27)
							)
						)
					)
					(number "AB17"
						(effects
							(font
								(size 1.27 1.27)
							)
						)
					)
				)
				(pin bidirectional line
					(at 0 -16.51 0)
					(length 5.08)
					(name "IO_L3P_T0_DQS_13"
						(effects
							(font
								(size 1.27 1.27)
							)
						)
					)
					(number "AA13"
						(effects
							(font
								(size 1.27 1.27)
							)
						)
					)
				)
				(pin bidirectional line
					(at 0 -19.05 0)
					(length 5.08)
					(name "IO_L3N_T0_DQS_13"
						(effects
							(font
								(size 1.27 1.27)
							)
						)
					)
					(number "AB13"
						(effects
							(font
								(size 1.27 1.27)
							)
						)
					)
				)
				(pin bidirectional line
					(at 0 -21.59 0)
					(length 5.08)
					(name "IO_L4P_T0_13"
						(effects
							(font
								(size 1.27 1.27)
							)
						)
					)
					(number "AA15"
						(effects
							(font
								(size 1.27 1.27)
							)
						)
					)
				)
				(pin bidirectional line
					(at 0 -24.13 0)
					(length 5.08)
					(name "IO_L4N_T0_13"
						(effects
							(font
								(size 1.27 1.27)
							)
						)
					)
					(number "AB15"
						(effects
							(font
								(size 1.27 1.27)
							)
						)
					)
				)
				(pin bidirectional line
					(at 0 -26.67 0)
					(length 5.08)
					(name "IO_L5P_T0_13"
						(effects
							(font
								(size 1.27 1.27)
							)
						)
					)
					(number "Y13"
						(effects
							(font
								(size 1.27 1.27)
							)
						)
					)
				)
				(pin bidirectional line
					(at 0 -29.21 0)
					(length 5.08)
					(name "IO_L5N_T0_13"
						(effects
							(font
								(size 1.27 1.27)
							)
						)
					)
					(number "AA14"
						(effects
							(font
								(size 1.27 1.27)
							)
						)
					)
				)
				(pin bidirectional line
					(at 0 -31.75 0)
					(length 5.08)
					(name "IO_L6P_T0_13"
						(effects
							(font
								(size 1.27 1.27)
							)
						)
					)
					(number "W14"
						(effects
							(font
								(size 1.27 1.27)
							)
						)
					)
				)
				(pin bidirectional line
					(at 0 -34.29 0)
					(length 5.08)
					(name "IO_L6N_T0_VREF_13"
						(effects
							(font
								(size 1.27 1.27)
							)
						)
					)
					(number "Y14"
						(effects
							(font
								(size 1.27 1.27)
							)
						)
					)
				)
				(pin bidirectional line
					(at 0 -36.83 0)
					(length 5.08)
					(name "IO_L7P_T1_13"
						(effects
							(font
								(size 1.27 1.27)
							)
						)
					)
					(number "AB11"
						(effects
							(font
								(size 1.27 1.27)
							)
						)
					)
				)
				(pin bidirectional line
					(at 0 -39.37 0)
					(length 5.08)
					(name "IO_L7N_T1_13"
						(effects
							(font
								(size 1.27 1.27)
							)
						)
					)
					(number "AB12"
						(effects
							(font
								(size 1.27 1.27)
							)
						)
					)
				)
				(pin bidirectional line
					(at 0 -41.91 0)
					(length 5.08)
					(name "IO_L8P_T1_13"
						(effects
							(font
								(size 1.27 1.27)
							)
						)
					)
					(number "AA9"
						(effects
							(font
								(size 1.27 1.27)
							)
						)
					)
				)
				(pin bidirectional line
					(at 0 -44.45 0)
					(length 5.08)
					(name "IO_L8N_T1_13"
						(effects
							(font
								(size 1.27 1.27)
							)
						)
					)
					(number "AB10"
						(effects
							(font
								(size 1.27 1.27)
							)
						)
					)
				)
				(pin bidirectional line
					(at 0 -46.99 0)
					(length 5.08)
					(name "IO_L9P_T1_DQS_13"
						(effects
							(font
								(size 1.27 1.27)
							)
						)
					)
					(number "AA10"
						(effects
							(font
								(size 1.27 1.27)
							)
						)
					)
				)
				(pin bidirectional line
					(at 0 -49.53 0)
					(length 5.08)
					(name "IO_L9N_T1_DQS_13"
						(effects
							(font
								(size 1.27 1.27)
							)
						)
					)
					(number "AA11"
						(effects
							(font
								(size 1.27 1.27)
							)
						)
					)
				)
				(pin bidirectional line
					(at 0 -52.07 0)
					(length 5.08)
					(name "IO_L10P_T1_13"
						(effects
							(font
								(size 1.27 1.27)
							)
						)
					)
					(number "V10"
						(effects
							(font
								(size 1.27 1.27)
							)
						)
					)
				)
				(pin bidirectional line
					(at 0 -54.61 0)
					(length 5.08)
					(name "IO_L10N_T1_13"
						(effects
							(font
								(size 1.27 1.27)
							)
						)
					)
					(number "W10"
						(effects
							(font
								(size 1.27 1.27)
							)
						)
					)
				)
				(pin bidirectional line
					(at 0 -57.15 0)
					(length 5.08)
					(name "IO_L11P_T1_SRCC_13"
						(effects
							(font
								(size 1.27 1.27)
							)
						)
					)
					(number "Y11"
						(effects
							(font
								(size 1.27 1.27)
							)
						)
					)
				)
				(pin bidirectional line
					(at 0 -59.69 0)
					(length 5.08)
					(name "IO_L11N_T1_SRCC_13"
						(effects
							(font
								(size 1.27 1.27)
							)
						)
					)
					(number "Y12"
						(effects
							(font
								(size 1.27 1.27)
							)
						)
					)
				)
				(pin bidirectional line
					(at 0 -62.23 0)
					(length 5.08)
					(name "IO_L12P_T1_MRCC_13"
						(effects
							(font
								(size 1.27 1.27)
							)
						)
					)
					(number "W11"
						(effects
							(font
								(size 1.27 1.27)
							)
						)
					)
				)
				(pin bidirectional line
					(at 0 -64.77 0)
					(length 5.08)
					(name "IO_L12N_T1_MRCC_13"
						(effects
							(font
								(size 1.27 1.27)
							)
						)
					)
					(number "W12"
						(effects
							(font
								(size 1.27 1.27)
							)
						)
					)
				)
				(pin bidirectional line
					(at 0 -67.31 0)
					(length 5.08)
					(name "IO_L13P_T2_MRCC_13"
						(effects
							(font
								(size 1.27 1.27)
							)
						)
					)
					(number "V13"
						(effects
							(font
								(size 1.27 1.27)
							)
						)
					)
				)
				(pin bidirectional line
					(at 0 -69.85 0)
					(length 5.08)
					(name "IO_L13N_T2_MRCC_13"
						(effects
							(font
								(size 1.27 1.27)
							)
						)
					)
					(number "V14"
						(effects
							(font
								(size 1.27 1.27)
							)
						)
					)
				)
				(pin bidirectional line
					(at 0 -72.39 0)
					(length 5.08)
					(name "IO_L14P_T2_SRCC_13"
						(effects
							(font
								(size 1.27 1.27)
							)
						)
					)
					(number "U15"
						(effects
							(font
								(size 1.27 1.27)
							)
						)
					)
				)
				(pin bidirectional line
					(at 0 -74.93 0)
					(length 5.08)
					(name "IO_L14N_T2_SRCC_13"
						(effects
							(font
								(size 1.27 1.27)
							)
						)
					)
					(number "V15"
						(effects
							(font
								(size 1.27 1.27)
							)
						)
					)
				)
				(pin bidirectional line
					(at 0 -77.47 0)
					(length 5.08)
					(name "IO_L15P_T2_DQS_13"
						(effects
							(font
								(size 1.27 1.27)
							)
						)
					)
					(number "T14"
						(effects
							(font
								(size 1.27 1.27)
							)
						)
					)
				)
				(pin bidirectional line
					(at 0 -80.01 0)
					(length 5.08)
					(name "IO_L15N_T2_DQS_13"
						(effects
							(font
								(size 1.27 1.27)
							)
						)
					)
					(number "T15"
						(effects
							(font
								(size 1.27 1.27)
							)
						)
					)
				)
				(pin bidirectional line
					(at 0 -82.55 0)
					(length 5.08)
					(name "IO_L16P_T2_13"
						(effects
							(font
								(size 1.27 1.27)
							)
						)
					)
					(number "W15"
						(effects
							(font
								(size 1.27 1.27)
							)
						)
					)
				)
				(pin bidirectional line
					(at 0 -85.09 0)
					(length 5.08)
					(name "IO_L16N_T2_13"
						(effects
							(font
								(size 1.27 1.27)
							)
						)
					)
					(number "W16"
						(effects
							(font
								(size 1.27 1.27)
							)
						)
					)
				)
				(pin bidirectional line
					(at 0 -87.63 0)
					(length 5.08)
					(name "IO_L17P_T2_13"
						(effects
							(font
								(size 1.27 1.27)
							)
						)
					)
					(number "T16"
						(effects
							(font
								(size 1.27 1.27)
							)
						)
					)
				)
				(pin bidirectional line
					(at 0 -90.17 0)
					(length 5.08)
					(name "IO_L17N_T2_13"
						(effects
							(font
								(size 1.27 1.27)
							)
						)
					)
					(number "U16"
						(effects
							(font
								(size 1.27 1.27)
							)
						)
					)
				)
				(pin passive line
					(at 63.5 0 180)
					(length 5.08)
					(hide yes)
					(name "VCCO_14"
						(effects
							(font
								(size 1.27 1.27)
							)
						)
					)
					(number "M14"
						(effects
							(font
								(size 1.27 1.27)
							)
						)
					)
				)
				(pin passive line
					(at 63.5 0 180)
					(length 5.08)
					(hide yes)
					(name "VCCO_14"
						(effects
							(font
								(size 1.27 1.27)
							)
						)
					)
					(number "P18"
						(effects
							(font
								(size 1.27 1.27)
							)
						)
					)
				)
				(pin passive line
					(at 63.5 0 180)
					(length 5.08)
					(hide yes)
					(name "VCCO_14"
						(effects
							(font
								(size 1.27 1.27)
							)
						)
					)
					(number "R15"
						(effects
							(font
								(size 1.27 1.27)
							)
						)
					)
				)
				(pin passive line
					(at 63.5 0 180)
					(length 5.08)
					(hide yes)
					(name "VCCO_14"
						(effects
							(font
								(size 1.27 1.27)
							)
						)
					)
					(number "T22"
						(effects
							(font
								(size 1.27 1.27)
							)
						)
					)
				)
				(pin passive line
					(at 63.5 0 180)
					(length 5.08)
					(hide yes)
					(name "VCCO_14"
						(effects
							(font
								(size 1.27 1.27)
							)
						)
					)
					(number "U19"
						(effects
							(font
								(size 1.27 1.27)
							)
						)
					)
				)
				(pin power_in line
					(at 63.5 0 180)
					(length 5.08)
					(name "VCCO_14"
						(effects
							(font
								(size 1.27 1.27)
							)
						)
					)
					(number "Y20"
						(effects
							(font
								(size 1.27 1.27)
							)
						)
					)
				)
				(pin bidirectional line
					(at 63.5 -3.81 180)
					(length 5.08)
					(name "IO_0_14"
						(effects
							(font
								(size 1.27 1.27)
							)
						)
					)
					(number "P20"
						(effects
							(font
								(size 1.27 1.27)
							)
						)
					)
				)
				(pin bidirectional line
					(at 63.5 -6.35 180)
					(length 5.08)
					(name "IO_L1P_T0_D00_MOSI_14"
						(effects
							(font
								(size 1.27 1.27)
							)
						)
					)
					(number "P22"
						(effects
							(font
								(size 1.27 1.27)
							)
						)
					)
				)
				(pin bidirectional line
					(at 63.5 -8.89 180)
					(length 5.08)
					(name "IO_L1N_T0_D01_DIN_14"
						(effects
							(font
								(size 1.27 1.27)
							)
						)
					)
					(number "R22"
						(effects
							(font
								(size 1.27 1.27)
							)
						)
					)
				)
				(pin bidirectional line
					(at 63.5 -11.43 180)
					(length 5.08)
					(name "IO_L2P_T0_D02_14"
						(effects
							(font
								(size 1.27 1.27)
							)
						)
					)
					(number "P21"
						(effects
							(font
								(size 1.27 1.27)
							)
						)
					)
				)
				(pin bidirectional line
					(at 63.5 -13.97 180)
					(length 5.08)
					(name "IO_L2N_T0_D03_14"
						(effects
							(font
								(size 1.27 1.27)
							)
						)
					)
					(number "R21"
						(effects
							(font
								(size 1.27 1.27)
							)
						)
					)
				)
				(pin bidirectional line
					(at 63.5 -16.51 180)
					(length 5.08)
					(name "IO_L3P_T0_DQS_PUDC_B_14"
						(effects
							(font
								(size 1.27 1.27)
							)
						)
					)
					(number "U22"
						(effects
							(font
								(size 1.27 1.27)
							)
						)
					)
				)
				(pin bidirectional line
					(at 63.5 -19.05 180)
					(length 5.08)
					(name "IO_L3N_T0_DQS_EMCCLK_14"
						(effects
							(font
								(size 1.27 1.27)
							)
						)
					)
					(number "V22"
						(effects
							(font
								(size 1.27 1.27)
							)
						)
					)
				)
				(pin bidirectional line
					(at 63.5 -21.59 180)
					(length 5.08)
					(name "IO_L4P_T0_D04_14"
						(effects
							(font
								(size 1.27 1.27)
							)
						)
					)
					(number "T21"
						(effects
							(font
								(size 1.27 1.27)
							)
						)
					)
				)
				(pin bidirectional line
					(at 63.5 -24.13 180)
					(length 5.08)
					(name "IO_L4N_T0_D05_14"
						(effects
							(font
								(size 1.27 1.27)
							)
						)
					)
					(number "U21"
						(effects
							(font
								(size 1.27 1.27)
							)
						)
					)
				)
				(pin bidirectional line
					(at 63.5 -26.67 180)
					(length 5.08)
					(name "IO_L5P_T0_D06_14"
						(effects
							(font
								(size 1.27 1.27)
							)
						)
					)
					(number "P19"
						(effects
							(font
								(size 1.27 1.27)
							)
						)
					)
				)
				(pin bidirectional line
					(at 63.5 -29.21 180)
					(length 5.08)
					(name "IO_L5N_T0_D07_14"
						(effects
							(font
								(size 1.27 1.27)
							)
						)
					)
					(number "R19"
						(effects
							(font
								(size 1.27 1.27)
							)
						)
					)
				)
				(pin bidirectional line
					(at 63.5 -31.75 180)
					(length 5.08)
					(name "IO_L6P_T0_FCS_B_14"
						(effects
							(font
								(size 1.27 1.27)
							)
						)
					)
					(number "T19"
						(effects
							(font
								(size 1.27 1.27)
							)
						)
					)
				)
				(pin bidirectional line
					(at 63.5 -34.29 180)
					(length 5.08)
					(name "IO_L6N_T0_D08_VREF_14"
						(effects
							(font
								(size 1.27 1.27)
							)
						)
					)
					(number "T20"
						(effects
							(font
								(size 1.27 1.27)
							)
						)
					)
				)
				(pin bidirectional line
					(at 63.5 -36.83 180)
					(length 5.08)
					(name "IO_L7P_T1_D09_14"
						(effects
							(font
								(size 1.27 1.27)
							)
						)
					)
					(number "W21"
						(effects
							(font
								(size 1.27 1.27)
							)
						)
					)
				)
				(pin bidirectional line
					(at 63.5 -39.37 180)
					(length 5.08)
					(name "IO_L7N_T1_D10_14"
						(effects
							(font
								(size 1.27 1.27)
							)
						)
					)
					(number "W22"
						(effects
							(font
								(size 1.27 1.27)
							)
						)
					)
				)
				(pin bidirectional line
					(at 63.5 -41.91 180)
					(length 5.08)
					(name "IO_L8P_T1_D11_14"
						(effects
							(font
								(size 1.27 1.27)
							)
						)
					)
					(number "AA20"
						(effects
							(font
								(size 1.27 1.27)
							)
						)
					)
				)
				(pin bidirectional line
					(at 63.5 -44.45 180)
					(length 5.08)
					(name "IO_L8N_T1_D12_14"
						(effects
							(font
								(size 1.27 1.27)
							)
						)
					)
					(number "AA21"
						(effects
							(font
								(size 1.27 1.27)
							)
						)
					)
				)
				(pin bidirectional line
					(at 63.5 -46.99 180)
					(length 5.08)
					(name "IO_L9P_T1_DQS_14"
						(effects
							(font
								(size 1.27 1.27)
							)
						)
					)
					(number "Y21"
						(effects
							(font
								(size 1.27 1.27)
							)
						)
					)
				)
				(pin bidirectional line
					(at 63.5 -49.53 180)
					(length 5.08)
					(name "IO_L9N_T1_DQS_D13_14"
						(effects
							(font
								(size 1.27 1.27)
							)
						)
					)
					(number "Y22"
						(effects
							(font
								(size 1.27 1.27)
							)
						)
					)
				)
				(pin bidirectional line
					(at 63.5 -52.07 180)
					(length 5.08)
					(name "IO_L10P_T1_D14_14"
						(effects
							(font
								(size 1.27 1.27)
							)
						)
					)
					(number "AB21"
						(effects
							(font
								(size 1.27 1.27)
							)
						)
					)
				)
				(pin bidirectional line
					(at 63.5 -54.61 180)
					(length 5.08)
					(name "IO_L10N_T1_D15_14"
						(effects
							(font
								(size 1.27 1.27)
							)
						)
					)
					(number "AB22"
						(effects
							(font
								(size 1.27 1.27)
							)
						)
					)
				)
				(pin bidirectional line
					(at 63.5 -57.15 180)
					(length 5.08)
					(name "IO_L11P_T1_SRCC_14"
						(effects
							(font
								(size 1.27 1.27)
							)
						)
					)
					(number "U20"
						(effects
							(font
								(size 1.27 1.27)
							)
						)
					)
				)
				(pin bidirectional line
					(at 63.5 -59.69 180)
					(length 5.08)
					(name "IO_L11N_T1_SRCC_14"
						(effects
							(font
								(size 1.27 1.27)
							)
						)
					)
					(number "V20"
						(effects
							(font
								(size 1.27 1.27)
							)
						)
					)
				)
				(pin bidirectional line
					(at 63.5 -62.23 180)
					(length 5.08)
					(name "IO_L12P_T1_MRCC_14"
						(effects
							(font
								(size 1.27 1.27)
							)
						)
					)
					(number "W19"
						(effects
							(font
								(size 1.27 1.27)
							)
						)
					)
				)
				(pin bidirectional line
					(at 63.5 -64.77 180)
					(length 5.08)
					(name "IO_L12N_T1_MRCC_14"
						(effects
							(font
								(size 1.27 1.27)
							)
						)
					)
					(number "W20"
						(effects
							(font
								(size 1.27 1.27)
							)
						)
					)
				)
				(pin bidirectional line
					(at 63.5 -67.31 180)
					(length 5.08)
					(name "IO_L13P_T2_MRCC_14"
						(effects
							(font
								(size 1.27 1.27)
							)
						)
					)
					(number "Y18"
						(effects
							(font
								(size 1.27 1.27)
							)
						)
					)
				)
				(pin bidirectional line
					(at 63.5 -69.85 180)
					(length 5.08)
					(name "IO_L13N_T2_MRCC_14"
						(effects
							(font
								(size 1.27 1.27)
							)
						)
					)
					(number "Y19"
						(effects
							(font
								(size 1.27 1.27)
							)
						)
					)
				)
				(pin bidirectional line
					(at 63.5 -72.39 180)
					(length 5.08)
					(name "IO_L14P_T2_SRCC_14"
						(effects
							(font
								(size 1.27 1.27)
							)
						)
					)
					(number "V18"
						(effects
							(font
								(size 1.27 1.27)
							)
						)
					)
				)
				(pin bidirectional line
					(at 63.5 -74.93 180)
					(length 5.08)
					(name "IO_L14N_T2_SRCC_14"
						(effects
							(font
								(size 1.27 1.27)
							)
						)
					)
					(number "V19"
						(effects
							(font
								(size 1.27 1.27)
							)
						)
					)
				)
				(pin bidirectional line
					(at 63.5 -77.47 180)
					(length 5.08)
					(name "IO_L15P_T2_DQS_RDWR_B_14"
						(effects
							(font
								(size 1.27 1.27)
							)
						)
					)
					(number "AA19"
						(effects
							(font
								(size 1.27 1.27)
							)
						)
					)
				)
				(pin bidirectional line
					(at 63.5 -80.01 180)
					(length 5.08)
					(name "IO_L15N_T2_DQS_DOUT_CSO_B_14"
						(effects
							(font
								(size 1.27 1.27)
							)
						)
					)
					(number "AB20"
						(effects
							(font
								(size 1.27 1.27)
							)
						)
					)
				)
				(pin bidirectional line
					(at 63.5 -82.55 180)
					(length 5.08)
					(name "IO_L16P_T2_CSI_B_14"
						(effects
							(font
								(size 1.27 1.27)
							)
						)
					)
					(number "V17"
						(effects
							(font
								(size 1.27 1.27)
							)
						)
					)
				)
				(pin bidirectional line
					(at 63.5 -85.09 180)
					(length 5.08)
					(name "IO_L16N_T2_A15_D31_14"
						(effects
							(font
								(size 1.27 1.27)
							)
						)
					)
					(number "W17"
						(effects
							(font
								(size 1.27 1.27)
							)
						)
					)
				)
				(pin bidirectional line
					(at 63.5 -87.63 180)
					(length 5.08)
					(name "IO_L17P_T2_A14_D30_14"
						(effects
							(font
								(size 1.27 1.27)
							)
						)
					)
					(number "AA18"
						(effects
							(font
								(size 1.27 1.27)
							)
						)
					)
				)
				(pin bidirectional line
					(at 63.5 -90.17 180)
					(length 5.08)
					(name "IO_L17N_T2_A13_D29_14"
						(effects
							(font
								(size 1.27 1.27)
							)
						)
					)
					(number "AB18"
						(effects
							(font
								(size 1.27 1.27)
							)
						)
					)
				)
				(pin bidirectional line
					(at 63.5 -92.71 180)
					(length 5.08)
					(name "IO_L18P_T2_A12_D28_14"
						(effects
							(font
								(size 1.27 1.27)
							)
						)
					)
					(number "U17"
						(effects
							(font
								(size 1.27 1.27)
							)
						)
					)
				)
				(pin bidirectional line
					(at 63.5 -95.25 180)
					(length 5.08)
					(name "IO_L18N_T2_A11_D27_14"
						(effects
							(font
								(size 1.27 1.27)
							)
						)
					)
					(number "U18"
						(effects
							(font
								(size 1.27 1.27)
							)
						)
					)
				)
				(pin bidirectional line
					(at 63.5 -97.79 180)
					(length 5.08)
					(name "IO_L19P_T3_A10_D26_14"
						(effects
							(font
								(size 1.27 1.27)
							)
						)
					)
					(number "P14"
						(effects
							(font
								(size 1.27 1.27)
							)
						)
					)
				)
				(pin bidirectional line
					(at 63.5 -100.33 180)
					(length 5.08)
					(name "IO_L19N_T3_A09_D25_VREF_14"
						(effects
							(font
								(size 1.27 1.27)
							)
						)
					)
					(number "R14"
						(effects
							(font
								(size 1.27 1.27)
							)
						)
					)
				)
				(pin bidirectional line
					(at 63.5 -102.87 180)
					(length 5.08)
					(name "IO_L20P_T3_A08_D24_14"
						(effects
							(font
								(size 1.27 1.27)
							)
						)
					)
					(number "R18"
						(effects
							(font
								(size 1.27 1.27)
							)
						)
					)
				)
				(pin bidirectional line
					(at 63.5 -105.41 180)
					(length 5.08)
					(name "IO_L20N_T3_A07_D23_14"
						(effects
							(font
								(size 1.27 1.27)
							)
						)
					)
					(number "T18"
						(effects
							(font
								(size 1.27 1.27)
							)
						)
					)
				)
				(pin bidirectional line
					(at 63.5 -107.95 180)
					(length 5.08)
					(name "IO_L21P_T3_DQS_14"
						(effects
							(font
								(size 1.27 1.27)
							)
						)
					)
					(number "N17"
						(effects
							(font
								(size 1.27 1.27)
							)
						)
					)
				)
				(pin bidirectional line
					(at 63.5 -110.49 180)
					(length 5.08)
					(name "IO_L21N_T3_DQS_A06_D22_14"
						(effects
							(font
								(size 1.27 1.27)
							)
						)
					)
					(number "P17"
						(effects
							(font
								(size 1.27 1.27)
							)
						)
					)
				)
				(pin bidirectional line
					(at 63.5 -113.03 180)
					(length 5.08)
					(name "IO_L22P_T3_A05_D21_14"
						(effects
							(font
								(size 1.27 1.27)
							)
						)
					)
					(number "P15"
						(effects
							(font
								(size 1.27 1.27)
							)
						)
					)
				)
				(pin bidirectional line
					(at 63.5 -115.57 180)
					(length 5.08)
					(name "IO_L22N_T3_A04_D20_14"
						(effects
							(font
								(size 1.27 1.27)
							)
						)
					)
					(number "R16"
						(effects
							(font
								(size 1.27 1.27)
							)
						)
					)
				)
				(pin bidirectional line
					(at 63.5 -118.11 180)
					(length 5.08)
					(name "IO_L23P_T3_A03_D19_14"
						(effects
							(font
								(size 1.27 1.27)
							)
						)
					)
					(number "N13"
						(effects
							(font
								(size 1.27 1.27)
							)
						)
					)
				)
				(pin bidirectional line
					(at 63.5 -120.65 180)
					(length 5.08)
					(name "IO_L23N_T3_A02_D18_14"
						(effects
							(font
								(size 1.27 1.27)
							)
						)
					)
					(number "N14"
						(effects
							(font
								(size 1.27 1.27)
							)
						)
					)
				)
				(pin bidirectional line
					(at 63.5 -123.19 180)
					(length 5.08)
					(name "IO_L24P_T3_A01_D17_14"
						(effects
							(font
								(size 1.27 1.27)
							)
						)
					)
					(number "P16"
						(effects
							(font
								(size 1.27 1.27)
							)
						)
					)
				)
				(pin bidirectional line
					(at 63.5 -125.73 180)
					(length 5.08)
					(name "IO_L24N_T3_A00_D16_14"
						(effects
							(font
								(size 1.27 1.27)
							)
						)
					)
					(number "R17"
						(effects
							(font
								(size 1.27 1.27)
							)
						)
					)
				)
				(pin bidirectional line
					(at 63.5 -128.27 180)
					(length 5.08)
					(name "IO_25_14"
						(effects
							(font
								(size 1.27 1.27)
							)
						)
					)
					(number "N15"
						(effects
							(font
								(size 1.27 1.27)
							)
						)
					)
				)
			)
			(symbol "XC7A100T-FGG484_2_1"
				(rectangle
					(start 5.08 5.08)
					(end 58.42 -130.81)
					(stroke
						(width 0.254)
						(type default)
					)
					(fill
						(type background)
					)
				)
				(text "BANK 15"
					(at 11.43 2.54 0)
					(effects
						(font
							(size 1.27 1.27)
							(thickness 0.15)
						)
						(justify left bottom)
					)
				)
				(text "BANK 16"
					(at 43.18 2.54 0)
					(effects
						(font
							(size 1.27 1.27)
							(thickness 0.15)
						)
						(justify left bottom)
					)
				)
				(pin power_in line
					(at 0 0 0)
					(length 5.08)
					(name "VCCO_15"
						(effects
							(font
								(size 1.27 1.27)
							)
						)
					)
					(number "G19"
						(effects
							(font
								(size 1.27 1.27)
							)
						)
					)
				)
				(pin passive line
					(at 0 0 0)
					(length 5.08)
					(hide yes)
					(name "VCCO_15"
						(effects
							(font
								(size 1.27 1.27)
							)
						)
					)
					(number "H16"
						(effects
							(font
								(size 1.27 1.27)
							)
						)
					)
				)
				(pin passive line
					(at 0 0 0)
					(length 5.08)
					(hide yes)
					(name "VCCO_15"
						(effects
							(font
								(size 1.27 1.27)
							)
						)
					)
					(number "J13"
						(effects
							(font
								(size 1.27 1.27)
							)
						)
					)
				)
				(pin passive line
					(at 0 0 0)
					(length 5.08)
					(hide yes)
					(name "VCCO_15"
						(effects
							(font
								(size 1.27 1.27)
							)
						)
					)
					(number "K20"
						(effects
							(font
								(size 1.27 1.27)
							)
						)
					)
				)
				(pin passive line
					(at 0 0 0)
					(length 5.08)
					(hide yes)
					(name "VCCO_15"
						(effects
							(font
								(size 1.27 1.27)
							)
						)
					)
					(number "L17"
						(effects
							(font
								(size 1.27 1.27)
							)
						)
					)
				)
				(pin passive line
					(at 0 0 0)
					(length 5.08)
					(hide yes)
					(name "VCCO_15"
						(effects
							(font
								(size 1.27 1.27)
							)
						)
					)
					(number "N21"
						(effects
							(font
								(size 1.27 1.27)
							)
						)
					)
				)
				(pin bidirectional line
					(at 0 -3.81 0)
					(length 5.08)
					(name "IO_0_15"
						(effects
							(font
								(size 1.27 1.27)
							)
						)
					)
					(number "J16"
						(effects
							(font
								(size 1.27 1.27)
							)
						)
					)
				)
				(pin bidirectional line
					(at 0 -6.35 0)
					(length 5.08)
					(name "IO_L1P_T0_AD0P_15"
						(effects
							(font
								(size 1.27 1.27)
							)
						)
					)
					(number "H13"
						(effects
							(font
								(size 1.27 1.27)
							)
						)
					)
				)
				(pin bidirectional line
					(at 0 -8.89 0)
					(length 5.08)
					(name "IO_L1N_T0_AD0N_15"
						(effects
							(font
								(size 1.27 1.27)
							)
						)
					)
					(number "G13"
						(effects
							(font
								(size 1.27 1.27)
							)
						)
					)
				)
				(pin bidirectional line
					(at 0 -11.43 0)
					(length 5.08)
					(name "IO_L2P_T0_AD8P_15"
						(effects
							(font
								(size 1.27 1.27)
							)
						)
					)
					(number "G15"
						(effects
							(font
								(size 1.27 1.27)
							)
						)
					)
				)
				(pin bidirectional line
					(at 0 -13.97 0)
					(length 5.08)
					(name "IO_L2N_T0_AD8N_15"
						(effects
							(font
								(size 1.27 1.27)
							)
						)
					)
					(number "G16"
						(effects
							(font
								(size 1.27 1.27)
							)
						)
					)
				)
				(pin bidirectional line
					(at 0 -16.51 0)
					(length 5.08)
					(name "IO_L3P_T0_DQS_AD1P_15"
						(effects
							(font
								(size 1.27 1.27)
							)
						)
					)
					(number "J14"
						(effects
							(font
								(size 1.27 1.27)
							)
						)
					)
				)
				(pin bidirectional line
					(at 0 -19.05 0)
					(length 5.08)
					(name "IO_L3N_T0_DQS_AD1N_15"
						(effects
							(font
								(size 1.27 1.27)
							)
						)
					)
					(number "H14"
						(effects
							(font
								(size 1.27 1.27)
							)
						)
					)
				)
				(pin bidirectional line
					(at 0 -21.59 0)
					(length 5.08)
					(name "IO_L4P_T0_15"
						(effects
							(font
								(size 1.27 1.27)
							)
						)
					)
					(number "G17"
						(effects
							(font
								(size 1.27 1.27)
							)
						)
					)
				)
				(pin bidirectional line
					(at 0 -24.13 0)
					(length 5.08)
					(name "IO_L4N_T0_15"
						(effects
							(font
								(size 1.27 1.27)
							)
						)
					)
					(number "G18"
						(effects
							(font
								(size 1.27 1.27)
							)
						)
					)
				)
				(pin bidirectional line
					(at 0 -26.67 0)
					(length 5.08)
					(name "IO_L5P_T0_AD9P_15"
						(effects
							(font
								(size 1.27 1.27)
							)
						)
					)
					(number "J15"
						(effects
							(font
								(size 1.27 1.27)
							)
						)
					)
				)
				(pin bidirectional line
					(at 0 -29.21 0)
					(length 5.08)
					(name "IO_L5N_T0_AD9N_15"
						(effects
							(font
								(size 1.27 1.27)
							)
						)
					)
					(number "H15"
						(effects
							(font
								(size 1.27 1.27)
							)
						)
					)
				)
				(pin bidirectional line
					(at 0 -31.75 0)
					(length 5.08)
					(name "IO_L6P_T0_15"
						(effects
							(font
								(size 1.27 1.27)
							)
						)
					)
					(number "H17"
						(effects
							(font
								(size 1.27 1.27)
							)
						)
					)
				)
				(pin bidirectional line
					(at 0 -34.29 0)
					(length 5.08)
					(name "IO_L6N_T0_VREF_15"
						(effects
							(font
								(size 1.27 1.27)
							)
						)
					)
					(number "H18"
						(effects
							(font
								(size 1.27 1.27)
							)
						)
					)
				)
				(pin bidirectional line
					(at 0 -36.83 0)
					(length 5.08)
					(name "IO_L7P_T1_AD2P_15"
						(effects
							(font
								(size 1.27 1.27)
							)
						)
					)
					(number "J22"
						(effects
							(font
								(size 1.27 1.27)
							)
						)
					)
				)
				(pin bidirectional line
					(at 0 -39.37 0)
					(length 5.08)
					(name "IO_L7N_T1_AD2N_15"
						(effects
							(font
								(size 1.27 1.27)
							)
						)
					)
					(number "H22"
						(effects
							(font
								(size 1.27 1.27)
							)
						)
					)
				)
				(pin bidirectional line
					(at 0 -41.91 0)
					(length 5.08)
					(name "IO_L8P_T1_AD10P_15"
						(effects
							(font
								(size 1.27 1.27)
							)
						)
					)
					(number "H20"
						(effects
							(font
								(size 1.27 1.27)
							)
						)
					)
				)
				(pin bidirectional line
					(at 0 -44.45 0)
					(length 5.08)
					(name "IO_L8N_T1_AD10N_15"
						(effects
							(font
								(size 1.27 1.27)
							)
						)
					)
					(number "G20"
						(effects
							(font
								(size 1.27 1.27)
							)
						)
					)
				)
				(pin bidirectional line
					(at 0 -46.99 0)
					(length 5.08)
					(name "IO_L9P_T1_DQS_AD3P_15"
						(effects
							(font
								(size 1.27 1.27)
							)
						)
					)
					(number "K21"
						(effects
							(font
								(size 1.27 1.27)
							)
						)
					)
				)
				(pin bidirectional line
					(at 0 -49.53 0)
					(length 5.08)
					(name "IO_L9N_T1_DQS_AD3N_15"
						(effects
							(font
								(size 1.27 1.27)
							)
						)
					)
					(number "K22"
						(effects
							(font
								(size 1.27 1.27)
							)
						)
					)
				)
				(pin bidirectional line
					(at 0 -52.07 0)
					(length 5.08)
					(name "IO_L10P_T1_AD11P_15"
						(effects
							(font
								(size 1.27 1.27)
							)
						)
					)
					(number "M21"
						(effects
							(font
								(size 1.27 1.27)
							)
						)
					)
				)
				(pin bidirectional line
					(at 0 -54.61 0)
					(length 5.08)
					(name "IO_L10N_T1_AD11N_15"
						(effects
							(font
								(size 1.27 1.27)
							)
						)
					)
					(number "L21"
						(effects
							(font
								(size 1.27 1.27)
							)
						)
					)
				)
				(pin bidirectional line
					(at 0 -57.15 0)
					(length 5.08)
					(name "IO_L11P_T1_SRCC_15"
						(effects
							(font
								(size 1.27 1.27)
							)
						)
					)
					(number "J20"
						(effects
							(font
								(size 1.27 1.27)
							)
						)
					)
				)
				(pin bidirectional line
					(at 0 -59.69 0)
					(length 5.08)
					(name "IO_L11N_T1_SRCC_15"
						(effects
							(font
								(size 1.27 1.27)
							)
						)
					)
					(number "J21"
						(effects
							(font
								(size 1.27 1.27)
							)
						)
					)
				)
				(pin bidirectional line
					(at 0 -62.23 0)
					(length 5.08)
					(name "IO_L12P_T1_MRCC_15"
						(effects
							(font
								(size 1.27 1.27)
							)
						)
					)
					(number "J19"
						(effects
							(font
								(size 1.27 1.27)
							)
						)
					)
				)
				(pin bidirectional line
					(at 0 -64.77 0)
					(length 5.08)
					(name "IO_L12N_T1_MRCC_15"
						(effects
							(font
								(size 1.27 1.27)
							)
						)
					)
					(number "H19"
						(effects
							(font
								(size 1.27 1.27)
							)
						)
					)
				)
				(pin bidirectional line
					(at 0 -67.31 0)
					(length 5.08)
					(name "IO_L13P_T2_MRCC_15"
						(effects
							(font
								(size 1.27 1.27)
							)
						)
					)
					(number "K18"
						(effects
							(font
								(size 1.27 1.27)
							)
						)
					)
				)
				(pin bidirectional line
					(at 0 -69.85 0)
					(length 5.08)
					(name "IO_L13N_T2_MRCC_15"
						(effects
							(font
								(size 1.27 1.27)
							)
						)
					)
					(number "K19"
						(effects
							(font
								(size 1.27 1.27)
							)
						)
					)
				)
				(pin bidirectional line
					(at 0 -72.39 0)
					(length 5.08)
					(name "IO_L14P_T2_SRCC_15"
						(effects
							(font
								(size 1.27 1.27)
							)
						)
					)
					(number "L19"
						(effects
							(font
								(size 1.27 1.27)
							)
						)
					)
				)
				(pin bidirectional line
					(at 0 -74.93 0)
					(length 5.08)
					(name "IO_L14N_T2_SRCC_15"
						(effects
							(font
								(size 1.27 1.27)
							)
						)
					)
					(number "L20"
						(effects
							(font
								(size 1.27 1.27)
							)
						)
					)
				)
				(pin bidirectional line
					(at 0 -77.47 0)
					(length 5.08)
					(name "IO_L15P_T2_DQS_15"
						(effects
							(font
								(size 1.27 1.27)
							)
						)
					)
					(number "N22"
						(effects
							(font
								(size 1.27 1.27)
							)
						)
					)
				)
				(pin bidirectional line
					(at 0 -80.01 0)
					(length 5.08)
					(name "IO_L15N_T2_DQS_ADV_B_15"
						(effects
							(font
								(size 1.27 1.27)
							)
						)
					)
					(number "M22"
						(effects
							(font
								(size 1.27 1.27)
							)
						)
					)
				)
				(pin bidirectional line
					(at 0 -82.55 0)
					(length 5.08)
					(name "IO_L16P_T2_A28_15"
						(effects
							(font
								(size 1.27 1.27)
							)
						)
					)
					(number "M18"
						(effects
							(font
								(size 1.27 1.27)
							)
						)
					)
				)
				(pin bidirectional line
					(at 0 -85.09 0)
					(length 5.08)
					(name "IO_L16N_T2_A27_15"
						(effects
							(font
								(size 1.27 1.27)
							)
						)
					)
					(number "L18"
						(effects
							(font
								(size 1.27 1.27)
							)
						)
					)
				)
				(pin bidirectional line
					(at 0 -87.63 0)
					(length 5.08)
					(name "IO_L17P_T2_A26_15"
						(effects
							(font
								(size 1.27 1.27)
							)
						)
					)
					(number "N18"
						(effects
							(font
								(size 1.27 1.27)
							)
						)
					)
				)
				(pin bidirectional line
					(at 0 -90.17 0)
					(length 5.08)
					(name "IO_L17N_T2_A25_15"
						(effects
							(font
								(size 1.27 1.27)
							)
						)
					)
					(number "N19"
						(effects
							(font
								(size 1.27 1.27)
							)
						)
					)
				)
				(pin bidirectional line
					(at 0 -92.71 0)
					(length 5.08)
					(name "IO_L18P_T2_A24_15"
						(effects
							(font
								(size 1.27 1.27)
							)
						)
					)
					(number "N20"
						(effects
							(font
								(size 1.27 1.27)
							)
						)
					)
				)
				(pin bidirectional line
					(at 0 -95.25 0)
					(length 5.08)
					(name "IO_L18N_T2_A23_15"
						(effects
							(font
								(size 1.27 1.27)
							)
						)
					)
					(number "M20"
						(effects
							(font
								(size 1.27 1.27)
							)
						)
					)
				)
				(pin bidirectional line
					(at 0 -97.79 0)
					(length 5.08)
					(name "IO_L19P_T3_A22_15"
						(effects
							(font
								(size 1.27 1.27)
							)
						)
					)
					(number "K13"
						(effects
							(font
								(size 1.27 1.27)
							)
						)
					)
				)
				(pin bidirectional line
					(at 0 -100.33 0)
					(length 5.08)
					(name "IO_L19N_T3_A21_VREF_15"
						(effects
							(font
								(size 1.27 1.27)
							)
						)
					)
					(number "K14"
						(effects
							(font
								(size 1.27 1.27)
							)
						)
					)
				)
				(pin bidirectional line
					(at 0 -102.87 0)
					(length 5.08)
					(name "IO_L20P_T3_A20_15"
						(effects
							(font
								(size 1.27 1.27)
							)
						)
					)
					(number "M13"
						(effects
							(font
								(size 1.27 1.27)
							)
						)
					)
				)
				(pin bidirectional line
					(at 0 -105.41 0)
					(length 5.08)
					(name "IO_L20N_T3_A19_15"
						(effects
							(font
								(size 1.27 1.27)
							)
						)
					)
					(number "L13"
						(effects
							(font
								(size 1.27 1.27)
							)
						)
					)
				)
				(pin bidirectional line
					(at 0 -107.95 0)
					(length 5.08)
					(name "IO_L21P_T3_DQS_15"
						(effects
							(font
								(size 1.27 1.27)
							)
						)
					)
					(number "K17"
						(effects
							(font
								(size 1.27 1.27)
							)
						)
					)
				)
				(pin bidirectional line
					(at 0 -110.49 0)
					(length 5.08)
					(name "IO_L21N_T3_DQS_A18_15"
						(effects
							(font
								(size 1.27 1.27)
							)
						)
					)
					(number "J17"
						(effects
							(font
								(size 1.27 1.27)
							)
						)
					)
				)
				(pin bidirectional line
					(at 0 -113.03 0)
					(length 5.08)
					(name "IO_L22P_T3_A17_15"
						(effects
							(font
								(size 1.27 1.27)
							)
						)
					)
					(number "L14"
						(effects
							(font
								(size 1.27 1.27)
							)
						)
					)
				)
				(pin bidirectional line
					(at 0 -115.57 0)
					(length 5.08)
					(name "IO_L22N_T3_A16_15"
						(effects
							(font
								(size 1.27 1.27)
							)
						)
					)
					(number "L15"
						(effects
							(font
								(size 1.27 1.27)
							)
						)
					)
				)
				(pin bidirectional line
					(at 0 -118.11 0)
					(length 5.08)
					(name "IO_L23P_T3_FOE_B_15"
						(effects
							(font
								(size 1.27 1.27)
							)
						)
					)
					(number "L16"
						(effects
							(font
								(size 1.27 1.27)
							)
						)
					)
				)
				(pin bidirectional line
					(at 0 -120.65 0)
					(length 5.08)
					(name "IO_L23N_T3_FWE_B_15"
						(effects
							(font
								(size 1.27 1.27)
							)
						)
					)
					(number "K16"
						(effects
							(font
								(size 1.27 1.27)
							)
						)
					)
				)
				(pin bidirectional line
					(at 0 -123.19 0)
					(length 5.08)
					(name "IO_L24P_T3_RS1_15"
						(effects
							(font
								(size 1.27 1.27)
							)
						)
					)
					(number "M15"
						(effects
							(font
								(size 1.27 1.27)
							)
						)
					)
				)
				(pin bidirectional line
					(at 0 -125.73 0)
					(length 5.08)
					(name "IO_L24N_T3_RS0_15"
						(effects
							(font
								(size 1.27 1.27)
							)
						)
					)
					(number "M16"
						(effects
							(font
								(size 1.27 1.27)
							)
						)
					)
				)
				(pin bidirectional line
					(at 0 -128.27 0)
					(length 5.08)
					(name "IO_25_15"
						(effects
							(font
								(size 1.27 1.27)
							)
						)
					)
					(number "M17"
						(effects
							(font
								(size 1.27 1.27)
							)
						)
					)
				)
				(pin power_in line
					(at 63.5 0 180)
					(length 5.08)
					(name "VCCO_16"
						(effects
							(font
								(size 1.27 1.27)
							)
						)
					)
					(number "A17"
						(effects
							(font
								(size 1.27 1.27)
							)
						)
					)
				)
				(pin passive line
					(at 63.5 0 180)
					(length 5.08)
					(hide yes)
					(name "VCCO_16"
						(effects
							(font
								(size 1.27 1.27)
							)
						)
					)
					(number "B14"
						(effects
							(font
								(size 1.27 1.27)
							)
						)
					)
				)
				(pin passive line
					(at 63.5 0 180)
					(length 5.08)
					(hide yes)
					(name "VCCO_16"
						(effects
							(font
								(size 1.27 1.27)
							)
						)
					)
					(number "C21"
						(effects
							(font
								(size 1.27 1.27)
							)
						)
					)
				)
				(pin passive line
					(at 63.5 0 180)
					(length 5.08)
					(hide yes)
					(name "VCCO_16"
						(effects
							(font
								(size 1.27 1.27)
							)
						)
					)
					(number "D18"
						(effects
							(font
								(size 1.27 1.27)
							)
						)
					)
				)
				(pin passive line
					(at 63.5 0 180)
					(length 5.08)
					(hide yes)
					(name "VCCO_16"
						(effects
							(font
								(size 1.27 1.27)
							)
						)
					)
					(number "E15"
						(effects
							(font
								(size 1.27 1.27)
							)
						)
					)
				)
				(pin passive line
					(at 63.5 0 180)
					(length 5.08)
					(hide yes)
					(name "VCCO_16"
						(effects
							(font
								(size 1.27 1.27)
							)
						)
					)
					(number "F22"
						(effects
							(font
								(size 1.27 1.27)
							)
						)
					)
				)
				(pin bidirectional line
					(at 63.5 -3.81 180)
					(length 5.08)
					(name "IO_0_16"
						(effects
							(font
								(size 1.27 1.27)
							)
						)
					)
					(number "F15"
						(effects
							(font
								(size 1.27 1.27)
							)
						)
					)
				)
				(pin bidirectional line
					(at 63.5 -6.35 180)
					(length 5.08)
					(name "IO_L1P_T0_16"
						(effects
							(font
								(size 1.27 1.27)
							)
						)
					)
					(number "F13"
						(effects
							(font
								(size 1.27 1.27)
							)
						)
					)
				)
				(pin bidirectional line
					(at 63.5 -8.89 180)
					(length 5.08)
					(name "IO_L1N_T0_16"
						(effects
							(font
								(size 1.27 1.27)
							)
						)
					)
					(number "F14"
						(effects
							(font
								(size 1.27 1.27)
							)
						)
					)
				)
				(pin bidirectional line
					(at 63.5 -11.43 180)
					(length 5.08)
					(name "IO_L2P_T0_16"
						(effects
							(font
								(size 1.27 1.27)
							)
						)
					)
					(number "F16"
						(effects
							(font
								(size 1.27 1.27)
							)
						)
					)
				)
				(pin bidirectional line
					(at 63.5 -13.97 180)
					(length 5.08)
					(name "IO_L2N_T0_16"
						(effects
							(font
								(size 1.27 1.27)
							)
						)
					)
					(number "E17"
						(effects
							(font
								(size 1.27 1.27)
							)
						)
					)
				)
				(pin bidirectional line
					(at 63.5 -16.51 180)
					(length 5.08)
					(name "IO_L3P_T0_DQS_16"
						(effects
							(font
								(size 1.27 1.27)
							)
						)
					)
					(number "C14"
						(effects
							(font
								(size 1.27 1.27)
							)
						)
					)
				)
				(pin bidirectional line
					(at 63.5 -19.05 180)
					(length 5.08)
					(name "IO_L3N_T0_DQS_16"
						(effects
							(font
								(size 1.27 1.27)
							)
						)
					)
					(number "C15"
						(effects
							(font
								(size 1.27 1.27)
							)
						)
					)
				)
				(pin bidirectional line
					(at 63.5 -21.59 180)
					(length 5.08)
					(name "IO_L4P_T0_16"
						(effects
							(font
								(size 1.27 1.27)
							)
						)
					)
					(number "E13"
						(effects
							(font
								(size 1.27 1.27)
							)
						)
					)
				)
				(pin bidirectional line
					(at 63.5 -24.13 180)
					(length 5.08)
					(name "IO_L4N_T0_16"
						(effects
							(font
								(size 1.27 1.27)
							)
						)
					)
					(number "E14"
						(effects
							(font
								(size 1.27 1.27)
							)
						)
					)
				)
				(pin bidirectional line
					(at 63.5 -26.67 180)
					(length 5.08)
					(name "IO_L5P_T0_16"
						(effects
							(font
								(size 1.27 1.27)
							)
						)
					)
					(number "E16"
						(effects
							(font
								(size 1.27 1.27)
							)
						)
					)
				)
				(pin bidirectional line
					(at 63.5 -29.21 180)
					(length 5.08)
					(name "IO_L5N_T0_16"
						(effects
							(font
								(size 1.27 1.27)
							)
						)
					)
					(number "D16"
						(effects
							(font
								(size 1.27 1.27)
							)
						)
					)
				)
				(pin bidirectional line
					(at 63.5 -31.75 180)
					(length 5.08)
					(name "IO_L6P_T0_16"
						(effects
							(font
								(size 1.27 1.27)
							)
						)
					)
					(number "D14"
						(effects
							(font
								(size 1.27 1.27)
							)
						)
					)
				)
				(pin bidirectional line
					(at 63.5 -34.29 180)
					(length 5.08)
					(name "IO_L6N_T0_VREF_16"
						(effects
							(font
								(size 1.27 1.27)
							)
						)
					)
					(number "D15"
						(effects
							(font
								(size 1.27 1.27)
							)
						)
					)
				)
				(pin bidirectional line
					(at 63.5 -36.83 180)
					(length 5.08)
					(name "IO_L7P_T1_16"
						(effects
							(font
								(size 1.27 1.27)
							)
						)
					)
					(number "B15"
						(effects
							(font
								(size 1.27 1.27)
							)
						)
					)
				)
				(pin bidirectional line
					(at 63.5 -39.37 180)
					(length 5.08)
					(name "IO_L7N_T1_16"
						(effects
							(font
								(size 1.27 1.27)
							)
						)
					)
					(number "B16"
						(effects
							(font
								(size 1.27 1.27)
							)
						)
					)
				)
				(pin bidirectional line
					(at 63.5 -41.91 180)
					(length 5.08)
					(name "IO_L8P_T1_16"
						(effects
							(font
								(size 1.27 1.27)
							)
						)
					)
					(number "C13"
						(effects
							(font
								(size 1.27 1.27)
							)
						)
					)
				)
				(pin bidirectional line
					(at 63.5 -44.45 180)
					(length 5.08)
					(name "IO_L8N_T1_16"
						(effects
							(font
								(size 1.27 1.27)
							)
						)
					)
					(number "B13"
						(effects
							(font
								(size 1.27 1.27)
							)
						)
					)
				)
				(pin bidirectional line
					(at 63.5 -46.99 180)
					(length 5.08)
					(name "IO_L9P_T1_DQS_16"
						(effects
							(font
								(size 1.27 1.27)
							)
						)
					)
					(number "A15"
						(effects
							(font
								(size 1.27 1.27)
							)
						)
					)
				)
				(pin bidirectional line
					(at 63.5 -49.53 180)
					(length 5.08)
					(name "IO_L9N_T1_DQS_16"
						(effects
							(font
								(size 1.27 1.27)
							)
						)
					)
					(number "A16"
						(effects
							(font
								(size 1.27 1.27)
							)
						)
					)
				)
				(pin bidirectional line
					(at 63.5 -52.07 180)
					(length 5.08)
					(name "IO_L10P_T1_16"
						(effects
							(font
								(size 1.27 1.27)
							)
						)
					)
					(number "A13"
						(effects
							(font
								(size 1.27 1.27)
							)
						)
					)
				)
				(pin bidirectional line
					(at 63.5 -54.61 180)
					(length 5.08)
					(name "IO_L10N_T1_16"
						(effects
							(font
								(size 1.27 1.27)
							)
						)
					)
					(number "A14"
						(effects
							(font
								(size 1.27 1.27)
							)
						)
					)
				)
				(pin bidirectional line
					(at 63.5 -57.15 180)
					(length 5.08)
					(name "IO_L11P_T1_SRCC_16"
						(effects
							(font
								(size 1.27 1.27)
							)
						)
					)
					(number "B17"
						(effects
							(font
								(size 1.27 1.27)
							)
						)
					)
				)
				(pin bidirectional line
					(at 63.5 -59.69 180)
					(length 5.08)
					(name "IO_L11N_T1_SRCC_16"
						(effects
							(font
								(size 1.27 1.27)
							)
						)
					)
					(number "B18"
						(effects
							(font
								(size 1.27 1.27)
							)
						)
					)
				)
				(pin bidirectional line
					(at 63.5 -62.23 180)
					(length 5.08)
					(name "IO_L12P_T1_MRCC_16"
						(effects
							(font
								(size 1.27 1.27)
							)
						)
					)
					(number "D17"
						(effects
							(font
								(size 1.27 1.27)
							)
						)
					)
				)
				(pin bidirectional line
					(at 63.5 -64.77 180)
					(length 5.08)
					(name "IO_L12N_T1_MRCC_16"
						(effects
							(font
								(size 1.27 1.27)
							)
						)
					)
					(number "C17"
						(effects
							(font
								(size 1.27 1.27)
							)
						)
					)
				)
				(pin bidirectional line
					(at 63.5 -67.31 180)
					(length 5.08)
					(name "IO_L13P_T2_MRCC_16"
						(effects
							(font
								(size 1.27 1.27)
							)
						)
					)
					(number "C18"
						(effects
							(font
								(size 1.27 1.27)
							)
						)
					)
				)
				(pin bidirectional line
					(at 63.5 -69.85 180)
					(length 5.08)
					(name "IO_L13N_T2_MRCC_16"
						(effects
							(font
								(size 1.27 1.27)
							)
						)
					)
					(number "C19"
						(effects
							(font
								(size 1.27 1.27)
							)
						)
					)
				)
				(pin bidirectional line
					(at 63.5 -72.39 180)
					(length 5.08)
					(name "IO_L14P_T2_SRCC_16"
						(effects
							(font
								(size 1.27 1.27)
							)
						)
					)
					(number "E19"
						(effects
							(font
								(size 1.27 1.27)
							)
						)
					)
				)
				(pin bidirectional line
					(at 63.5 -74.93 180)
					(length 5.08)
					(name "IO_L14N_T2_SRCC_16"
						(effects
							(font
								(size 1.27 1.27)
							)
						)
					)
					(number "D19"
						(effects
							(font
								(size 1.27 1.27)
							)
						)
					)
				)
				(pin bidirectional line
					(at 63.5 -77.47 180)
					(length 5.08)
					(name "IO_L15P_T2_DQS_16"
						(effects
							(font
								(size 1.27 1.27)
							)
						)
					)
					(number "F18"
						(effects
							(font
								(size 1.27 1.27)
							)
						)
					)
				)
				(pin bidirectional line
					(at 63.5 -80.01 180)
					(length 5.08)
					(name "IO_L15N_T2_DQS_16"
						(effects
							(font
								(size 1.27 1.27)
							)
						)
					)
					(number "E18"
						(effects
							(font
								(size 1.27 1.27)
							)
						)
					)
				)
				(pin bidirectional line
					(at 63.5 -82.55 180)
					(length 5.08)
					(name "IO_L16P_T2_16"
						(effects
							(font
								(size 1.27 1.27)
							)
						)
					)
					(number "B20"
						(effects
							(font
								(size 1.27 1.27)
							)
						)
					)
				)
				(pin bidirectional line
					(at 63.5 -85.09 180)
					(length 5.08)
					(name "IO_L16N_T2_16"
						(effects
							(font
								(size 1.27 1.27)
							)
						)
					)
					(number "A20"
						(effects
							(font
								(size 1.27 1.27)
							)
						)
					)
				)
				(pin bidirectional line
					(at 63.5 -87.63 180)
					(length 5.08)
					(name "IO_L17P_T2_16"
						(effects
							(font
								(size 1.27 1.27)
							)
						)
					)
					(number "A18"
						(effects
							(font
								(size 1.27 1.27)
							)
						)
					)
				)
				(pin bidirectional line
					(at 63.5 -90.17 180)
					(length 5.08)
					(name "IO_L17N_T2_16"
						(effects
							(font
								(size 1.27 1.27)
							)
						)
					)
					(number "A19"
						(effects
							(font
								(size 1.27 1.27)
							)
						)
					)
				)
				(pin bidirectional line
					(at 63.5 -92.71 180)
					(length 5.08)
					(name "IO_L18P_T2_16"
						(effects
							(font
								(size 1.27 1.27)
							)
						)
					)
					(number "F19"
						(effects
							(font
								(size 1.27 1.27)
							)
						)
					)
				)
				(pin bidirectional line
					(at 63.5 -95.25 180)
					(length 5.08)
					(name "IO_L18N_T2_16"
						(effects
							(font
								(size 1.27 1.27)
							)
						)
					)
					(number "F20"
						(effects
							(font
								(size 1.27 1.27)
							)
						)
					)
				)
				(pin bidirectional line
					(at 63.5 -97.79 180)
					(length 5.08)
					(name "IO_L19P_T3_16"
						(effects
							(font
								(size 1.27 1.27)
							)
						)
					)
					(number "D20"
						(effects
							(font
								(size 1.27 1.27)
							)
						)
					)
				)
				(pin bidirectional line
					(at 63.5 -100.33 180)
					(length 5.08)
					(name "IO_L19N_T3_VREF_16"
						(effects
							(font
								(size 1.27 1.27)
							)
						)
					)
					(number "C20"
						(effects
							(font
								(size 1.27 1.27)
							)
						)
					)
				)
				(pin bidirectional line
					(at 63.5 -102.87 180)
					(length 5.08)
					(name "IO_L20P_T3_16"
						(effects
							(font
								(size 1.27 1.27)
							)
						)
					)
					(number "C22"
						(effects
							(font
								(size 1.27 1.27)
							)
						)
					)
				)
				(pin bidirectional line
					(at 63.5 -105.41 180)
					(length 5.08)
					(name "IO_L20N_T3_16"
						(effects
							(font
								(size 1.27 1.27)
							)
						)
					)
					(number "B22"
						(effects
							(font
								(size 1.27 1.27)
							)
						)
					)
				)
				(pin bidirectional line
					(at 63.5 -107.95 180)
					(length 5.08)
					(name "IO_L21P_T3_DQS_16"
						(effects
							(font
								(size 1.27 1.27)
							)
						)
					)
					(number "B21"
						(effects
							(font
								(size 1.27 1.27)
							)
						)
					)
				)
				(pin bidirectional line
					(at 63.5 -110.49 180)
					(length 5.08)
					(name "IO_L21N_T3_DQS_16"
						(effects
							(font
								(size 1.27 1.27)
							)
						)
					)
					(number "A21"
						(effects
							(font
								(size 1.27 1.27)
							)
						)
					)
				)
				(pin bidirectional line
					(at 63.5 -113.03 180)
					(length 5.08)
					(name "IO_L22P_T3_16"
						(effects
							(font
								(size 1.27 1.27)
							)
						)
					)
					(number "E22"
						(effects
							(font
								(size 1.27 1.27)
							)
						)
					)
				)
				(pin bidirectional line
					(at 63.5 -115.57 180)
					(length 5.08)
					(name "IO_L22N_T3_16"
						(effects
							(font
								(size 1.27 1.27)
							)
						)
					)
					(number "D22"
						(effects
							(font
								(size 1.27 1.27)
							)
						)
					)
				)
				(pin bidirectional line
					(at 63.5 -118.11 180)
					(length 5.08)
					(name "IO_L23P_T3_16"
						(effects
							(font
								(size 1.27 1.27)
							)
						)
					)
					(number "E21"
						(effects
							(font
								(size 1.27 1.27)
							)
						)
					)
				)
				(pin bidirectional line
					(at 63.5 -120.65 180)
					(length 5.08)
					(name "IO_L23N_T3_16"
						(effects
							(font
								(size 1.27 1.27)
							)
						)
					)
					(number "D21"
						(effects
							(font
								(size 1.27 1.27)
							)
						)
					)
				)
				(pin bidirectional line
					(at 63.5 -123.19 180)
					(length 5.08)
					(name "IO_L24P_T3_16"
						(effects
							(font
								(size 1.27 1.27)
							)
						)
					)
					(number "G21"
						(effects
							(font
								(size 1.27 1.27)
							)
						)
					)
				)
				(pin bidirectional line
					(at 63.5 -125.73 180)
					(length 5.08)
					(name "IO_L24N_T3_16"
						(effects
							(font
								(size 1.27 1.27)
							)
						)
					)
					(number "G22"
						(effects
							(font
								(size 1.27 1.27)
							)
						)
					)
				)
				(pin bidirectional line
					(at 63.5 -128.27 180)
					(length 5.08)
					(name "IO_25_16"
						(effects
							(font
								(size 1.27 1.27)
							)
						)
					)
					(number "F21"
						(effects
							(font
								(size 1.27 1.27)
							)
						)
					)
				)
			)
			(symbol "XC7A100T-FGG484_3_1"
				(rectangle
					(start 5.08 5.08)
					(end 58.42 -130.81)
					(stroke
						(width 0.254)
						(type default)
					)
					(fill
						(type background)
					)
				)
				(text "BANK 34"
					(at 11.43 2.54 0)
					(effects
						(font
							(size 1.27 1.27)
							(thickness 0.15)
						)
						(justify left bottom)
					)
				)
				(text "BANK 35"
					(at 43.18 2.54 0)
					(effects
						(font
							(size 1.27 1.27)
							(thickness 0.15)
						)
						(justify left bottom)
					)
				)
				(pin passive line
					(at 0 0 0)
					(length 5.08)
					(hide yes)
					(name "VCCO_34"
						(effects
							(font
								(size 1.27 1.27)
							)
						)
					)
					(number "AA7"
						(effects
							(font
								(size 1.27 1.27)
							)
						)
					)
				)
				(pin passive line
					(at 0 0 0)
					(length 5.08)
					(hide yes)
					(name "VCCO_34"
						(effects
							(font
								(size 1.27 1.27)
							)
						)
					)
					(number "AB4"
						(effects
							(font
								(size 1.27 1.27)
							)
						)
					)
				)
				(pin passive line
					(at 0 0 0)
					(length 5.08)
					(hide yes)
					(name "VCCO_34"
						(effects
							(font
								(size 1.27 1.27)
							)
						)
					)
					(number "R5"
						(effects
							(font
								(size 1.27 1.27)
							)
						)
					)
				)
				(pin passive line
					(at 0 0 0)
					(length 5.08)
					(hide yes)
					(name "VCCO_34"
						(effects
							(font
								(size 1.27 1.27)
							)
						)
					)
					(number "T2"
						(effects
							(font
								(size 1.27 1.27)
							)
						)
					)
				)
				(pin passive line
					(at 0 0 0)
					(length 5.08)
					(hide yes)
					(name "VCCO_34"
						(effects
							(font
								(size 1.27 1.27)
							)
						)
					)
					(number "V6"
						(effects
							(font
								(size 1.27 1.27)
							)
						)
					)
				)
				(pin power_in line
					(at 0 0 0)
					(length 5.08)
					(name "VCCO_34"
						(effects
							(font
								(size 1.27 1.27)
							)
						)
					)
					(number "W3"
						(effects
							(font
								(size 1.27 1.27)
							)
						)
					)
				)
				(pin bidirectional line
					(at 0 -3.81 0)
					(length 5.08)
					(name "IO_0_34"
						(effects
							(font
								(size 1.27 1.27)
							)
						)
					)
					(number "T3"
						(effects
							(font
								(size 1.27 1.27)
							)
						)
					)
				)
				(pin bidirectional line
					(at 0 -6.35 0)
					(length 5.08)
					(name "IO_L1P_T0_34"
						(effects
							(font
								(size 1.27 1.27)
							)
						)
					)
					(number "T1"
						(effects
							(font
								(size 1.27 1.27)
							)
						)
					)
				)
				(pin bidirectional line
					(at 0 -8.89 0)
					(length 5.08)
					(name "IO_L1N_T0_34"
						(effects
							(font
								(size 1.27 1.27)
							)
						)
					)
					(number "U1"
						(effects
							(font
								(size 1.27 1.27)
							)
						)
					)
				)
				(pin bidirectional line
					(at 0 -11.43 0)
					(length 5.08)
					(name "IO_L2P_T0_34"
						(effects
							(font
								(size 1.27 1.27)
							)
						)
					)
					(number "U2"
						(effects
							(font
								(size 1.27 1.27)
							)
						)
					)
				)
				(pin bidirectional line
					(at 0 -13.97 0)
					(length 5.08)
					(name "IO_L2N_T0_34"
						(effects
							(font
								(size 1.27 1.27)
							)
						)
					)
					(number "V2"
						(effects
							(font
								(size 1.27 1.27)
							)
						)
					)
				)
				(pin bidirectional line
					(at 0 -16.51 0)
					(length 5.08)
					(name "IO_L3P_T0_DQS_34"
						(effects
							(font
								(size 1.27 1.27)
							)
						)
					)
					(number "R3"
						(effects
							(font
								(size 1.27 1.27)
							)
						)
					)
				)
				(pin bidirectional line
					(at 0 -19.05 0)
					(length 5.08)
					(name "IO_L3N_T0_DQS_34"
						(effects
							(font
								(size 1.27 1.27)
							)
						)
					)
					(number "R2"
						(effects
							(font
								(size 1.27 1.27)
							)
						)
					)
				)
				(pin bidirectional line
					(at 0 -21.59 0)
					(length 5.08)
					(name "IO_L4P_T0_34"
						(effects
							(font
								(size 1.27 1.27)
							)
						)
					)
					(number "W2"
						(effects
							(font
								(size 1.27 1.27)
							)
						)
					)
				)
				(pin bidirectional line
					(at 0 -24.13 0)
					(length 5.08)
					(name "IO_L4N_T0_34"
						(effects
							(font
								(size 1.27 1.27)
							)
						)
					)
					(number "Y2"
						(effects
							(font
								(size 1.27 1.27)
							)
						)
					)
				)
				(pin bidirectional line
					(at 0 -26.67 0)
					(length 5.08)
					(name "IO_L5P_T0_34"
						(effects
							(font
								(size 1.27 1.27)
							)
						)
					)
					(number "W1"
						(effects
							(font
								(size 1.27 1.27)
							)
						)
					)
				)
				(pin bidirectional line
					(at 0 -29.21 0)
					(length 5.08)
					(name "IO_L5N_T0_34"
						(effects
							(font
								(size 1.27 1.27)
							)
						)
					)
					(number "Y1"
						(effects
							(font
								(size 1.27 1.27)
							)
						)
					)
				)
				(pin bidirectional line
					(at 0 -31.75 0)
					(length 5.08)
					(name "IO_L6P_T0_34"
						(effects
							(font
								(size 1.27 1.27)
							)
						)
					)
					(number "U3"
						(effects
							(font
								(size 1.27 1.27)
							)
						)
					)
				)
				(pin bidirectional line
					(at 0 -34.29 0)
					(length 5.08)
					(name "IO_L6N_T0_VREF_34"
						(effects
							(font
								(size 1.27 1.27)
							)
						)
					)
					(number "V3"
						(effects
							(font
								(size 1.27 1.27)
							)
						)
					)
				)
				(pin bidirectional line
					(at 0 -36.83 0)
					(length 5.08)
					(name "IO_L7P_T1_34"
						(effects
							(font
								(size 1.27 1.27)
							)
						)
					)
					(number "AA1"
						(effects
							(font
								(size 1.27 1.27)
							)
						)
					)
				)
				(pin bidirectional line
					(at 0 -39.37 0)
					(length 5.08)
					(name "IO_L7N_T1_34"
						(effects
							(font
								(size 1.27 1.27)
							)
						)
					)
					(number "AB1"
						(effects
							(font
								(size 1.27 1.27)
							)
						)
					)
				)
				(pin bidirectional line
					(at 0 -41.91 0)
					(length 5.08)
					(name "IO_L8P_T1_34"
						(effects
							(font
								(size 1.27 1.27)
							)
						)
					)
					(number "AB3"
						(effects
							(font
								(size 1.27 1.27)
							)
						)
					)
				)
				(pin bidirectional line
					(at 0 -44.45 0)
					(length 5.08)
					(name "IO_L8N_T1_34"
						(effects
							(font
								(size 1.27 1.27)
							)
						)
					)
					(number "AB2"
						(effects
							(font
								(size 1.27 1.27)
							)
						)
					)
				)
				(pin bidirectional line
					(at 0 -46.99 0)
					(length 5.08)
					(name "IO_L9P_T1_DQS_34"
						(effects
							(font
								(size 1.27 1.27)
							)
						)
					)
					(number "Y3"
						(effects
							(font
								(size 1.27 1.27)
							)
						)
					)
				)
				(pin bidirectional line
					(at 0 -49.53 0)
					(length 5.08)
					(name "IO_L9N_T1_DQS_34"
						(effects
							(font
								(size 1.27 1.27)
							)
						)
					)
					(number "AA3"
						(effects
							(font
								(size 1.27 1.27)
							)
						)
					)
				)
				(pin bidirectional line
					(at 0 -52.07 0)
					(length 5.08)
					(name "IO_L10P_T1_34"
						(effects
							(font
								(size 1.27 1.27)
							)
						)
					)
					(number "AA5"
						(effects
							(font
								(size 1.27 1.27)
							)
						)
					)
				)
				(pin bidirectional line
					(at 0 -54.61 0)
					(length 5.08)
					(name "IO_L10N_T1_34"
						(effects
							(font
								(size 1.27 1.27)
							)
						)
					)
					(number "AB5"
						(effects
							(font
								(size 1.27 1.27)
							)
						)
					)
				)
				(pin bidirectional line
					(at 0 -57.15 0)
					(length 5.08)
					(name "IO_L11P_T1_SRCC_34"
						(effects
							(font
								(size 1.27 1.27)
							)
						)
					)
					(number "Y4"
						(effects
							(font
								(size 1.27 1.27)
							)
						)
					)
				)
				(pin bidirectional line
					(at 0 -59.69 0)
					(length 5.08)
					(name "IO_L11N_T1_SRCC_34"
						(effects
							(font
								(size 1.27 1.27)
							)
						)
					)
					(number "AA4"
						(effects
							(font
								(size 1.27 1.27)
							)
						)
					)
				)
				(pin bidirectional line
					(at 0 -62.23 0)
					(length 5.08)
					(name "IO_L12P_T1_MRCC_34"
						(effects
							(font
								(size 1.27 1.27)
							)
						)
					)
					(number "V4"
						(effects
							(font
								(size 1.27 1.27)
							)
						)
					)
				)
				(pin bidirectional line
					(at 0 -64.77 0)
					(length 5.08)
					(name "IO_L12N_T1_MRCC_34"
						(effects
							(font
								(size 1.27 1.27)
							)
						)
					)
					(number "W4"
						(effects
							(font
								(size 1.27 1.27)
							)
						)
					)
				)
				(pin bidirectional line
					(at 0 -67.31 0)
					(length 5.08)
					(name "IO_L13P_T2_MRCC_34"
						(effects
							(font
								(size 1.27 1.27)
							)
						)
					)
					(number "R4"
						(effects
							(font
								(size 1.27 1.27)
							)
						)
					)
				)
				(pin bidirectional line
					(at 0 -69.85 0)
					(length 5.08)
					(name "IO_L13N_T2_MRCC_34"
						(effects
							(font
								(size 1.27 1.27)
							)
						)
					)
					(number "T4"
						(effects
							(font
								(size 1.27 1.27)
							)
						)
					)
				)
				(pin bidirectional line
					(at 0 -72.39 0)
					(length 5.08)
					(name "IO_L14P_T2_SRCC_34"
						(effects
							(font
								(size 1.27 1.27)
							)
						)
					)
					(number "T5"
						(effects
							(font
								(size 1.27 1.27)
							)
						)
					)
				)
				(pin bidirectional line
					(at 0 -74.93 0)
					(length 5.08)
					(name "IO_L14N_T2_SRCC_34"
						(effects
							(font
								(size 1.27 1.27)
							)
						)
					)
					(number "U5"
						(effects
							(font
								(size 1.27 1.27)
							)
						)
					)
				)
				(pin bidirectional line
					(at 0 -77.47 0)
					(length 5.08)
					(name "IO_L15P_T2_DQS_34"
						(effects
							(font
								(size 1.27 1.27)
							)
						)
					)
					(number "W6"
						(effects
							(font
								(size 1.27 1.27)
							)
						)
					)
				)
				(pin bidirectional line
					(at 0 -80.01 0)
					(length 5.08)
					(name "IO_L15N_T2_DQS_34"
						(effects
							(font
								(size 1.27 1.27)
							)
						)
					)
					(number "W5"
						(effects
							(font
								(size 1.27 1.27)
							)
						)
					)
				)
				(pin bidirectional line
					(at 0 -82.55 0)
					(length 5.08)
					(name "IO_L16P_T2_34"
						(effects
							(font
								(size 1.27 1.27)
							)
						)
					)
					(number "U6"
						(effects
							(font
								(size 1.27 1.27)
							)
						)
					)
				)
				(pin bidirectional line
					(at 0 -85.09 0)
					(length 5.08)
					(name "IO_L16N_T2_34"
						(effects
							(font
								(size 1.27 1.27)
							)
						)
					)
					(number "V5"
						(effects
							(font
								(size 1.27 1.27)
							)
						)
					)
				)
				(pin bidirectional line
					(at 0 -87.63 0)
					(length 5.08)
					(name "IO_L17P_T2_34"
						(effects
							(font
								(size 1.27 1.27)
							)
						)
					)
					(number "R6"
						(effects
							(font
								(size 1.27 1.27)
							)
						)
					)
				)
				(pin bidirectional line
					(at 0 -90.17 0)
					(length 5.08)
					(name "IO_L17N_T2_34"
						(effects
							(font
								(size 1.27 1.27)
							)
						)
					)
					(number "T6"
						(effects
							(font
								(size 1.27 1.27)
							)
						)
					)
				)
				(pin bidirectional line
					(at 0 -92.71 0)
					(length 5.08)
					(name "IO_L18P_T2_34"
						(effects
							(font
								(size 1.27 1.27)
							)
						)
					)
					(number "Y6"
						(effects
							(font
								(size 1.27 1.27)
							)
						)
					)
				)
				(pin bidirectional line
					(at 0 -95.25 0)
					(length 5.08)
					(name "IO_L18N_T2_34"
						(effects
							(font
								(size 1.27 1.27)
							)
						)
					)
					(number "AA6"
						(effects
							(font
								(size 1.27 1.27)
							)
						)
					)
				)
				(pin bidirectional line
					(at 0 -97.79 0)
					(length 5.08)
					(name "IO_L19P_T3_34"
						(effects
							(font
								(size 1.27 1.27)
							)
						)
					)
					(number "V7"
						(effects
							(font
								(size 1.27 1.27)
							)
						)
					)
				)
				(pin bidirectional line
					(at 0 -100.33 0)
					(length 5.08)
					(name "IO_L19N_T3_VREF_34"
						(effects
							(font
								(size 1.27 1.27)
							)
						)
					)
					(number "W7"
						(effects
							(font
								(size 1.27 1.27)
							)
						)
					)
				)
				(pin bidirectional line
					(at 0 -102.87 0)
					(length 5.08)
					(name "IO_L20P_T3_34"
						(effects
							(font
								(size 1.27 1.27)
							)
						)
					)
					(number "AB7"
						(effects
							(font
								(size 1.27 1.27)
							)
						)
					)
				)
				(pin bidirectional line
					(at 0 -105.41 0)
					(length 5.08)
					(name "IO_L20N_T3_34"
						(effects
							(font
								(size 1.27 1.27)
							)
						)
					)
					(number "AB6"
						(effects
							(font
								(size 1.27 1.27)
							)
						)
					)
				)
				(pin bidirectional line
					(at 0 -107.95 0)
					(length 5.08)
					(name "IO_L21P_T3_DQS_34"
						(effects
							(font
								(size 1.27 1.27)
							)
						)
					)
					(number "V9"
						(effects
							(font
								(size 1.27 1.27)
							)
						)
					)
				)
				(pin bidirectional line
					(at 0 -110.49 0)
					(length 5.08)
					(name "IO_L21N_T3_DQS_34"
						(effects
							(font
								(size 1.27 1.27)
							)
						)
					)
					(number "V8"
						(effects
							(font
								(size 1.27 1.27)
							)
						)
					)
				)
				(pin bidirectional line
					(at 0 -113.03 0)
					(length 5.08)
					(name "IO_L22P_T3_34"
						(effects
							(font
								(size 1.27 1.27)
							)
						)
					)
					(number "AA8"
						(effects
							(font
								(size 1.27 1.27)
							)
						)
					)
				)
				(pin bidirectional line
					(at 0 -115.57 0)
					(length 5.08)
					(name "IO_L22N_T3_34"
						(effects
							(font
								(size 1.27 1.27)
							)
						)
					)
					(number "AB8"
						(effects
							(font
								(size 1.27 1.27)
							)
						)
					)
				)
				(pin bidirectional line
					(at 0 -118.11 0)
					(length 5.08)
					(name "IO_L23P_T3_34"
						(effects
							(font
								(size 1.27 1.27)
							)
						)
					)
					(number "Y8"
						(effects
							(font
								(size 1.27 1.27)
							)
						)
					)
				)
				(pin bidirectional line
					(at 0 -120.65 0)
					(length 5.08)
					(name "IO_L23N_T3_34"
						(effects
							(font
								(size 1.27 1.27)
							)
						)
					)
					(number "Y7"
						(effects
							(font
								(size 1.27 1.27)
							)
						)
					)
				)
				(pin bidirectional line
					(at 0 -123.19 0)
					(length 5.08)
					(name "IO_L24P_T3_34"
						(effects
							(font
								(size 1.27 1.27)
							)
						)
					)
					(number "W9"
						(effects
							(font
								(size 1.27 1.27)
							)
						)
					)
				)
				(pin bidirectional line
					(at 0 -125.73 0)
					(length 5.08)
					(name "IO_L24N_T3_34"
						(effects
							(font
								(size 1.27 1.27)
							)
						)
					)
					(number "Y9"
						(effects
							(font
								(size 1.27 1.27)
							)
						)
					)
				)
				(pin bidirectional line
					(at 0 -128.27 0)
					(length 5.08)
					(name "IO_25_34"
						(effects
							(font
								(size 1.27 1.27)
							)
						)
					)
					(number "U7"
						(effects
							(font
								(size 1.27 1.27)
							)
						)
					)
				)
				(pin power_in line
					(at 63.5 0 180)
					(length 5.08)
					(name "VCCO_35"
						(effects
							(font
								(size 1.27 1.27)
							)
						)
					)
					(number "C1"
						(effects
							(font
								(size 1.27 1.27)
							)
						)
					)
				)
				(pin passive line
					(at 63.5 0 180)
					(length 5.08)
					(hide yes)
					(name "VCCO_35"
						(effects
							(font
								(size 1.27 1.27)
							)
						)
					)
					(number "F2"
						(effects
							(font
								(size 1.27 1.27)
							)
						)
					)
				)
				(pin passive line
					(at 63.5 0 180)
					(length 5.08)
					(hide yes)
					(name "VCCO_35"
						(effects
							(font
								(size 1.27 1.27)
							)
						)
					)
					(number "H6"
						(effects
							(font
								(size 1.27 1.27)
							)
						)
					)
				)
				(pin passive line
					(at 63.5 0 180)
					(length 5.08)
					(hide yes)
					(name "VCCO_35"
						(effects
							(font
								(size 1.27 1.27)
							)
						)
					)
					(number "J3"
						(effects
							(font
								(size 1.27 1.27)
							)
						)
					)
				)
				(pin passive line
					(at 63.5 0 180)
					(length 5.08)
					(hide yes)
					(name "VCCO_35"
						(effects
							(font
								(size 1.27 1.27)
							)
						)
					)
					(number "M4"
						(effects
							(font
								(size 1.27 1.27)
							)
						)
					)
				)
				(pin passive line
					(at 63.5 0 180)
					(length 5.08)
					(hide yes)
					(name "VCCO_35"
						(effects
							(font
								(size 1.27 1.27)
							)
						)
					)
					(number "N1"
						(effects
							(font
								(size 1.27 1.27)
							)
						)
					)
				)
				(pin bidirectional line
					(at 63.5 -3.81 180)
					(length 5.08)
					(name "IO_0_35"
						(effects
							(font
								(size 1.27 1.27)
							)
						)
					)
					(number "F4"
						(effects
							(font
								(size 1.27 1.27)
							)
						)
					)
				)
				(pin bidirectional line
					(at 63.5 -6.35 180)
					(length 5.08)
					(name "IO_L1P_T0_AD4P_35"
						(effects
							(font
								(size 1.27 1.27)
							)
						)
					)
					(number "B1"
						(effects
							(font
								(size 1.27 1.27)
							)
						)
					)
				)
				(pin bidirectional line
					(at 63.5 -8.89 180)
					(length 5.08)
					(name "IO_L1N_T0_AD4N_35"
						(effects
							(font
								(size 1.27 1.27)
							)
						)
					)
					(number "A1"
						(effects
							(font
								(size 1.27 1.27)
							)
						)
					)
				)
				(pin bidirectional line
					(at 63.5 -11.43 180)
					(length 5.08)
					(name "IO_L2P_T0_AD12P_35"
						(effects
							(font
								(size 1.27 1.27)
							)
						)
					)
					(number "C2"
						(effects
							(font
								(size 1.27 1.27)
							)
						)
					)
				)
				(pin bidirectional line
					(at 63.5 -13.97 180)
					(length 5.08)
					(name "IO_L2N_T0_AD12N_35"
						(effects
							(font
								(size 1.27 1.27)
							)
						)
					)
					(number "B2"
						(effects
							(font
								(size 1.27 1.27)
							)
						)
					)
				)
				(pin bidirectional line
					(at 63.5 -16.51 180)
					(length 5.08)
					(name "IO_L3P_T0_DQS_AD5P_35"
						(effects
							(font
								(size 1.27 1.27)
							)
						)
					)
					(number "E1"
						(effects
							(font
								(size 1.27 1.27)
							)
						)
					)
				)
				(pin bidirectional line
					(at 63.5 -19.05 180)
					(length 5.08)
					(name "IO_L3N_T0_DQS_AD5N_35"
						(effects
							(font
								(size 1.27 1.27)
							)
						)
					)
					(number "D1"
						(effects
							(font
								(size 1.27 1.27)
							)
						)
					)
				)
				(pin bidirectional line
					(at 63.5 -21.59 180)
					(length 5.08)
					(name "IO_L4P_T0_35"
						(effects
							(font
								(size 1.27 1.27)
							)
						)
					)
					(number "E2"
						(effects
							(font
								(size 1.27 1.27)
							)
						)
					)
				)
				(pin bidirectional line
					(at 63.5 -24.13 180)
					(length 5.08)
					(name "IO_L4N_T0_35"
						(effects
							(font
								(size 1.27 1.27)
							)
						)
					)
					(number "D2"
						(effects
							(font
								(size 1.27 1.27)
							)
						)
					)
				)
				(pin bidirectional line
					(at 63.5 -26.67 180)
					(length 5.08)
					(name "IO_L5P_T0_AD13P_35"
						(effects
							(font
								(size 1.27 1.27)
							)
						)
					)
					(number "G1"
						(effects
							(font
								(size 1.27 1.27)
							)
						)
					)
				)
				(pin bidirectional line
					(at 63.5 -29.21 180)
					(length 5.08)
					(name "IO_L5N_T0_AD13N_35"
						(effects
							(font
								(size 1.27 1.27)
							)
						)
					)
					(number "F1"
						(effects
							(font
								(size 1.27 1.27)
							)
						)
					)
				)
				(pin bidirectional line
					(at 63.5 -31.75 180)
					(length 5.08)
					(name "IO_L6P_T0_35"
						(effects
							(font
								(size 1.27 1.27)
							)
						)
					)
					(number "F3"
						(effects
							(font
								(size 1.27 1.27)
							)
						)
					)
				)
				(pin bidirectional line
					(at 63.5 -34.29 180)
					(length 5.08)
					(name "IO_L6N_T0_VREF_35"
						(effects
							(font
								(size 1.27 1.27)
							)
						)
					)
					(number "E3"
						(effects
							(font
								(size 1.27 1.27)
							)
						)
					)
				)
				(pin bidirectional line
					(at 63.5 -36.83 180)
					(length 5.08)
					(name "IO_L7P_T1_AD6P_35"
						(effects
							(font
								(size 1.27 1.27)
							)
						)
					)
					(number "K1"
						(effects
							(font
								(size 1.27 1.27)
							)
						)
					)
				)
				(pin bidirectional line
					(at 63.5 -39.37 180)
					(length 5.08)
					(name "IO_L7N_T1_AD6N_35"
						(effects
							(font
								(size 1.27 1.27)
							)
						)
					)
					(number "J1"
						(effects
							(font
								(size 1.27 1.27)
							)
						)
					)
				)
				(pin bidirectional line
					(at 63.5 -41.91 180)
					(length 5.08)
					(name "IO_L8P_T1_AD14P_35"
						(effects
							(font
								(size 1.27 1.27)
							)
						)
					)
					(number "H2"
						(effects
							(font
								(size 1.27 1.27)
							)
						)
					)
				)
				(pin bidirectional line
					(at 63.5 -44.45 180)
					(length 5.08)
					(name "IO_L8N_T1_AD14N_35"
						(effects
							(font
								(size 1.27 1.27)
							)
						)
					)
					(number "G2"
						(effects
							(font
								(size 1.27 1.27)
							)
						)
					)
				)
				(pin bidirectional line
					(at 63.5 -46.99 180)
					(length 5.08)
					(name "IO_L9P_T1_DQS_AD7P_35"
						(effects
							(font
								(size 1.27 1.27)
							)
						)
					)
					(number "K2"
						(effects
							(font
								(size 1.27 1.27)
							)
						)
					)
				)
				(pin bidirectional line
					(at 63.5 -49.53 180)
					(length 5.08)
					(name "IO_L9N_T1_DQS_AD7N_35"
						(effects
							(font
								(size 1.27 1.27)
							)
						)
					)
					(number "J2"
						(effects
							(font
								(size 1.27 1.27)
							)
						)
					)
				)
				(pin bidirectional line
					(at 63.5 -52.07 180)
					(length 5.08)
					(name "IO_L10P_T1_AD15P_35"
						(effects
							(font
								(size 1.27 1.27)
							)
						)
					)
					(number "J5"
						(effects
							(font
								(size 1.27 1.27)
							)
						)
					)
				)
				(pin bidirectional line
					(at 63.5 -54.61 180)
					(length 5.08)
					(name "IO_L10N_T1_AD15N_35"
						(effects
							(font
								(size 1.27 1.27)
							)
						)
					)
					(number "H5"
						(effects
							(font
								(size 1.27 1.27)
							)
						)
					)
				)
				(pin bidirectional line
					(at 63.5 -57.15 180)
					(length 5.08)
					(name "IO_L11P_T1_SRCC_35"
						(effects
							(font
								(size 1.27 1.27)
							)
						)
					)
					(number "H3"
						(effects
							(font
								(size 1.27 1.27)
							)
						)
					)
				)
				(pin bidirectional line
					(at 63.5 -59.69 180)
					(length 5.08)
					(name "IO_L11N_T1_SRCC_35"
						(effects
							(font
								(size 1.27 1.27)
							)
						)
					)
					(number "G3"
						(effects
							(font
								(size 1.27 1.27)
							)
						)
					)
				)
				(pin bidirectional line
					(at 63.5 -62.23 180)
					(length 5.08)
					(name "IO_L12P_T1_MRCC_35"
						(effects
							(font
								(size 1.27 1.27)
							)
						)
					)
					(number "H4"
						(effects
							(font
								(size 1.27 1.27)
							)
						)
					)
				)
				(pin bidirectional line
					(at 63.5 -64.77 180)
					(length 5.08)
					(name "IO_L12N_T1_MRCC_35"
						(effects
							(font
								(size 1.27 1.27)
							)
						)
					)
					(number "G4"
						(effects
							(font
								(size 1.27 1.27)
							)
						)
					)
				)
				(pin bidirectional line
					(at 63.5 -67.31 180)
					(length 5.08)
					(name "IO_L13P_T2_MRCC_35"
						(effects
							(font
								(size 1.27 1.27)
							)
						)
					)
					(number "K4"
						(effects
							(font
								(size 1.27 1.27)
							)
						)
					)
				)
				(pin bidirectional line
					(at 63.5 -69.85 180)
					(length 5.08)
					(name "IO_L13N_T2_MRCC_35"
						(effects
							(font
								(size 1.27 1.27)
							)
						)
					)
					(number "J4"
						(effects
							(font
								(size 1.27 1.27)
							)
						)
					)
				)
				(pin bidirectional line
					(at 63.5 -72.39 180)
					(length 5.08)
					(name "IO_L14P_T2_SRCC_35"
						(effects
							(font
								(size 1.27 1.27)
							)
						)
					)
					(number "L3"
						(effects
							(font
								(size 1.27 1.27)
							)
						)
					)
				)
				(pin bidirectional line
					(at 63.5 -74.93 180)
					(length 5.08)
					(name "IO_L14N_T2_SRCC_35"
						(effects
							(font
								(size 1.27 1.27)
							)
						)
					)
					(number "K3"
						(effects
							(font
								(size 1.27 1.27)
							)
						)
					)
				)
				(pin bidirectional line
					(at 63.5 -77.47 180)
					(length 5.08)
					(name "IO_L15P_T2_DQS_35"
						(effects
							(font
								(size 1.27 1.27)
							)
						)
					)
					(number "M1"
						(effects
							(font
								(size 1.27 1.27)
							)
						)
					)
				)
				(pin bidirectional line
					(at 63.5 -80.01 180)
					(length 5.08)
					(name "IO_L15N_T2_DQS_35"
						(effects
							(font
								(size 1.27 1.27)
							)
						)
					)
					(number "L1"
						(effects
							(font
								(size 1.27 1.27)
							)
						)
					)
				)
				(pin bidirectional line
					(at 63.5 -82.55 180)
					(length 5.08)
					(name "IO_L16P_T2_35"
						(effects
							(font
								(size 1.27 1.27)
							)
						)
					)
					(number "M3"
						(effects
							(font
								(size 1.27 1.27)
							)
						)
					)
				)
				(pin bidirectional line
					(at 63.5 -85.09 180)
					(length 5.08)
					(name "IO_L16N_T2_35"
						(effects
							(font
								(size 1.27 1.27)
							)
						)
					)
					(number "M2"
						(effects
							(font
								(size 1.27 1.27)
							)
						)
					)
				)
				(pin bidirectional line
					(at 63.5 -87.63 180)
					(length 5.08)
					(name "IO_L17P_T2_35"
						(effects
							(font
								(size 1.27 1.27)
							)
						)
					)
					(number "K6"
						(effects
							(font
								(size 1.27 1.27)
							)
						)
					)
				)
				(pin bidirectional line
					(at 63.5 -90.17 180)
					(length 5.08)
					(name "IO_L17N_T2_35"
						(effects
							(font
								(size 1.27 1.27)
							)
						)
					)
					(number "J6"
						(effects
							(font
								(size 1.27 1.27)
							)
						)
					)
				)
				(pin bidirectional line
					(at 63.5 -92.71 180)
					(length 5.08)
					(name "IO_L18P_T2_35"
						(effects
							(font
								(size 1.27 1.27)
							)
						)
					)
					(number "L5"
						(effects
							(font
								(size 1.27 1.27)
							)
						)
					)
				)
				(pin bidirectional line
					(at 63.5 -95.25 180)
					(length 5.08)
					(name "IO_L18N_T2_35"
						(effects
							(font
								(size 1.27 1.27)
							)
						)
					)
					(number "L4"
						(effects
							(font
								(size 1.27 1.27)
							)
						)
					)
				)
				(pin bidirectional line
					(at 63.5 -97.79 180)
					(length 5.08)
					(name "IO_L19P_T3_35"
						(effects
							(font
								(size 1.27 1.27)
							)
						)
					)
					(number "N4"
						(effects
							(font
								(size 1.27 1.27)
							)
						)
					)
				)
				(pin bidirectional line
					(at 63.5 -100.33 180)
					(length 5.08)
					(name "IO_L19N_T3_VREF_35"
						(effects
							(font
								(size 1.27 1.27)
							)
						)
					)
					(number "N3"
						(effects
							(font
								(size 1.27 1.27)
							)
						)
					)
				)
				(pin bidirectional line
					(at 63.5 -102.87 180)
					(length 5.08)
					(name "IO_L20P_T3_35"
						(effects
							(font
								(size 1.27 1.27)
							)
						)
					)
					(number "R1"
						(effects
							(font
								(size 1.27 1.27)
							)
						)
					)
				)
				(pin bidirectional line
					(at 63.5 -105.41 180)
					(length 5.08)
					(name "IO_L20N_T3_35"
						(effects
							(font
								(size 1.27 1.27)
							)
						)
					)
					(number "P1"
						(effects
							(font
								(size 1.27 1.27)
							)
						)
					)
				)
				(pin bidirectional line
					(at 63.5 -107.95 180)
					(length 5.08)
					(name "IO_L21P_T3_DQS_35"
						(effects
							(font
								(size 1.27 1.27)
							)
						)
					)
					(number "P5"
						(effects
							(font
								(size 1.27 1.27)
							)
						)
					)
				)
				(pin bidirectional line
					(at 63.5 -110.49 180)
					(length 5.08)
					(name "IO_L21N_T3_DQS_35"
						(effects
							(font
								(size 1.27 1.27)
							)
						)
					)
					(number "P4"
						(effects
							(font
								(size 1.27 1.27)
							)
						)
					)
				)
				(pin bidirectional line
					(at 63.5 -113.03 180)
					(length 5.08)
					(name "IO_L22P_T3_35"
						(effects
							(font
								(size 1.27 1.27)
							)
						)
					)
					(number "P2"
						(effects
							(font
								(size 1.27 1.27)
							)
						)
					)
				)
				(pin bidirectional line
					(at 63.5 -115.57 180)
					(length 5.08)
					(name "IO_L22N_T3_35"
						(effects
							(font
								(size 1.27 1.27)
							)
						)
					)
					(number "N2"
						(effects
							(font
								(size 1.27 1.27)
							)
						)
					)
				)
				(pin bidirectional line
					(at 63.5 -118.11 180)
					(length 5.08)
					(name "IO_L23P_T3_35"
						(effects
							(font
								(size 1.27 1.27)
							)
						)
					)
					(number "M6"
						(effects
							(font
								(size 1.27 1.27)
							)
						)
					)
				)
				(pin bidirectional line
					(at 63.5 -120.65 180)
					(length 5.08)
					(name "IO_L23N_T3_35"
						(effects
							(font
								(size 1.27 1.27)
							)
						)
					)
					(number "M5"
						(effects
							(font
								(size 1.27 1.27)
							)
						)
					)
				)
				(pin bidirectional line
					(at 63.5 -123.19 180)
					(length 5.08)
					(name "IO_L24P_T3_35"
						(effects
							(font
								(size 1.27 1.27)
							)
						)
					)
					(number "P6"
						(effects
							(font
								(size 1.27 1.27)
							)
						)
					)
				)
				(pin bidirectional line
					(at 63.5 -125.73 180)
					(length 5.08)
					(name "IO_L24N_T3_35"
						(effects
							(font
								(size 1.27 1.27)
							)
						)
					)
					(number "N5"
						(effects
							(font
								(size 1.27 1.27)
							)
						)
					)
				)
				(pin bidirectional line
					(at 63.5 -128.27 180)
					(length 5.08)
					(name "IO_25_35"
						(effects
							(font
								(size 1.27 1.27)
							)
						)
					)
					(number "L6"
						(effects
							(font
								(size 1.27 1.27)
							)
						)
					)
				)
			)
			(symbol "XC7A100T-FGG484_4_1"
				(rectangle
					(start 5.08 2.54)
					(end 21.59 -55.88)
					(stroke
						(width 0.254)
						(type default)
					)
					(fill
						(type background)
					)
				)
				(pin power_in line
					(at 0 0 0)
					(length 5.08)
					(name "VCCO_0"
						(effects
							(font
								(size 1.27 1.27)
							)
						)
					)
					(number "F12"
						(effects
							(font
								(size 1.27 1.27)
							)
						)
					)
				)
				(pin passive line
					(at 0 0 0)
					(length 5.08)
					(hide yes)
					(name "VCCO_0"
						(effects
							(font
								(size 1.27 1.27)
							)
						)
					)
					(number "T12"
						(effects
							(font
								(size 1.27 1.27)
							)
						)
					)
				)
				(pin bidirectional line
					(at 0 -3.81 0)
					(length 5.08)
					(name "DONE_0"
						(effects
							(font
								(size 1.27 1.27)
							)
						)
					)
					(number "G11"
						(effects
							(font
								(size 1.27 1.27)
							)
						)
					)
				)
				(pin bidirectional line
					(at 0 -6.35 0)
					(length 5.08)
					(name "INIT_B_0"
						(effects
							(font
								(size 1.27 1.27)
							)
						)
					)
					(number "U12"
						(effects
							(font
								(size 1.27 1.27)
							)
						)
					)
				)
				(pin bidirectional line
					(at 0 -8.89 0)
					(length 5.08)
					(name "PROGRAM_B_0"
						(effects
							(font
								(size 1.27 1.27)
							)
						)
					)
					(number "N12"
						(effects
							(font
								(size 1.27 1.27)
							)
						)
					)
				)
				(pin bidirectional line
					(at 0 -11.43 0)
					(length 5.08)
					(name "CFGBVS_0"
						(effects
							(font
								(size 1.27 1.27)
							)
						)
					)
					(number "U8"
						(effects
							(font
								(size 1.27 1.27)
							)
						)
					)
				)
				(pin bidirectional line
					(at 0 -15.24 0)
					(length 5.08)
					(name "CCLK_0"
						(effects
							(font
								(size 1.27 1.27)
							)
						)
					)
					(number "L12"
						(effects
							(font
								(size 1.27 1.27)
							)
						)
					)
				)
				(pin bidirectional line
					(at 0 -17.78 0)
					(length 5.08)
					(name "M0_0"
						(effects
							(font
								(size 1.27 1.27)
							)
						)
					)
					(number "U11"
						(effects
							(font
								(size 1.27 1.27)
							)
						)
					)
				)
				(pin bidirectional line
					(at 0 -20.32 0)
					(length 5.08)
					(name "M1_0"
						(effects
							(font
								(size 1.27 1.27)
							)
						)
					)
					(number "U10"
						(effects
							(font
								(size 1.27 1.27)
							)
						)
					)
				)
				(pin bidirectional line
					(at 0 -22.86 0)
					(length 5.08)
					(name "M2_0"
						(effects
							(font
								(size 1.27 1.27)
							)
						)
					)
					(number "U9"
						(effects
							(font
								(size 1.27 1.27)
							)
						)
					)
				)
				(pin bidirectional line
					(at 0 -26.67 0)
					(length 5.08)
					(name "TDI_0"
						(effects
							(font
								(size 1.27 1.27)
							)
						)
					)
					(number "R13"
						(effects
							(font
								(size 1.27 1.27)
							)
						)
					)
				)
				(pin bidirectional line
					(at 0 -29.21 0)
					(length 5.08)
					(name "TDO_0"
						(effects
							(font
								(size 1.27 1.27)
							)
						)
					)
					(number "U13"
						(effects
							(font
								(size 1.27 1.27)
							)
						)
					)
				)
				(pin bidirectional line
					(at 0 -31.75 0)
					(length 5.08)
					(name "TMS_0"
						(effects
							(font
								(size 1.27 1.27)
							)
						)
					)
					(number "T13"
						(effects
							(font
								(size 1.27 1.27)
							)
						)
					)
				)
				(pin bidirectional line
					(at 0 -34.29 0)
					(length 5.08)
					(name "TCK_0"
						(effects
							(font
								(size 1.27 1.27)
							)
						)
					)
					(number "V12"
						(effects
							(font
								(size 1.27 1.27)
							)
						)
					)
				)
				(pin bidirectional line
					(at 0 -38.1 0)
					(length 5.08)
					(name "VP_0"
						(effects
							(font
								(size 1.27 1.27)
							)
						)
					)
					(number "L10"
						(effects
							(font
								(size 1.27 1.27)
							)
						)
					)
				)
				(pin bidirectional line
					(at 0 -40.64 0)
					(length 5.08)
					(name "VN_0"
						(effects
							(font
								(size 1.27 1.27)
							)
						)
					)
					(number "M9"
						(effects
							(font
								(size 1.27 1.27)
							)
						)
					)
				)
				(pin bidirectional line
					(at 0 -44.45 0)
					(length 5.08)
					(name "VREFP_0"
						(effects
							(font
								(size 1.27 1.27)
							)
						)
					)
					(number "M10"
						(effects
							(font
								(size 1.27 1.27)
							)
						)
					)
				)
				(pin bidirectional line
					(at 0 -46.99 0)
					(length 5.08)
					(name "VREFN_0"
						(effects
							(font
								(size 1.27 1.27)
							)
						)
					)
					(number "L9"
						(effects
							(font
								(size 1.27 1.27)
							)
						)
					)
				)
				(pin bidirectional line
					(at 0 -50.8 0)
					(length 5.08)
					(name "DXP_0"
						(effects
							(font
								(size 1.27 1.27)
							)
						)
					)
					(number "N10"
						(effects
							(font
								(size 1.27 1.27)
							)
						)
					)
				)
				(pin bidirectional line
					(at 0 -53.34 0)
					(length 5.08)
					(name "DXN_0"
						(effects
							(font
								(size 1.27 1.27)
							)
						)
					)
					(number "N9"
						(effects
							(font
								(size 1.27 1.27)
							)
						)
					)
				)
			)
			(symbol "XC7A100T-FGG484_5_1"
				(rectangle
					(start 5.08 2.54)
					(end 26.67 -62.23)
					(stroke
						(width 0.254)
						(type default)
					)
					(fill
						(type background)
					)
				)
				(pin passive line
					(at 0 0 0)
					(length 5.08)
					(hide yes)
					(name "MGTAVTT"
						(effects
							(font
								(size 1.27 1.27)
							)
						)
					)
					(number "B11"
						(effects
							(font
								(size 1.27 1.27)
							)
						)
					)
				)
				(pin power_in line
					(at 0 0 0)
					(length 5.08)
					(name "MGTAVTT"
						(effects
							(font
								(size 1.27 1.27)
							)
						)
					)
					(number "B5"
						(effects
							(font
								(size 1.27 1.27)
							)
						)
					)
				)
				(pin passive line
					(at 0 0 0)
					(length 5.08)
					(hide yes)
					(name "MGTAVTT"
						(effects
							(font
								(size 1.27 1.27)
							)
						)
					)
					(number "B7"
						(effects
							(font
								(size 1.27 1.27)
							)
						)
					)
				)
				(pin passive line
					(at 0 0 0)
					(length 5.08)
					(hide yes)
					(name "MGTAVTT"
						(effects
							(font
								(size 1.27 1.27)
							)
						)
					)
					(number "B9"
						(effects
							(font
								(size 1.27 1.27)
							)
						)
					)
				)
				(pin passive line
					(at 0 0 0)
					(length 5.08)
					(hide yes)
					(name "MGTAVTT"
						(effects
							(font
								(size 1.27 1.27)
							)
						)
					)
					(number "C4"
						(effects
							(font
								(size 1.27 1.27)
							)
						)
					)
				)
				(pin passive line
					(at 0 0 0)
					(length 5.08)
					(hide yes)
					(name "MGTAVTT"
						(effects
							(font
								(size 1.27 1.27)
							)
						)
					)
					(number "C8"
						(effects
							(font
								(size 1.27 1.27)
							)
						)
					)
				)
				(pin passive line
					(at 0 -2.54 0)
					(length 5.08)
					(name "MGTRREF_216"
						(effects
							(font
								(size 1.27 1.27)
							)
						)
					)
					(number "F8"
						(effects
							(font
								(size 1.27 1.27)
							)
						)
					)
				)
				(pin passive line
					(at 0 -5.08 0)
					(length 5.08)
					(hide yes)
					(name "MGTAVCC"
						(effects
							(font
								(size 1.27 1.27)
							)
						)
					)
					(number "D10"
						(effects
							(font
								(size 1.27 1.27)
							)
						)
					)
				)
				(pin power_in line
					(at 0 -5.08 0)
					(length 5.08)
					(name "MGTAVCC"
						(effects
							(font
								(size 1.27 1.27)
							)
						)
					)
					(number "D6"
						(effects
							(font
								(size 1.27 1.27)
							)
						)
					)
				)
				(pin passive line
					(at 0 -5.08 0)
					(length 5.08)
					(hide yes)
					(name "MGTAVCC"
						(effects
							(font
								(size 1.27 1.27)
							)
						)
					)
					(number "E8"
						(effects
							(font
								(size 1.27 1.27)
							)
						)
					)
				)
				(pin passive line
					(at 0 -5.08 0)
					(length 5.08)
					(hide yes)
					(name "MGTAVCC"
						(effects
							(font
								(size 1.27 1.27)
							)
						)
					)
					(number "F7"
						(effects
							(font
								(size 1.27 1.27)
							)
						)
					)
				)
				(pin passive line
					(at 0 -5.08 0)
					(length 5.08)
					(hide yes)
					(name "MGTAVCC"
						(effects
							(font
								(size 1.27 1.27)
							)
						)
					)
					(number "F9"
						(effects
							(font
								(size 1.27 1.27)
							)
						)
					)
				)
				(pin bidirectional line
					(at 0 -8.89 0)
					(length 5.08)
					(name "MGTPTXP0_216"
						(effects
							(font
								(size 1.27 1.27)
							)
						)
					)
					(number "B4"
						(effects
							(font
								(size 1.27 1.27)
							)
						)
					)
				)
				(pin bidirectional line
					(at 0 -11.43 0)
					(length 5.08)
					(name "MGTPTXN0_216"
						(effects
							(font
								(size 1.27 1.27)
							)
						)
					)
					(number "A4"
						(effects
							(font
								(size 1.27 1.27)
							)
						)
					)
				)
				(pin bidirectional line
					(at 0 -13.97 0)
					(length 5.08)
					(name "MGTPTXP1_216"
						(effects
							(font
								(size 1.27 1.27)
							)
						)
					)
					(number "D5"
						(effects
							(font
								(size 1.27 1.27)
							)
						)
					)
				)
				(pin bidirectional line
					(at 0 -16.51 0)
					(length 5.08)
					(name "MGTPTXN1_216"
						(effects
							(font
								(size 1.27 1.27)
							)
						)
					)
					(number "C5"
						(effects
							(font
								(size 1.27 1.27)
							)
						)
					)
				)
				(pin bidirectional line
					(at 0 -19.05 0)
					(length 5.08)
					(name "MGTPTXP2_216"
						(effects
							(font
								(size 1.27 1.27)
							)
						)
					)
					(number "B6"
						(effects
							(font
								(size 1.27 1.27)
							)
						)
					)
				)
				(pin bidirectional line
					(at 0 -21.59 0)
					(length 5.08)
					(name "MGTPTXN2_216"
						(effects
							(font
								(size 1.27 1.27)
							)
						)
					)
					(number "A6"
						(effects
							(font
								(size 1.27 1.27)
							)
						)
					)
				)
				(pin bidirectional line
					(at 0 -24.13 0)
					(length 5.08)
					(name "MGTPTXP3_216"
						(effects
							(font
								(size 1.27 1.27)
							)
						)
					)
					(number "D7"
						(effects
							(font
								(size 1.27 1.27)
							)
						)
					)
				)
				(pin bidirectional line
					(at 0 -26.67 0)
					(length 5.08)
					(name "MGTPTXN3_216"
						(effects
							(font
								(size 1.27 1.27)
							)
						)
					)
					(number "C7"
						(effects
							(font
								(size 1.27 1.27)
							)
						)
					)
				)
				(pin bidirectional line
					(at 0 -30.48 0)
					(length 5.08)
					(name "MGTPRXP0_216"
						(effects
							(font
								(size 1.27 1.27)
							)
						)
					)
					(number "B8"
						(effects
							(font
								(size 1.27 1.27)
							)
						)
					)
				)
				(pin bidirectional line
					(at 0 -33.02 0)
					(length 5.08)
					(name "MGTPRXN0_216"
						(effects
							(font
								(size 1.27 1.27)
							)
						)
					)
					(number "A8"
						(effects
							(font
								(size 1.27 1.27)
							)
						)
					)
				)
				(pin bidirectional line
					(at 0 -35.56 0)
					(length 5.08)
					(name "MGTPRXP1_216"
						(effects
							(font
								(size 1.27 1.27)
							)
						)
					)
					(number "D11"
						(effects
							(font
								(size 1.27 1.27)
							)
						)
					)
				)
				(pin bidirectional line
					(at 0 -38.1 0)
					(length 5.08)
					(name "MGTPRXN1_216"
						(effects
							(font
								(size 1.27 1.27)
							)
						)
					)
					(number "C11"
						(effects
							(font
								(size 1.27 1.27)
							)
						)
					)
				)
				(pin bidirectional line
					(at 0 -40.64 0)
					(length 5.08)
					(name "MGTPRXP2_216"
						(effects
							(font
								(size 1.27 1.27)
							)
						)
					)
					(number "B10"
						(effects
							(font
								(size 1.27 1.27)
							)
						)
					)
				)
				(pin bidirectional line
					(at 0 -43.18 0)
					(length 5.08)
					(name "MGTPRXN2_216"
						(effects
							(font
								(size 1.27 1.27)
							)
						)
					)
					(number "A10"
						(effects
							(font
								(size 1.27 1.27)
							)
						)
					)
				)
				(pin bidirectional line
					(at 0 -45.72 0)
					(length 5.08)
					(name "MGTPRXP3_216"
						(effects
							(font
								(size 1.27 1.27)
							)
						)
					)
					(number "D9"
						(effects
							(font
								(size 1.27 1.27)
							)
						)
					)
				)
				(pin bidirectional line
					(at 0 -48.26 0)
					(length 5.08)
					(name "MGTPRXN3_216"
						(effects
							(font
								(size 1.27 1.27)
							)
						)
					)
					(number "C9"
						(effects
							(font
								(size 1.27 1.27)
							)
						)
					)
				)
				(pin bidirectional line
					(at 0 -52.07 0)
					(length 5.08)
					(name "MGTREFCLK0P_216"
						(effects
							(font
								(size 1.27 1.27)
							)
						)
					)
					(number "F6"
						(effects
							(font
								(size 1.27 1.27)
							)
						)
					)
				)
				(pin bidirectional line
					(at 0 -54.61 0)
					(length 5.08)
					(name "MGTREFCLK0N_216"
						(effects
							(font
								(size 1.27 1.27)
							)
						)
					)
					(number "E6"
						(effects
							(font
								(size 1.27 1.27)
							)
						)
					)
				)
				(pin bidirectional line
					(at 0 -57.15 0)
					(length 5.08)
					(name "MGTREFCLK1P_216"
						(effects
							(font
								(size 1.27 1.27)
							)
						)
					)
					(number "F10"
						(effects
							(font
								(size 1.27 1.27)
							)
						)
					)
				)
				(pin bidirectional line
					(at 0 -59.69 0)
					(length 5.08)
					(name "MGTREFCLK1N_216"
						(effects
							(font
								(size 1.27 1.27)
							)
						)
					)
					(number "E10"
						(effects
							(font
								(size 1.27 1.27)
							)
						)
					)
				)
			)
			(symbol "XC7A100T-FGG484_6_1"
				(rectangle
					(start 5.08 2.54)
					(end 16.51 -19.05)
					(stroke
						(width 0.254)
						(type default)
					)
					(fill
						(type background)
					)
				)
				(pin power_in line
					(at 0 0 0)
					(length 5.08)
					(name "VCCAUX"
						(effects
							(font
								(size 1.27 1.27)
							)
						)
					)
					(number "H12"
						(effects
							(font
								(size 1.27 1.27)
							)
						)
					)
				)
				(pin passive line
					(at 0 0 0)
					(length 5.08)
					(hide yes)
					(name "VCCAUX"
						(effects
							(font
								(size 1.27 1.27)
							)
						)
					)
					(number "K12"
						(effects
							(font
								(size 1.27 1.27)
							)
						)
					)
				)
				(pin passive line
					(at 0 0 0)
					(length 5.08)
					(hide yes)
					(name "VCCAUX"
						(effects
							(font
								(size 1.27 1.27)
							)
						)
					)
					(number "M12"
						(effects
							(font
								(size 1.27 1.27)
							)
						)
					)
				)
				(pin passive line
					(at 0 0 0)
					(length 5.08)
					(hide yes)
					(name "VCCAUX"
						(effects
							(font
								(size 1.27 1.27)
							)
						)
					)
					(number "P12"
						(effects
							(font
								(size 1.27 1.27)
							)
						)
					)
				)
				(pin passive line
					(at 0 0 0)
					(length 5.08)
					(hide yes)
					(name "VCCAUX"
						(effects
							(font
								(size 1.27 1.27)
							)
						)
					)
					(number "R11"
						(effects
							(font
								(size 1.27 1.27)
							)
						)
					)
				)
				(pin power_in line
					(at 0 -2.54 0)
					(length 5.08)
					(name "VCCADC"
						(effects
							(font
								(size 1.27 1.27)
							)
						)
					)
					(number "K10"
						(effects
							(font
								(size 1.27 1.27)
							)
						)
					)
				)
				(pin power_in line
					(at 0 -5.08 0)
					(length 5.08)
					(name "VCCBATT"
						(effects
							(font
								(size 1.27 1.27)
							)
						)
					)
					(number "E12"
						(effects
							(font
								(size 1.27 1.27)
							)
						)
					)
				)
				(pin passive line
					(at 0 -7.62 0)
					(length 5.08)
					(hide yes)
					(name "VCCINT"
						(effects
							(font
								(size 1.27 1.27)
							)
						)
					)
					(number "H10"
						(effects
							(font
								(size 1.27 1.27)
							)
						)
					)
				)
				(pin power_in line
					(at 0 -7.62 0)
					(length 5.08)
					(name "VCCINT"
						(effects
							(font
								(size 1.27 1.27)
							)
						)
					)
					(number "H8"
						(effects
							(font
								(size 1.27 1.27)
							)
						)
					)
				)
				(pin passive line
					(at 0 -7.62 0)
					(length 5.08)
					(hide yes)
					(name "VCCINT"
						(effects
							(font
								(size 1.27 1.27)
							)
						)
					)
					(number "J7"
						(effects
							(font
								(size 1.27 1.27)
							)
						)
					)
				)
				(pin passive line
					(at 0 -7.62 0)
					(length 5.08)
					(hide yes)
					(name "VCCINT"
						(effects
							(font
								(size 1.27 1.27)
							)
						)
					)
					(number "J9"
						(effects
							(font
								(size 1.27 1.27)
							)
						)
					)
				)
				(pin passive line
					(at 0 -7.62 0)
					(length 5.08)
					(hide yes)
					(name "VCCINT"
						(effects
							(font
								(size 1.27 1.27)
							)
						)
					)
					(number "K8"
						(effects
							(font
								(size 1.27 1.27)
							)
						)
					)
				)
				(pin passive line
					(at 0 -7.62 0)
					(length 5.08)
					(hide yes)
					(name "VCCINT"
						(effects
							(font
								(size 1.27 1.27)
							)
						)
					)
					(number "L7"
						(effects
							(font
								(size 1.27 1.27)
							)
						)
					)
				)
				(pin passive line
					(at 0 -7.62 0)
					(length 5.08)
					(hide yes)
					(name "VCCINT"
						(effects
							(font
								(size 1.27 1.27)
							)
						)
					)
					(number "M8"
						(effects
							(font
								(size 1.27 1.27)
							)
						)
					)
				)
				(pin passive line
					(at 0 -7.62 0)
					(length 5.08)
					(hide yes)
					(name "VCCINT"
						(effects
							(font
								(size 1.27 1.27)
							)
						)
					)
					(number "N7"
						(effects
							(font
								(size 1.27 1.27)
							)
						)
					)
				)
				(pin passive line
					(at 0 -7.62 0)
					(length 5.08)
					(hide yes)
					(name "VCCINT"
						(effects
							(font
								(size 1.27 1.27)
							)
						)
					)
					(number "P10"
						(effects
							(font
								(size 1.27 1.27)
							)
						)
					)
				)
				(pin passive line
					(at 0 -7.62 0)
					(length 5.08)
					(hide yes)
					(name "VCCINT"
						(effects
							(font
								(size 1.27 1.27)
							)
						)
					)
					(number "P8"
						(effects
							(font
								(size 1.27 1.27)
							)
						)
					)
				)
				(pin passive line
					(at 0 -7.62 0)
					(length 5.08)
					(hide yes)
					(name "VCCINT"
						(effects
							(font
								(size 1.27 1.27)
							)
						)
					)
					(number "R7"
						(effects
							(font
								(size 1.27 1.27)
							)
						)
					)
				)
				(pin passive line
					(at 0 -7.62 0)
					(length 5.08)
					(hide yes)
					(name "VCCINT"
						(effects
							(font
								(size 1.27 1.27)
							)
						)
					)
					(number "R9"
						(effects
							(font
								(size 1.27 1.27)
							)
						)
					)
				)
				(pin passive line
					(at 0 -7.62 0)
					(length 5.08)
					(hide yes)
					(name "VCCINT"
						(effects
							(font
								(size 1.27 1.27)
							)
						)
					)
					(number "T10"
						(effects
							(font
								(size 1.27 1.27)
							)
						)
					)
				)
				(pin passive line
					(at 0 -7.62 0)
					(length 5.08)
					(hide yes)
					(name "VCCINT"
						(effects
							(font
								(size 1.27 1.27)
							)
						)
					)
					(number "T8"
						(effects
							(font
								(size 1.27 1.27)
							)
						)
					)
				)
				(pin power_in line
					(at 0 -10.16 0)
					(length 5.08)
					(name "VCCBRAM"
						(effects
							(font
								(size 1.27 1.27)
							)
						)
					)
					(number "J11"
						(effects
							(font
								(size 1.27 1.27)
							)
						)
					)
				)
				(pin passive line
					(at 0 -10.16 0)
					(length 5.08)
					(hide yes)
					(name "VCCBRAM"
						(effects
							(font
								(size 1.27 1.27)
							)
						)
					)
					(number "L11"
						(effects
							(font
								(size 1.27 1.27)
							)
						)
					)
				)
				(pin passive line
					(at 0 -10.16 0)
					(length 5.08)
					(hide yes)
					(name "VCCBRAM"
						(effects
							(font
								(size 1.27 1.27)
							)
						)
					)
					(number "N11"
						(effects
							(font
								(size 1.27 1.27)
							)
						)
					)
				)
				(pin power_in line
					(at 0 -13.97 0)
					(length 5.08)
					(name "GND_ADC"
						(effects
							(font
								(size 1.27 1.27)
							)
						)
					)
					(number "K9"
						(effects
							(font
								(size 1.27 1.27)
							)
						)
					)
				)
				(pin passive line
					(at 0 -16.51 0)
					(length 5.08)
					(hide yes)
					(name "GND"
						(effects
							(font
								(size 1.27 1.27)
							)
						)
					)
					(number "A11"
						(effects
							(font
								(size 1.27 1.27)
							)
						)
					)
				)
				(pin passive line
					(at 0 -16.51 0)
					(length 5.08)
					(hide yes)
					(name "GND"
						(effects
							(font
								(size 1.27 1.27)
							)
						)
					)
					(number "A12"
						(effects
							(font
								(size 1.27 1.27)
							)
						)
					)
				)
				(pin power_in line
					(at 0 -16.51 0)
					(length 5.08)
					(name "GND"
						(effects
							(font
								(size 1.27 1.27)
							)
						)
					)
					(number "A2"
						(effects
							(font
								(size 1.27 1.27)
							)
						)
					)
				)
				(pin passive line
					(at 0 -16.51 0)
					(length 5.08)
					(hide yes)
					(name "GND"
						(effects
							(font
								(size 1.27 1.27)
							)
						)
					)
					(number "A22"
						(effects
							(font
								(size 1.27 1.27)
							)
						)
					)
				)
				(pin passive line
					(at 0 -16.51 0)
					(length 5.08)
					(hide yes)
					(name "GND"
						(effects
							(font
								(size 1.27 1.27)
							)
						)
					)
					(number "A3"
						(effects
							(font
								(size 1.27 1.27)
							)
						)
					)
				)
				(pin passive line
					(at 0 -16.51 0)
					(length 5.08)
					(hide yes)
					(name "GND"
						(effects
							(font
								(size 1.27 1.27)
							)
						)
					)
					(number "A5"
						(effects
							(font
								(size 1.27 1.27)
							)
						)
					)
				)
				(pin passive line
					(at 0 -16.51 0)
					(length 5.08)
					(hide yes)
					(name "GND"
						(effects
							(font
								(size 1.27 1.27)
							)
						)
					)
					(number "A7"
						(effects
							(font
								(size 1.27 1.27)
							)
						)
					)
				)
				(pin passive line
					(at 0 -16.51 0)
					(length 5.08)
					(hide yes)
					(name "GND"
						(effects
							(font
								(size 1.27 1.27)
							)
						)
					)
					(number "A9"
						(effects
							(font
								(size 1.27 1.27)
							)
						)
					)
				)
				(pin passive line
					(at 0 -16.51 0)
					(length 5.08)
					(hide yes)
					(name "GND"
						(effects
							(font
								(size 1.27 1.27)
							)
						)
					)
					(number "AA12"
						(effects
							(font
								(size 1.27 1.27)
							)
						)
					)
				)
				(pin passive line
					(at 0 -16.51 0)
					(length 5.08)
					(hide yes)
					(name "GND"
						(effects
							(font
								(size 1.27 1.27)
							)
						)
					)
					(number "AA2"
						(effects
							(font
								(size 1.27 1.27)
							)
						)
					)
				)
				(pin passive line
					(at 0 -16.51 0)
					(length 5.08)
					(hide yes)
					(name "GND"
						(effects
							(font
								(size 1.27 1.27)
							)
						)
					)
					(number "AA22"
						(effects
							(font
								(size 1.27 1.27)
							)
						)
					)
				)
				(pin passive line
					(at 0 -16.51 0)
					(length 5.08)
					(hide yes)
					(name "GND"
						(effects
							(font
								(size 1.27 1.27)
							)
						)
					)
					(number "AB19"
						(effects
							(font
								(size 1.27 1.27)
							)
						)
					)
				)
				(pin passive line
					(at 0 -16.51 0)
					(length 5.08)
					(hide yes)
					(name "GND"
						(effects
							(font
								(size 1.27 1.27)
							)
						)
					)
					(number "AB9"
						(effects
							(font
								(size 1.27 1.27)
							)
						)
					)
				)
				(pin passive line
					(at 0 -16.51 0)
					(length 5.08)
					(hide yes)
					(name "GND"
						(effects
							(font
								(size 1.27 1.27)
							)
						)
					)
					(number "B12"
						(effects
							(font
								(size 1.27 1.27)
							)
						)
					)
				)
				(pin passive line
					(at 0 -16.51 0)
					(length 5.08)
					(hide yes)
					(name "GND"
						(effects
							(font
								(size 1.27 1.27)
							)
						)
					)
					(number "B19"
						(effects
							(font
								(size 1.27 1.27)
							)
						)
					)
				)
				(pin passive line
					(at 0 -16.51 0)
					(length 5.08)
					(hide yes)
					(name "GND"
						(effects
							(font
								(size 1.27 1.27)
							)
						)
					)
					(number "B3"
						(effects
							(font
								(size 1.27 1.27)
							)
						)
					)
				)
				(pin passive line
					(at 0 -16.51 0)
					(length 5.08)
					(hide yes)
					(name "GND"
						(effects
							(font
								(size 1.27 1.27)
							)
						)
					)
					(number "C10"
						(effects
							(font
								(size 1.27 1.27)
							)
						)
					)
				)
				(pin passive line
					(at 0 -16.51 0)
					(length 5.08)
					(hide yes)
					(name "GND"
						(effects
							(font
								(size 1.27 1.27)
							)
						)
					)
					(number "C12"
						(effects
							(font
								(size 1.27 1.27)
							)
						)
					)
				)
				(pin passive line
					(at 0 -16.51 0)
					(length 5.08)
					(hide yes)
					(name "GND"
						(effects
							(font
								(size 1.27 1.27)
							)
						)
					)
					(number "C16"
						(effects
							(font
								(size 1.27 1.27)
							)
						)
					)
				)
				(pin passive line
					(at 0 -16.51 0)
					(length 5.08)
					(hide yes)
					(name "GND"
						(effects
							(font
								(size 1.27 1.27)
							)
						)
					)
					(number "C3"
						(effects
							(font
								(size 1.27 1.27)
							)
						)
					)
				)
				(pin passive line
					(at 0 -16.51 0)
					(length 5.08)
					(hide yes)
					(name "GND"
						(effects
							(font
								(size 1.27 1.27)
							)
						)
					)
					(number "C6"
						(effects
							(font
								(size 1.27 1.27)
							)
						)
					)
				)
				(pin passive line
					(at 0 -16.51 0)
					(length 5.08)
					(hide yes)
					(name "GND"
						(effects
							(font
								(size 1.27 1.27)
							)
						)
					)
					(number "D12"
						(effects
							(font
								(size 1.27 1.27)
							)
						)
					)
				)
				(pin passive line
					(at 0 -16.51 0)
					(length 5.08)
					(hide yes)
					(name "GND"
						(effects
							(font
								(size 1.27 1.27)
							)
						)
					)
					(number "D13"
						(effects
							(font
								(size 1.27 1.27)
							)
						)
					)
				)
				(pin passive line
					(at 0 -16.51 0)
					(length 5.08)
					(hide yes)
					(name "GND"
						(effects
							(font
								(size 1.27 1.27)
							)
						)
					)
					(number "D3"
						(effects
							(font
								(size 1.27 1.27)
							)
						)
					)
				)
				(pin passive line
					(at 0 -16.51 0)
					(length 5.08)
					(hide yes)
					(name "GND"
						(effects
							(font
								(size 1.27 1.27)
							)
						)
					)
					(number "D4"
						(effects
							(font
								(size 1.27 1.27)
							)
						)
					)
				)
				(pin passive line
					(at 0 -16.51 0)
					(length 5.08)
					(hide yes)
					(name "GND"
						(effects
							(font
								(size 1.27 1.27)
							)
						)
					)
					(number "D8"
						(effects
							(font
								(size 1.27 1.27)
							)
						)
					)
				)
				(pin passive line
					(at 0 -16.51 0)
					(length 5.08)
					(hide yes)
					(name "GND"
						(effects
							(font
								(size 1.27 1.27)
							)
						)
					)
					(number "E11"
						(effects
							(font
								(size 1.27 1.27)
							)
						)
					)
				)
				(pin passive line
					(at 0 -16.51 0)
					(length 5.08)
					(hide yes)
					(name "GND"
						(effects
							(font
								(size 1.27 1.27)
							)
						)
					)
					(number "E20"
						(effects
							(font
								(size 1.27 1.27)
							)
						)
					)
				)
				(pin passive line
					(at 0 -16.51 0)
					(length 5.08)
					(hide yes)
					(name "GND"
						(effects
							(font
								(size 1.27 1.27)
							)
						)
					)
					(number "E4"
						(effects
							(font
								(size 1.27 1.27)
							)
						)
					)
				)
				(pin passive line
					(at 0 -16.51 0)
					(length 5.08)
					(hide yes)
					(name "GND"
						(effects
							(font
								(size 1.27 1.27)
							)
						)
					)
					(number "E5"
						(effects
							(font
								(size 1.27 1.27)
							)
						)
					)
				)
				(pin passive line
					(at 0 -16.51 0)
					(length 5.08)
					(hide yes)
					(name "GND"
						(effects
							(font
								(size 1.27 1.27)
							)
						)
					)
					(number "E7"
						(effects
							(font
								(size 1.27 1.27)
							)
						)
					)
				)
				(pin passive line
					(at 0 -16.51 0)
					(length 5.08)
					(hide yes)
					(name "GND"
						(effects
							(font
								(size 1.27 1.27)
							)
						)
					)
					(number "E9"
						(effects
							(font
								(size 1.27 1.27)
							)
						)
					)
				)
				(pin passive line
					(at 0 -16.51 0)
					(length 5.08)
					(hide yes)
					(name "GND"
						(effects
							(font
								(size 1.27 1.27)
							)
						)
					)
					(number "F11"
						(effects
							(font
								(size 1.27 1.27)
							)
						)
					)
				)
				(pin passive line
					(at 0 -16.51 0)
					(length 5.08)
					(hide yes)
					(name "GND"
						(effects
							(font
								(size 1.27 1.27)
							)
						)
					)
					(number "F17"
						(effects
							(font
								(size 1.27 1.27)
							)
						)
					)
				)
				(pin passive line
					(at 0 -16.51 0)
					(length 5.08)
					(hide yes)
					(name "GND"
						(effects
							(font
								(size 1.27 1.27)
							)
						)
					)
					(number "F5"
						(effects
							(font
								(size 1.27 1.27)
							)
						)
					)
				)
				(pin passive line
					(at 0 -16.51 0)
					(length 5.08)
					(hide yes)
					(name "GND"
						(effects
							(font
								(size 1.27 1.27)
							)
						)
					)
					(number "G10"
						(effects
							(font
								(size 1.27 1.27)
							)
						)
					)
				)
				(pin passive line
					(at 0 -16.51 0)
					(length 5.08)
					(hide yes)
					(name "GND"
						(effects
							(font
								(size 1.27 1.27)
							)
						)
					)
					(number "G12"
						(effects
							(font
								(size 1.27 1.27)
							)
						)
					)
				)
				(pin passive line
					(at 0 -16.51 0)
					(length 5.08)
					(hide yes)
					(name "GND"
						(effects
							(font
								(size 1.27 1.27)
							)
						)
					)
					(number "G14"
						(effects
							(font
								(size 1.27 1.27)
							)
						)
					)
				)
				(pin passive line
					(at 0 -16.51 0)
					(length 5.08)
					(hide yes)
					(name "GND"
						(effects
							(font
								(size 1.27 1.27)
							)
						)
					)
					(number "G5"
						(effects
							(font
								(size 1.27 1.27)
							)
						)
					)
				)
				(pin passive line
					(at 0 -16.51 0)
					(length 5.08)
					(hide yes)
					(name "GND"
						(effects
							(font
								(size 1.27 1.27)
							)
						)
					)
					(number "G6"
						(effects
							(font
								(size 1.27 1.27)
							)
						)
					)
				)
				(pin passive line
					(at 0 -16.51 0)
					(length 5.08)
					(hide yes)
					(name "GND"
						(effects
							(font
								(size 1.27 1.27)
							)
						)
					)
					(number "G7"
						(effects
							(font
								(size 1.27 1.27)
							)
						)
					)
				)
				(pin passive line
					(at 0 -16.51 0)
					(length 5.08)
					(hide yes)
					(name "GND"
						(effects
							(font
								(size 1.27 1.27)
							)
						)
					)
					(number "G8"
						(effects
							(font
								(size 1.27 1.27)
							)
						)
					)
				)
				(pin passive line
					(at 0 -16.51 0)
					(length 5.08)
					(hide yes)
					(name "GND"
						(effects
							(font
								(size 1.27 1.27)
							)
						)
					)
					(number "G9"
						(effects
							(font
								(size 1.27 1.27)
							)
						)
					)
				)
				(pin passive line
					(at 0 -16.51 0)
					(length 5.08)
					(hide yes)
					(name "GND"
						(effects
							(font
								(size 1.27 1.27)
							)
						)
					)
					(number "H1"
						(effects
							(font
								(size 1.27 1.27)
							)
						)
					)
				)
				(pin passive line
					(at 0 -16.51 0)
					(length 5.08)
					(hide yes)
					(name "GND"
						(effects
							(font
								(size 1.27 1.27)
							)
						)
					)
					(number "H11"
						(effects
							(font
								(size 1.27 1.27)
							)
						)
					)
				)
				(pin passive line
					(at 0 -16.51 0)
					(length 5.08)
					(hide yes)
					(name "GND"
						(effects
							(font
								(size 1.27 1.27)
							)
						)
					)
					(number "H21"
						(effects
							(font
								(size 1.27 1.27)
							)
						)
					)
				)
				(pin passive line
					(at 0 -16.51 0)
					(length 5.08)
					(hide yes)
					(name "GND"
						(effects
							(font
								(size 1.27 1.27)
							)
						)
					)
					(number "H7"
						(effects
							(font
								(size 1.27 1.27)
							)
						)
					)
				)
				(pin passive line
					(at 0 -16.51 0)
					(length 5.08)
					(hide yes)
					(name "GND"
						(effects
							(font
								(size 1.27 1.27)
							)
						)
					)
					(number "H9"
						(effects
							(font
								(size 1.27 1.27)
							)
						)
					)
				)
				(pin passive line
					(at 0 -16.51 0)
					(length 5.08)
					(hide yes)
					(name "GND"
						(effects
							(font
								(size 1.27 1.27)
							)
						)
					)
					(number "J10"
						(effects
							(font
								(size 1.27 1.27)
							)
						)
					)
				)
				(pin passive line
					(at 0 -16.51 0)
					(length 5.08)
					(hide yes)
					(name "GND"
						(effects
							(font
								(size 1.27 1.27)
							)
						)
					)
					(number "J12"
						(effects
							(font
								(size 1.27 1.27)
							)
						)
					)
				)
				(pin passive line
					(at 0 -16.51 0)
					(length 5.08)
					(hide yes)
					(name "GND"
						(effects
							(font
								(size 1.27 1.27)
							)
						)
					)
					(number "J18"
						(effects
							(font
								(size 1.27 1.27)
							)
						)
					)
				)
				(pin passive line
					(at 0 -16.51 0)
					(length 5.08)
					(hide yes)
					(name "GND"
						(effects
							(font
								(size 1.27 1.27)
							)
						)
					)
					(number "J8"
						(effects
							(font
								(size 1.27 1.27)
							)
						)
					)
				)
				(pin passive line
					(at 0 -16.51 0)
					(length 5.08)
					(hide yes)
					(name "GND"
						(effects
							(font
								(size 1.27 1.27)
							)
						)
					)
					(number "K11"
						(effects
							(font
								(size 1.27 1.27)
							)
						)
					)
				)
				(pin passive line
					(at 0 -16.51 0)
					(length 5.08)
					(hide yes)
					(name "GND"
						(effects
							(font
								(size 1.27 1.27)
							)
						)
					)
					(number "K15"
						(effects
							(font
								(size 1.27 1.27)
							)
						)
					)
				)
				(pin passive line
					(at 0 -16.51 0)
					(length 5.08)
					(hide yes)
					(name "GND"
						(effects
							(font
								(size 1.27 1.27)
							)
						)
					)
					(number "K5"
						(effects
							(font
								(size 1.27 1.27)
							)
						)
					)
				)
				(pin passive line
					(at 0 -16.51 0)
					(length 5.08)
					(hide yes)
					(name "GND"
						(effects
							(font
								(size 1.27 1.27)
							)
						)
					)
					(number "K7"
						(effects
							(font
								(size 1.27 1.27)
							)
						)
					)
				)
				(pin passive line
					(at 0 -16.51 0)
					(length 5.08)
					(hide yes)
					(name "GND"
						(effects
							(font
								(size 1.27 1.27)
							)
						)
					)
					(number "L2"
						(effects
							(font
								(size 1.27 1.27)
							)
						)
					)
				)
				(pin passive line
					(at 0 -16.51 0)
					(length 5.08)
					(hide yes)
					(name "GND"
						(effects
							(font
								(size 1.27 1.27)
							)
						)
					)
					(number "L22"
						(effects
							(font
								(size 1.27 1.27)
							)
						)
					)
				)
				(pin passive line
					(at 0 -16.51 0)
					(length 5.08)
					(hide yes)
					(name "GND"
						(effects
							(font
								(size 1.27 1.27)
							)
						)
					)
					(number "L8"
						(effects
							(font
								(size 1.27 1.27)
							)
						)
					)
				)
				(pin passive line
					(at 0 -16.51 0)
					(length 5.08)
					(hide yes)
					(name "GND"
						(effects
							(font
								(size 1.27 1.27)
							)
						)
					)
					(number "M11"
						(effects
							(font
								(size 1.27 1.27)
							)
						)
					)
				)
				(pin passive line
					(at 0 -16.51 0)
					(length 5.08)
					(hide yes)
					(name "GND"
						(effects
							(font
								(size 1.27 1.27)
							)
						)
					)
					(number "M19"
						(effects
							(font
								(size 1.27 1.27)
							)
						)
					)
				)
				(pin passive line
					(at 0 -16.51 0)
					(length 5.08)
					(hide yes)
					(name "GND"
						(effects
							(font
								(size 1.27 1.27)
							)
						)
					)
					(number "M7"
						(effects
							(font
								(size 1.27 1.27)
							)
						)
					)
				)
				(pin passive line
					(at 0 -16.51 0)
					(length 5.08)
					(hide yes)
					(name "GND"
						(effects
							(font
								(size 1.27 1.27)
							)
						)
					)
					(number "N16"
						(effects
							(font
								(size 1.27 1.27)
							)
						)
					)
				)
				(pin passive line
					(at 0 -16.51 0)
					(length 5.08)
					(hide yes)
					(name "GND"
						(effects
							(font
								(size 1.27 1.27)
							)
						)
					)
					(number "N6"
						(effects
							(font
								(size 1.27 1.27)
							)
						)
					)
				)
				(pin passive line
					(at 0 -16.51 0)
					(length 5.08)
					(hide yes)
					(name "GND"
						(effects
							(font
								(size 1.27 1.27)
							)
						)
					)
					(number "N8"
						(effects
							(font
								(size 1.27 1.27)
							)
						)
					)
				)
				(pin passive line
					(at 0 -16.51 0)
					(length 5.08)
					(hide yes)
					(name "GND"
						(effects
							(font
								(size 1.27 1.27)
							)
						)
					)
					(number "P11"
						(effects
							(font
								(size 1.27 1.27)
							)
						)
					)
				)
				(pin passive line
					(at 0 -16.51 0)
					(length 5.08)
					(hide yes)
					(name "GND"
						(effects
							(font
								(size 1.27 1.27)
							)
						)
					)
					(number "P13"
						(effects
							(font
								(size 1.27 1.27)
							)
						)
					)
				)
				(pin passive line
					(at 0 -16.51 0)
					(length 5.08)
					(hide yes)
					(name "GND"
						(effects
							(font
								(size 1.27 1.27)
							)
						)
					)
					(number "P3"
						(effects
							(font
								(size 1.27 1.27)
							)
						)
					)
				)
				(pin passive line
					(at 0 -16.51 0)
					(length 5.08)
					(hide yes)
					(name "GND"
						(effects
							(font
								(size 1.27 1.27)
							)
						)
					)
					(number "P7"
						(effects
							(font
								(size 1.27 1.27)
							)
						)
					)
				)
				(pin passive line
					(at 0 -16.51 0)
					(length 5.08)
					(hide yes)
					(name "GND"
						(effects
							(font
								(size 1.27 1.27)
							)
						)
					)
					(number "P9"
						(effects
							(font
								(size 1.27 1.27)
							)
						)
					)
				)
				(pin passive line
					(at 0 -16.51 0)
					(length 5.08)
					(hide yes)
					(name "GND"
						(effects
							(font
								(size 1.27 1.27)
							)
						)
					)
					(number "R10"
						(effects
							(font
								(size 1.27 1.27)
							)
						)
					)
				)
				(pin passive line
					(at 0 -16.51 0)
					(length 5.08)
					(hide yes)
					(name "GND"
						(effects
							(font
								(size 1.27 1.27)
							)
						)
					)
					(number "R12"
						(effects
							(font
								(size 1.27 1.27)
							)
						)
					)
				)
				(pin passive line
					(at 0 -16.51 0)
					(length 5.08)
					(hide yes)
					(name "GND"
						(effects
							(font
								(size 1.27 1.27)
							)
						)
					)
					(number "R20"
						(effects
							(font
								(size 1.27 1.27)
							)
						)
					)
				)
				(pin passive line
					(at 0 -16.51 0)
					(length 5.08)
					(hide yes)
					(name "GND"
						(effects
							(font
								(size 1.27 1.27)
							)
						)
					)
					(number "R8"
						(effects
							(font
								(size 1.27 1.27)
							)
						)
					)
				)
				(pin passive line
					(at 0 -16.51 0)
					(length 5.08)
					(hide yes)
					(name "GND"
						(effects
							(font
								(size 1.27 1.27)
							)
						)
					)
					(number "T11"
						(effects
							(font
								(size 1.27 1.27)
							)
						)
					)
				)
				(pin passive line
					(at 0 -16.51 0)
					(length 5.08)
					(hide yes)
					(name "GND"
						(effects
							(font
								(size 1.27 1.27)
							)
						)
					)
					(number "T17"
						(effects
							(font
								(size 1.27 1.27)
							)
						)
					)
				)
				(pin passive line
					(at 0 -16.51 0)
					(length 5.08)
					(hide yes)
					(name "GND"
						(effects
							(font
								(size 1.27 1.27)
							)
						)
					)
					(number "T7"
						(effects
							(font
								(size 1.27 1.27)
							)
						)
					)
				)
				(pin passive line
					(at 0 -16.51 0)
					(length 5.08)
					(hide yes)
					(name "GND"
						(effects
							(font
								(size 1.27 1.27)
							)
						)
					)
					(number "T9"
						(effects
							(font
								(size 1.27 1.27)
							)
						)
					)
				)
				(pin passive line
					(at 0 -16.51 0)
					(length 5.08)
					(hide yes)
					(name "GND"
						(effects
							(font
								(size 1.27 1.27)
							)
						)
					)
					(number "U14"
						(effects
							(font
								(size 1.27 1.27)
							)
						)
					)
				)
				(pin passive line
					(at 0 -16.51 0)
					(length 5.08)
					(hide yes)
					(name "GND"
						(effects
							(font
								(size 1.27 1.27)
							)
						)
					)
					(number "U4"
						(effects
							(font
								(size 1.27 1.27)
							)
						)
					)
				)
				(pin passive line
					(at 0 -16.51 0)
					(length 5.08)
					(hide yes)
					(name "GND"
						(effects
							(font
								(size 1.27 1.27)
							)
						)
					)
					(number "V1"
						(effects
							(font
								(size 1.27 1.27)
							)
						)
					)
				)
				(pin passive line
					(at 0 -16.51 0)
					(length 5.08)
					(hide yes)
					(name "GND"
						(effects
							(font
								(size 1.27 1.27)
							)
						)
					)
					(number "V11"
						(effects
							(font
								(size 1.27 1.27)
							)
						)
					)
				)
				(pin passive line
					(at 0 -16.51 0)
					(length 5.08)
					(hide yes)
					(name "GND"
						(effects
							(font
								(size 1.27 1.27)
							)
						)
					)
					(number "V21"
						(effects
							(font
								(size 1.27 1.27)
							)
						)
					)
				)
				(pin passive line
					(at 0 -16.51 0)
					(length 5.08)
					(hide yes)
					(name "GND"
						(effects
							(font
								(size 1.27 1.27)
							)
						)
					)
					(number "W18"
						(effects
							(font
								(size 1.27 1.27)
							)
						)
					)
				)
				(pin passive line
					(at 0 -16.51 0)
					(length 5.08)
					(hide yes)
					(name "GND"
						(effects
							(font
								(size 1.27 1.27)
							)
						)
					)
					(number "W8"
						(effects
							(font
								(size 1.27 1.27)
							)
						)
					)
				)
				(pin passive line
					(at 0 -16.51 0)
					(length 5.08)
					(hide yes)
					(name "GND"
						(effects
							(font
								(size 1.27 1.27)
							)
						)
					)
					(number "Y15"
						(effects
							(font
								(size 1.27 1.27)
							)
						)
					)
				)
				(pin passive line
					(at 0 -16.51 0)
					(length 5.08)
					(hide yes)
					(name "GND"
						(effects
							(font
								(size 1.27 1.27)
							)
						)
					)
					(number "Y5"
						(effects
							(font
								(size 1.27 1.27)
							)
						)
					)
				)
			)
		)
	(symbol "antmicroFerriteBeadsandChips:FB_120Z_2A_Murata-BLM18PG_0603"
			(pin_numbers
				(hide yes)
			)
			(pin_names
				(hide yes)
			)
			(exclude_from_sim no)
			(in_bom yes)
			(on_board yes)
			(property "Reference" "FB"
				(at 15.24 0 0)
				(effects
					(font
						(size 1.27 1.27)
						(thickness 0.15)
					)
					(justify left bottom)
				)
			)
			(property "Value" "FB_120Z_2A_Murata-BLM18PG_0603"
				(at 15.24 -2.54 0)
				(effects
					(font
						(size 1.27 1.27)
						(thickness 0.15)
					)
					(justify left bottom)
					(hide yes)
				)
			)
			(property "Footprint" "antmicro-footprints:FB_0603_1608Metric"
				(at 15.24 -7.62 0)
				(effects
					(font
						(size 1.27 1.27)
						(thickness 0.15)
					)
					(justify left bottom)
					(hide yes)
				)
			)
			(property "Datasheet" "https://www.murata.com/en-us/products/productdata/8796738650142/ENFA0003.pdf"
				(at 15.24 -10.16 0)
				(effects
					(font
						(size 1.27 1.27)
						(thickness 0.15)
					)
					(justify left bottom)
					(hide yes)
				)
			)
			(property "Description" "Ferrite Bead, 0603 [1608 Metric], 120 ohm, 2 A, BLM18P, 0.05 ohm, ± 25%, DC power line"
				(at 15.24 -22.86 0)
				(effects
					(font
						(size 1.27 1.27)
					)
					(justify left bottom)
					(hide yes)
				)
			)
			(property "Val" "120Z/2A"
				(at 15.24 -5.08 0)
				(effects
					(font
						(size 1.27 1.27)
					)
					(justify left bottom)
				)
			)
			(property "MPN" "BLM18PG121SN1D"
				(at 15.24 -12.7 0)
				(effects
					(font
						(size 1.27 1.27)
						(thickness 0.15)
					)
					(justify left bottom)
					(hide yes)
				)
			)
			(property "Manufacturer" "Murata"
				(at 15.24 -15.24 0)
				(effects
					(font
						(size 1.27 1.27)
						(thickness 0.15)
					)
					(justify left bottom)
					(hide yes)
				)
			)
			(property "Current" ""
				(at 20.32 -22.86 0)
				(effects
					(font
						(size 1.27 1.27)
						(thickness 0.15)
					)
					(justify left bottom)
					(hide yes)
				)
			)
			(property "Author" "Antmicro"
				(at 15.24 -17.78 0)
				(effects
					(font
						(size 1.27 1.27)
						(thickness 0.15)
					)
					(justify left bottom)
					(hide yes)
				)
			)
			(property "License" "Apache-2.0"
				(at 15.24 -20.32 0)
				(effects
					(font
						(size 1.27 1.27)
						(thickness 0.15)
					)
					(justify left bottom)
					(hide yes)
				)
			)
			(property "ki_keywords" "0603, SMT, FERRITE BEAD, PASSIVE"
				(at 0 0 0)
				(effects
					(font
						(size 1.27 1.27)
					)
					(hide yes)
				)
			)
			(symbol "FB_120Z_2A_Murata-BLM18PG_0603_0_1"
				(polyline
					(pts
						(xy 1.651 0) (xy 1.2446 0)
					)
					(stroke
						(width 0)
						(type default)
					)
					(fill
						(type none)
					)
				)
				(polyline
					(pts
						(xy 2.2606 -1.8288) (xy 1.0414 -1.1176) (xy 2.7432 1.8288) (xy 3.9624 1.1176) (xy 2.2606 -1.8288)
					)
					(stroke
						(width 0)
						(type default)
					)
					(fill
						(type none)
					)
				)
				(polyline
					(pts
						(xy 3.81 0) (xy 3.3274 0)
					)
					(stroke
						(width 0)
						(type default)
					)
					(fill
						(type none)
					)
				)
			)
			(symbol "FB_120Z_2A_Murata-BLM18PG_0603_1_1"
				(pin passive line
					(at 0 0 0)
					(length 1.27)
					(name "~"
						(effects
							(font
								(size 1.27 1.27)
							)
						)
					)
					(number "1"
						(effects
							(font
								(size 1.27 1.27)
							)
						)
					)
				)
				(pin passive line
					(at 5.08 0 180)
					(length 1.27)
					(name "~"
						(effects
							(font
								(size 1.27 1.27)
							)
						)
					)
					(number "2"
						(effects
							(font
								(size 1.27 1.27)
							)
						)
					)
				)
			)
		)
	(symbol "antmicroFerriteBeadsandChips:FB_600Z_0.3A_Murata-BLM15AG_0402"
			(pin_numbers
				(hide yes)
			)
			(pin_names
				(hide yes)
			)
			(exclude_from_sim no)
			(in_bom yes)
			(on_board yes)
			(property "Reference" "FB"
				(at 15.24 0 0)
				(effects
					(font
						(size 1.27 1.27)
						(thickness 0.15)
					)
					(justify left bottom)
				)
			)
			(property "Value" "FB_600Z_0.3A_Murata-BLM15AG_0402"
				(at 15.24 -2.54 0)
				(effects
					(font
						(size 1.27 1.27)
						(thickness 0.15)
					)
					(justify left bottom)
					(hide yes)
				)
			)
			(property "Footprint" "antmicro-footprints:FB_0402_1005Metric"
				(at 15.24 -7.62 0)
				(effects
					(font
						(size 1.27 1.27)
						(thickness 0.15)
					)
					(justify left bottom)
					(hide yes)
				)
			)
			(property "Datasheet" "https://www.murata.com/en-us/products/productdata/8796740059166/ENFA0018.pdf"
				(at 15.24 -10.16 0)
				(effects
					(font
						(size 1.27 1.27)
						(thickness 0.15)
					)
					(justify left bottom)
					(hide yes)
				)
			)
			(property "Description" "Ferrite Bead, 0402 [1005 Metric], 600 ohm, 300 mA, BLM15AG_SN, 0.6 ohm, ± 25%, General use"
				(at 15.24 -22.86 0)
				(effects
					(font
						(size 1.27 1.27)
					)
					(justify left bottom)
					(hide yes)
				)
			)
			(property "Val" "600Z/0.3A"
				(at 15.24 -5.08 0)
				(effects
					(font
						(size 1.27 1.27)
					)
					(justify left bottom)
				)
			)
			(property "MPN" "BLM15AG601SN1D"
				(at 15.24 -12.7 0)
				(effects
					(font
						(size 1.27 1.27)
						(thickness 0.15)
					)
					(justify left bottom)
					(hide yes)
				)
			)
			(property "Manufacturer" "Murata"
				(at 15.24 -15.24 0)
				(effects
					(font
						(size 1.27 1.27)
						(thickness 0.15)
					)
					(justify left bottom)
					(hide yes)
				)
			)
			(property "Current" ""
				(at 20.32 -22.86 0)
				(effects
					(font
						(size 1.27 1.27)
						(thickness 0.15)
					)
					(justify left bottom)
					(hide yes)
				)
			)
			(property "Author" "Antmicro"
				(at 15.24 -17.78 0)
				(effects
					(font
						(size 1.27 1.27)
						(thickness 0.15)
					)
					(justify left bottom)
					(hide yes)
				)
			)
			(property "License" "Apache-2.0"
				(at 15.24 -20.32 0)
				(effects
					(font
						(size 1.27 1.27)
						(thickness 0.15)
					)
					(justify left bottom)
					(hide yes)
				)
			)
			(property "ki_keywords" "0402, SMT, FERRITE BEAD, PASSIVE"
				(at 0 0 0)
				(effects
					(font
						(size 1.27 1.27)
					)
					(hide yes)
				)
			)
			(symbol "FB_600Z_0.3A_Murata-BLM15AG_0402_0_1"
				(polyline
					(pts
						(xy 1.651 0) (xy 1.2446 0)
					)
					(stroke
						(width 0)
						(type default)
					)
					(fill
						(type none)
					)
				)
				(polyline
					(pts
						(xy 2.2606 -1.8288) (xy 1.0414 -1.1176) (xy 2.7432 1.8288) (xy 3.9624 1.1176) (xy 2.2606 -1.8288)
					)
					(stroke
						(width 0)
						(type default)
					)
					(fill
						(type none)
					)
				)
				(polyline
					(pts
						(xy 3.81 0) (xy 3.3274 0)
					)
					(stroke
						(width 0)
						(type default)
					)
					(fill
						(type none)
					)
				)
			)
			(symbol "FB_600Z_0.3A_Murata-BLM15AG_0402_1_1"
				(pin passive line
					(at 0 0 0)
					(length 1.27)
					(name "~"
						(effects
							(font
								(size 1.27 1.27)
							)
						)
					)
					(number "1"
						(effects
							(font
								(size 1.27 1.27)
							)
						)
					)
				)
				(pin passive line
					(at 5.08 0 180)
					(length 1.27)
					(name "~"
						(effects
							(font
								(size 1.27 1.27)
							)
						)
					)
					(number "2"
						(effects
							(font
								(size 1.27 1.27)
							)
						)
					)
				)
			)
		)
	(symbol "antmicroFixedInductors:L_470n_6.7A_Vishay-IHLP-1212AE-11"
			(pin_numbers
				(hide yes)
			)
			(pin_names
				(hide yes)
			)
			(exclude_from_sim no)
			(in_bom yes)
			(on_board yes)
			(property "Reference" "L"
				(at 13.97 0 0)
				(effects
					(font
						(size 1.27 1.27)
						(thickness 0.15)
					)
					(justify left bottom)
				)
			)
			(property "Value" "L_470n_6.7A_Vishay-IHLP-1212AE-11"
				(at 13.97 -2.54 0)
				(effects
					(font
						(size 1.27 1.27)
						(thickness 0.15)
					)
					(justify left bottom)
					(hide yes)
				)
			)
			(property "Footprint" "antmicro-footprints:L_Vishay-IHLP-1212AE"
				(at 13.97 -7.62 0)
				(effects
					(font
						(size 1.27 1.27)
						(thickness 0.15)
					)
					(justify left bottom)
					(hide yes)
				)
			)
			(property "Datasheet" "https://www.vishay.com/docs/34300/ihlp-1212ae-11.pdf"
				(at 13.97 -10.16 0)
				(effects
					(font
						(size 1.27 1.27)
						(thickness 0.15)
					)
					(justify left bottom)
					(hide yes)
				)
			)
			(property "Description" "Power Inductor (SMT), 470 nH, 6.7 A, Shielded, 6.7 A"
				(at 13.97 -30.48 0)
				(effects
					(font
						(size 1.27 1.27)
					)
					(justify left bottom)
					(hide yes)
				)
			)
			(property "Val" "470n/6.7A"
				(at 13.97 -5.08 0)
				(effects
					(font
						(size 1.27 1.27)
						(thickness 0.15)
					)
					(justify left bottom)
				)
			)
			(property "Manufacturer" "Vishay"
				(at 13.97 -12.7 0)
				(effects
					(font
						(size 1.27 1.27)
						(thickness 0.15)
					)
					(justify left bottom)
					(hide yes)
				)
			)
			(property "MPN" "IHLP1212AEERR47M11"
				(at 13.97 -15.24 0)
				(effects
					(font
						(size 1.27 1.27)
						(thickness 0.15)
					)
					(justify left bottom)
					(hide yes)
				)
			)
			(property "ISat" "6.7 A"
				(at 13.97 -16.51 0)
				(effects
					(font
						(size 1.27 1.27)
					)
					(justify left)
					(hide yes)
				)
			)
			(property "IMax" "6.7 A"
				(at 13.97 -20.32 0)
				(effects
					(font
						(size 1.27 1.27)
						(thickness 0.15)
					)
					(justify left bottom)
					(hide yes)
				)
			)
			(property "Size" "3.0x3.0"
				(at 13.97 -22.86 0)
				(effects
					(font
						(size 1.27 1.27)
						(thickness 0.15)
					)
					(justify left bottom)
					(hide yes)
				)
			)
			(property "Author" "Antmicro"
				(at 13.97 -25.4 0)
				(effects
					(font
						(size 1.27 1.27)
						(thickness 0.15)
					)
					(justify left bottom)
					(hide yes)
				)
			)
			(property "License" "Apache-2.0"
				(at 13.97 -27.94 0)
				(effects
					(font
						(size 1.27 1.27)
						(thickness 0.15)
					)
					(justify left bottom)
					(hide yes)
				)
			)
			(property "ki_keywords" "SMT, INDUCTOR, PASSIVE"
				(at 0 0 0)
				(effects
					(font
						(size 1.27 1.27)
					)
					(hide yes)
				)
			)
			(symbol "L_470n_6.7A_Vishay-IHLP-1212AE-11_0_1"
				(arc
					(start 0.508 0)
					(mid 1.016 0.5058)
					(end 1.524 0)
					(stroke
						(width 0)
						(type default)
					)
					(fill
						(type none)
					)
				)
				(arc
					(start 1.524 0)
					(mid 2.032 0.5058)
					(end 2.54 0)
					(stroke
						(width 0)
						(type default)
					)
					(fill
						(type none)
					)
				)
				(arc
					(start 2.54 0)
					(mid 3.048 0.5058)
					(end 3.556 0)
					(stroke
						(width 0)
						(type default)
					)
					(fill
						(type none)
					)
				)
				(arc
					(start 3.556 0)
					(mid 4.064 0.5058)
					(end 4.572 0)
					(stroke
						(width 0)
						(type default)
					)
					(fill
						(type none)
					)
				)
			)
			(symbol "L_470n_6.7A_Vishay-IHLP-1212AE-11_1_1"
				(pin passive line
					(at 0 0 0)
					(length 0.508)
					(name "~"
						(effects
							(font
								(size 1.27 1.27)
							)
						)
					)
					(number "1"
						(effects
							(font
								(size 1.27 1.27)
							)
						)
					)
				)
				(pin passive line
					(at 5.08 0 180)
					(length 0.508)
					(name "~"
						(effects
							(font
								(size 1.27 1.27)
							)
						)
					)
					(number "2"
						(effects
							(font
								(size 1.27 1.27)
							)
						)
					)
				)
			)
		)
	(symbol "antmicroFixedInductors:L_7u2_7.9A_WE-PDF-1064"
			(pin_numbers
				(hide yes)
			)
			(pin_names
				(hide yes)
			)
			(exclude_from_sim no)
			(in_bom yes)
			(on_board yes)
			(property "Reference" "L"
				(at 13.97 0 0)
				(effects
					(font
						(size 1.27 1.27)
						(thickness 0.15)
					)
					(justify left bottom)
				)
			)
			(property "Value" "L_7u2_7.9A_WE-PDF-1064"
				(at 13.97 -2.54 0)
				(effects
					(font
						(size 1.27 1.27)
						(thickness 0.15)
					)
					(justify left bottom)
					(hide yes)
				)
			)
			(property "Footprint" "antmicro-footprints:L_WE-PDF-1064"
				(at 13.97 -7.62 0)
				(effects
					(font
						(size 1.27 1.27)
						(thickness 0.15)
					)
					(justify left bottom)
					(hide yes)
				)
			)
			(property "Datasheet" "https://www.we-online.com/catalog/datasheet/7447798720.pdf"
				(at 13.97 -10.16 0)
				(effects
					(font
						(size 1.27 1.27)
						(thickness 0.15)
					)
					(justify left bottom)
					(hide yes)
				)
			)
			(property "Description" "Power Inductor (SMD), 7.2 µH, 7.9 A, Shielded, 6 A, WE-PDF"
				(at 13.97 -30.48 0)
				(effects
					(font
						(size 1.27 1.27)
					)
					(justify left bottom)
					(hide yes)
				)
			)
			(property "Val" "7u2/7.9A"
				(at 13.97 -5.08 0)
				(effects
					(font
						(size 1.27 1.27)
						(thickness 0.15)
					)
					(justify left bottom)
				)
			)
			(property "Manufacturer" "Würth Elektronik"
				(at 13.97 -12.7 0)
				(effects
					(font
						(size 1.27 1.27)
						(thickness 0.15)
					)
					(justify left bottom)
					(hide yes)
				)
			)
			(property "MPN" "7447798720"
				(at 13.97 -15.24 0)
				(effects
					(font
						(size 1.27 1.27)
						(thickness 0.15)
					)
					(justify left bottom)
					(hide yes)
				)
			)
			(property "ISat" "6 A"
				(at 13.97 -16.51 0)
				(effects
					(font
						(size 1.27 1.27)
					)
					(justify left)
					(hide yes)
				)
			)
			(property "IMax" "7.9 A"
				(at 13.97 -20.32 0)
				(effects
					(font
						(size 1.27 1.27)
						(thickness 0.15)
					)
					(justify left bottom)
					(hide yes)
				)
			)
			(property "Size" "10.2x10.2"
				(at 13.97 -22.86 0)
				(effects
					(font
						(size 1.27 1.27)
						(thickness 0.15)
					)
					(justify left bottom)
					(hide yes)
				)
			)
			(property "Author" "Antmicro"
				(at 13.97 -25.4 0)
				(effects
					(font
						(size 1.27 1.27)
						(thickness 0.15)
					)
					(justify left bottom)
					(hide yes)
				)
			)
			(property "License" "Apache-2.0"
				(at 13.97 -27.94 0)
				(effects
					(font
						(size 1.27 1.27)
						(thickness 0.15)
					)
					(justify left bottom)
					(hide yes)
				)
			)
			(property "ki_keywords" "INDUCTOR, PASSIVE, SMT"
				(at 0 0 0)
				(effects
					(font
						(size 1.27 1.27)
					)
					(hide yes)
				)
			)
			(symbol "L_7u2_7.9A_WE-PDF-1064_0_1"
				(arc
					(start 0.508 0)
					(mid 1.016 0.5058)
					(end 1.524 0)
					(stroke
						(width 0)
						(type default)
					)
					(fill
						(type none)
					)
				)
				(arc
					(start 1.524 0)
					(mid 2.032 0.5058)
					(end 2.54 0)
					(stroke
						(width 0)
						(type default)
					)
					(fill
						(type none)
					)
				)
				(arc
					(start 2.54 0)
					(mid 3.048 0.5058)
					(end 3.556 0)
					(stroke
						(width 0)
						(type default)
					)
					(fill
						(type none)
					)
				)
				(arc
					(start 3.556 0)
					(mid 4.064 0.5058)
					(end 4.572 0)
					(stroke
						(width 0)
						(type default)
					)
					(fill
						(type none)
					)
				)
			)
			(symbol "L_7u2_7.9A_WE-PDF-1064_1_1"
				(pin passive line
					(at 0 0 0)
					(length 0.508)
					(name "~"
						(effects
							(font
								(size 1.27 1.27)
							)
						)
					)
					(number "1"
						(effects
							(font
								(size 1.27 1.27)
							)
						)
					)
				)
				(pin passive line
					(at 5.08 0 180)
					(length 0.508)
					(name "~"
						(effects
							(font
								(size 1.27 1.27)
							)
						)
					)
					(number "2"
						(effects
							(font
								(size 1.27 1.27)
							)
						)
					)
				)
			)
		)
	(symbol "antmicroFuses:F_3A_1206"
			(pin_numbers
				(hide yes)
			)
			(pin_names
				(offset 0.9906)
				(hide yes)
			)
			(exclude_from_sim no)
			(in_bom yes)
			(on_board yes)
			(property "Reference" "F"
				(at 20.32 -5.08 0)
				(effects
					(font
						(size 1.27 1.27)
						(thickness 0.15)
					)
					(justify left bottom)
				)
			)
			(property "Value" "F_3A_1206"
				(at 20.32 -7.62 0)
				(effects
					(font
						(size 1.27 1.27)
						(thickness 0.15)
					)
					(justify left bottom)
					(hide yes)
				)
			)
			(property "Footprint" "antmicro-footprints:F_1206_3216Metric"
				(at 20.32 -10.16 0)
				(effects
					(font
						(size 1.27 1.27)
						(thickness 0.15)
					)
					(justify left bottom)
					(hide yes)
				)
			)
			(property "Datasheet" "https://www.littelfuse.com/~/media/electronics/datasheets/fuses/littelfuse_fuse_466_datasheet.pdf.pdf"
				(at 20.32 -12.7 0)
				(effects
					(font
						(size 1.27 1.27)
						(thickness 0.15)
					)
					(justify left bottom)
					(hide yes)
				)
			)
			(property "Description" "Fuse, Surface Mount, 3 A, Very Fast Acting, 32 V, 32 V, 1206 (3216 Metric), 466"
				(at 20.32 -25.4 0)
				(effects
					(font
						(size 1.27 1.27)
					)
					(justify left bottom)
					(hide yes)
				)
			)
			(property "Manufacturer" "Littelfuse"
				(at 20.32 -15.24 0)
				(effects
					(font
						(size 1.27 1.27)
						(thickness 0.15)
					)
					(justify left bottom)
					(hide yes)
				)
			)
			(property "MPN" "0466003.NR "
				(at 20.32 -17.78 0)
				(effects
					(font
						(size 1.27 1.27)
						(thickness 0.15)
					)
					(justify left bottom)
				)
			)
			(property "Author" "Antmicro"
				(at 20.32 -20.32 0)
				(effects
					(font
						(size 1.27 1.27)
						(thickness 0.15)
					)
					(justify left bottom)
					(hide yes)
				)
			)
			(property "License" "Apache-2.0"
				(at 20.32 -22.86 0)
				(effects
					(font
						(size 1.27 1.27)
						(thickness 0.15)
					)
					(justify left bottom)
					(hide yes)
				)
			)
			(property "ki_keywords" "FUSE, PASSIVE"
				(at 0 0 0)
				(effects
					(font
						(size 1.27 1.27)
					)
					(hide yes)
				)
			)
			(symbol "F_3A_1206_0_1"
				(rectangle
					(start 1.27 0.508)
					(end 3.81 -0.508)
					(stroke
						(width 0)
						(type default)
					)
					(fill
						(type none)
					)
				)
				(polyline
					(pts
						(xy 1.27 0) (xy 3.81 0)
					)
					(stroke
						(width 0)
						(type default)
					)
					(fill
						(type none)
					)
				)
			)
			(symbol "F_3A_1206_1_1"
				(pin passive line
					(at 0 0 0)
					(length 1.27)
					(name "~"
						(effects
							(font
								(size 1.27 1.27)
							)
						)
					)
					(number "1"
						(effects
							(font
								(size 1.27 1.27)
							)
						)
					)
				)
				(pin passive line
					(at 5.08 0 180)
					(length 1.27)
					(name "~"
						(effects
							(font
								(size 1.27 1.27)
							)
						)
					)
					(number "2"
						(effects
							(font
								(size 1.27 1.27)
							)
						)
					)
				)
			)
		)
	(symbol "antmicroGenericPinHeaders:PinHeader_1x3_P2.54mm_Drill1.1mm"
			(exclude_from_sim no)
			(in_bom yes)
			(on_board yes)
			(property "Reference" "J"
				(at 20.32 -5.08 0)
				(effects
					(font
						(size 1.27 1.27)
						(thickness 0.15)
					)
					(justify left bottom)
				)
			)
			(property "Value" "PinHeader_1x3_P2.54mm_Drill1.1mm"
				(at 20.32 -10.16 0)
				(effects
					(font
						(size 1.27 1.27)
						(thickness 0.15)
					)
					(justify left bottom)
					(hide yes)
				)
			)
			(property "Footprint" "antmicro-footprints:PinHeader_1x3_P2.54mm_Drill1.1mm"
				(at 20.32 -12.7 0)
				(effects
					(font
						(size 1.27 1.27)
						(thickness 0.15)
					)
					(justify left bottom)
					(hide yes)
				)
			)
			(property "Datasheet" "https://katalog.we-online.de/em/datasheet/6130xx11121.pdf"
				(at 20.32 -15.24 0)
				(effects
					(font
						(size 1.27 1.27)
						(thickness 0.15)
					)
					(justify left bottom)
					(hide yes)
				)
			)
			(property "Description" "Pin Header, Vertical, Board-to-Board, 2.54 mm, 1 Rows, 3 Contacts, Through Hole Straight, WR-PHD"
				(at 20.32 -25.4 0)
				(effects
					(font
						(size 1.27 1.27)
					)
					(justify left bottom)
					(hide yes)
				)
			)
			(property "MPN" "61300311121"
				(at 20.32 -7.62 0)
				(effects
					(font
						(size 1.27 1.27)
						(thickness 0.15)
					)
					(justify left bottom)
				)
			)
			(property "Manufacturer" "Würth Elektronik"
				(at 20.32 -17.78 0)
				(effects
					(font
						(size 1.27 1.27)
						(thickness 0.15)
					)
					(justify left bottom)
					(hide yes)
				)
			)
			(property "Author" "Antmicro"
				(at 20.32 -20.32 0)
				(effects
					(font
						(size 1.27 1.27)
						(thickness 0.15)
					)
					(justify left bottom)
					(hide yes)
				)
			)
			(property "License" "Apache-2.0"
				(at 20.32 -22.86 0)
				(effects
					(font
						(size 1.27 1.27)
						(thickness 0.15)
					)
					(justify left bottom)
					(hide yes)
				)
			)
			(property "ki_keywords" "VERTICAL, THT, HEADER, CONNECTOR, MALE"
				(at 0 0 0)
				(effects
					(font
						(size 1.27 1.27)
					)
					(hide yes)
				)
			)
			(symbol "PinHeader_1x3_P2.54mm_Drill1.1mm_1_1"
				(rectangle
					(start 2.54 2.54)
					(end 5.08 -7.62)
					(stroke
						(width 0.254)
						(type default)
					)
					(fill
						(type background)
					)
				)
				(rectangle
					(start 4.191 -0.254)
					(end 3.683 0.254)
					(stroke
						(width 0.254)
						(type default)
					)
					(fill
						(type none)
					)
				)
				(rectangle
					(start 4.191 -2.794)
					(end 3.683 -2.286)
					(stroke
						(width 0.254)
						(type default)
					)
					(fill
						(type none)
					)
				)
				(rectangle
					(start 4.191 -5.334)
					(end 3.683 -4.826)
					(stroke
						(width 0.254)
						(type default)
					)
					(fill
						(type none)
					)
				)
				(pin passive line
					(at 0 0 0)
					(length 2.54)
					(name "~"
						(effects
							(font
								(size 1.27 1.27)
							)
						)
					)
					(number "1"
						(effects
							(font
								(size 1.27 1.27)
							)
						)
					)
				)
				(pin passive line
					(at 0 -2.54 0)
					(length 2.54)
					(name "~"
						(effects
							(font
								(size 1.27 1.27)
							)
						)
					)
					(number "2"
						(effects
							(font
								(size 1.27 1.27)
							)
						)
					)
				)
				(pin passive line
					(at 0 -5.08 0)
					(length 2.54)
					(name "~"
						(effects
							(font
								(size 1.27 1.27)
							)
						)
					)
					(number "3"
						(effects
							(font
								(size 1.27 1.27)
							)
						)
					)
				)
			)
		)
	(symbol "antmicroGenericPinHeaders:PinHeader_1x6_P2.54mm_Drill1.1mm"
			(exclude_from_sim no)
			(in_bom yes)
			(on_board yes)
			(property "Reference" "J"
				(at 20.32 -5.08 0)
				(effects
					(font
						(size 1.27 1.27)
						(thickness 0.15)
					)
					(justify left bottom)
				)
			)
			(property "Value" "PinHeader_1x6_P2.54mm_Drill1.1mm"
				(at 20.32 -7.62 0)
				(effects
					(font
						(size 1.27 1.27)
						(thickness 0.15)
					)
					(justify left bottom)
					(hide yes)
				)
			)
			(property "Footprint" "antmicro-footprints:PinHeader_1x6_P2.54mm_Drill1.1mm"
				(at 20.32 -10.16 0)
				(effects
					(font
						(size 1.27 1.27)
						(thickness 0.15)
					)
					(justify left bottom)
					(hide yes)
				)
			)
			(property "Datasheet" "https://www.we-online.com/components/products/datasheet/61300611121.pdf"
				(at 20.32 -12.7 0)
				(effects
					(font
						(size 1.27 1.27)
						(thickness 0.15)
					)
					(justify left bottom)
					(hide yes)
				)
			)
			(property "Description" "Pin Header, Vertical, Board-to-Board, 2.54 mm, 1 Rows, 6 Contacts, Through Hole Straight, WR-PHD"
				(at 20.32 -25.4 0)
				(effects
					(font
						(size 1.27 1.27)
					)
					(justify left bottom)
					(hide yes)
				)
			)
			(property "MPN" "61300611121"
				(at 20.32 -15.24 0)
				(effects
					(font
						(size 1.27 1.27)
						(thickness 0.15)
					)
					(justify left bottom)
				)
			)
			(property "Manufacturer" "Würth Elektronik"
				(at 20.32 -17.78 0)
				(effects
					(font
						(size 1.27 1.27)
						(thickness 0.15)
					)
					(justify left bottom)
					(hide yes)
				)
			)
			(property "Author" "Antmicro"
				(at 20.32 -20.32 0)
				(effects
					(font
						(size 1.27 1.27)
						(thickness 0.15)
					)
					(justify left bottom)
					(hide yes)
				)
			)
			(property "License" "Apache-2.0"
				(at 20.32 -22.86 0)
				(effects
					(font
						(size 1.27 1.27)
						(thickness 0.15)
					)
					(justify left bottom)
					(hide yes)
				)
			)
			(property "ki_keywords" "VERTICAL, THT, HEADER, CONNECTOR, MALE"
				(at 0 0 0)
				(effects
					(font
						(size 1.27 1.27)
					)
					(hide yes)
				)
			)
			(symbol "PinHeader_1x6_P2.54mm_Drill1.1mm_1_1"
				(rectangle
					(start 4.191 -0.254)
					(end 3.683 0.254)
					(stroke
						(width 0.254)
						(type default)
					)
					(fill
						(type outline)
					)
				)
				(rectangle
					(start 4.191 -2.794)
					(end 3.683 -2.286)
					(stroke
						(width 0.254)
						(type default)
					)
					(fill
						(type outline)
					)
				)
				(rectangle
					(start 4.191 -5.334)
					(end 3.683 -4.826)
					(stroke
						(width 0.254)
						(type default)
					)
					(fill
						(type outline)
					)
				)
				(rectangle
					(start 4.191 -7.874)
					(end 3.683 -7.366)
					(stroke
						(width 0.254)
						(type default)
					)
					(fill
						(type outline)
					)
				)
				(rectangle
					(start 4.191 -10.414)
					(end 3.683 -9.906)
					(stroke
						(width 0.254)
						(type default)
					)
					(fill
						(type outline)
					)
				)
				(rectangle
					(start 4.191 -12.954)
					(end 3.683 -12.446)
					(stroke
						(width 0.254)
						(type default)
					)
					(fill
						(type outline)
					)
				)
				(rectangle
					(start 5.08 -13.97)
					(end 2.54 1.27)
					(stroke
						(width 0.254)
						(type default)
					)
					(fill
						(type background)
					)
				)
				(pin passive line
					(at 0 0 0)
					(length 2.54)
					(name "~"
						(effects
							(font
								(size 1.27 1.27)
							)
						)
					)
					(number "1"
						(effects
							(font
								(size 1.27 1.27)
							)
						)
					)
				)
				(pin passive line
					(at 0 -2.54 0)
					(length 2.54)
					(name "~"
						(effects
							(font
								(size 1.27 1.27)
							)
						)
					)
					(number "2"
						(effects
							(font
								(size 1.27 1.27)
							)
						)
					)
				)
				(pin passive line
					(at 0 -5.08 0)
					(length 2.54)
					(name "~"
						(effects
							(font
								(size 1.27 1.27)
							)
						)
					)
					(number "3"
						(effects
							(font
								(size 1.27 1.27)
							)
						)
					)
				)
				(pin passive line
					(at 0 -7.62 0)
					(length 2.54)
					(name "~"
						(effects
							(font
								(size 1.27 1.27)
							)
						)
					)
					(number "4"
						(effects
							(font
								(size 1.27 1.27)
							)
						)
					)
				)
				(pin passive line
					(at 0 -10.16 0)
					(length 2.54)
					(name "~"
						(effects
							(font
								(size 1.27 1.27)
							)
						)
					)
					(number "5"
						(effects
							(font
								(size 1.27 1.27)
							)
						)
					)
				)
				(pin passive line
					(at 0 -12.7 0)
					(length 2.54)
					(name "~"
						(effects
							(font
								(size 1.27 1.27)
							)
						)
					)
					(number "6"
						(effects
							(font
								(size 1.27 1.27)
							)
						)
					)
				)
			)
		)
	(symbol "antmicroGenericPinHeaders:PinHeader_2x7_P2mm_Drill0.9mm_878311420"
			(exclude_from_sim no)
			(in_bom yes)
			(on_board yes)
			(property "Reference" "J"
				(at 25.4 -2.54 0)
				(effects
					(font
						(size 1.27 1.27)
						(thickness 0.15)
					)
					(justify left bottom)
				)
			)
			(property "Value" "PinHeader_2x7_P2mm_Drill0.9mm_878311420"
				(at 25.4 -5.08 0)
				(effects
					(font
						(size 1.27 1.27)
						(thickness 0.15)
					)
					(justify left bottom)
					(hide yes)
				)
			)
			(property "Footprint" "antmicro-footprints:PinHeader_2x7_P2mm_Drill0.9mm_878311420"
				(at 25.4 -7.62 0)
				(effects
					(font
						(size 1.27 1.27)
						(thickness 0.15)
					)
					(justify left bottom)
					(hide yes)
				)
			)
			(property "Datasheet" "https://www.molex.com/en-us/products/part-detail-pdf/878311420?display=pdf"
				(at 25.4 -10.16 0)
				(effects
					(font
						(size 1.27 1.27)
						(thickness 0.15)
					)
					(justify left bottom)
					(hide yes)
				)
			)
			(property "Description" "2.00mm Pitch, Milli-Grid PCB Header, Dual Row, Vertical, Through Hole, Shrouded, 14 Circuits, 0.38µm Gold (Au) Plating, with Center Polarization Slot, with Locking Window, without PCB Locator, Tube"
				(at 25.4 -22.86 0)
				(effects
					(font
						(size 1.27 1.27)
					)
					(justify left bottom)
					(hide yes)
				)
			)
			(property "MPN" "878311420"
				(at 25.4 -12.7 0)
				(effects
					(font
						(size 1.27 1.27)
						(thickness 0.15)
					)
					(justify left bottom)
				)
			)
			(property "Manufacturer" "Molex"
				(at 25.4 -15.24 0)
				(effects
					(font
						(size 1.27 1.27)
						(thickness 0.15)
					)
					(justify left bottom)
					(hide yes)
				)
			)
			(property "Author" "Antmicro"
				(at 25.4 -17.78 0)
				(effects
					(font
						(size 1.27 1.27)
						(thickness 0.15)
					)
					(justify left bottom)
					(hide yes)
				)
			)
			(property "License" "Apache-2.0"
				(at 25.4 -20.32 0)
				(effects
					(font
						(size 1.27 1.27)
						(thickness 0.15)
					)
					(justify left bottom)
					(hide yes)
				)
			)
			(property "ki_keywords" "PINSTRIP, HEADER "
				(at 0 0 0)
				(effects
					(font
						(size 1.27 1.27)
					)
					(hide yes)
				)
			)
			(symbol "PinHeader_2x7_P2mm_Drill0.9mm_878311420_1_1"
				(rectangle
					(start 2.54 1.27)
					(end 7.62 -16.51)
					(stroke
						(width 0.254)
						(type default)
					)
					(fill
						(type background)
					)
				)
				(rectangle
					(start 3.556 0.254)
					(end 4.064 -0.254)
					(stroke
						(width 0.254)
						(type default)
					)
					(fill
						(type background)
					)
				)
				(rectangle
					(start 3.556 -2.286)
					(end 4.064 -2.794)
					(stroke
						(width 0.254)
						(type default)
					)
					(fill
						(type background)
					)
				)
				(rectangle
					(start 3.556 -4.826)
					(end 4.064 -5.334)
					(stroke
						(width 0.254)
						(type default)
					)
					(fill
						(type background)
					)
				)
				(rectangle
					(start 3.556 -7.366)
					(end 4.064 -7.874)
					(stroke
						(width 0.254)
						(type default)
					)
					(fill
						(type background)
					)
				)
				(rectangle
					(start 3.556 -9.906)
					(end 4.064 -10.414)
					(stroke
						(width 0.254)
						(type default)
					)
					(fill
						(type background)
					)
				)
				(rectangle
					(start 3.556 -12.446)
					(end 4.064 -12.954)
					(stroke
						(width 0.254)
						(type default)
					)
					(fill
						(type background)
					)
				)
				(rectangle
					(start 3.556 -14.986)
					(end 4.064 -15.494)
					(stroke
						(width 0.254)
						(type default)
					)
					(fill
						(type background)
					)
				)
				(rectangle
					(start 6.096 0.254)
					(end 6.604 -0.254)
					(stroke
						(width 0.254)
						(type default)
					)
					(fill
						(type background)
					)
				)
				(rectangle
					(start 6.096 -2.286)
					(end 6.604 -2.794)
					(stroke
						(width 0.254)
						(type default)
					)
					(fill
						(type background)
					)
				)
				(rectangle
					(start 6.096 -4.826)
					(end 6.604 -5.334)
					(stroke
						(width 0.254)
						(type default)
					)
					(fill
						(type background)
					)
				)
				(rectangle
					(start 6.096 -7.366)
					(end 6.604 -7.874)
					(stroke
						(width 0.254)
						(type default)
					)
					(fill
						(type background)
					)
				)
				(rectangle
					(start 6.096 -9.906)
					(end 6.604 -10.414)
					(stroke
						(width 0.254)
						(type default)
					)
					(fill
						(type background)
					)
				)
				(rectangle
					(start 6.096 -12.446)
					(end 6.604 -12.954)
					(stroke
						(width 0.254)
						(type default)
					)
					(fill
						(type background)
					)
				)
				(rectangle
					(start 6.096 -14.986)
					(end 6.604 -15.494)
					(stroke
						(width 0.254)
						(type default)
					)
					(fill
						(type background)
					)
				)
				(pin passive line
					(at 0 0 0)
					(length 2.54)
					(name "~"
						(effects
							(font
								(size 1.27 1.27)
							)
						)
					)
					(number "1"
						(effects
							(font
								(size 1.27 1.27)
							)
						)
					)
				)
				(pin passive line
					(at 0 -2.54 0)
					(length 2.54)
					(name "~"
						(effects
							(font
								(size 1.27 1.27)
							)
						)
					)
					(number "3"
						(effects
							(font
								(size 1.27 1.27)
							)
						)
					)
				)
				(pin passive line
					(at 0 -5.08 0)
					(length 2.54)
					(name "~"
						(effects
							(font
								(size 1.27 1.27)
							)
						)
					)
					(number "5"
						(effects
							(font
								(size 1.27 1.27)
							)
						)
					)
				)
				(pin passive line
					(at 0 -7.62 0)
					(length 2.54)
					(name "~"
						(effects
							(font
								(size 1.27 1.27)
							)
						)
					)
					(number "7"
						(effects
							(font
								(size 1.27 1.27)
							)
						)
					)
				)
				(pin passive line
					(at 0 -10.16 0)
					(length 2.54)
					(name "~"
						(effects
							(font
								(size 1.27 1.27)
							)
						)
					)
					(number "9"
						(effects
							(font
								(size 1.27 1.27)
							)
						)
					)
				)
				(pin passive line
					(at 0 -12.7 0)
					(length 2.54)
					(name "~"
						(effects
							(font
								(size 1.27 1.27)
							)
						)
					)
					(number "11"
						(effects
							(font
								(size 1.27 1.27)
							)
						)
					)
				)
				(pin passive line
					(at 0 -15.24 0)
					(length 2.54)
					(name "~"
						(effects
							(font
								(size 1.27 1.27)
							)
						)
					)
					(number "13"
						(effects
							(font
								(size 1.27 1.27)
							)
						)
					)
				)
				(pin passive line
					(at 10.16 0 180)
					(length 2.54)
					(name "~"
						(effects
							(font
								(size 1.27 1.27)
							)
						)
					)
					(number "2"
						(effects
							(font
								(size 1.27 1.27)
							)
						)
					)
				)
				(pin passive line
					(at 10.16 -2.54 180)
					(length 2.54)
					(name "~"
						(effects
							(font
								(size 1.27 1.27)
							)
						)
					)
					(number "4"
						(effects
							(font
								(size 1.27 1.27)
							)
						)
					)
				)
				(pin passive line
					(at 10.16 -5.08 180)
					(length 2.54)
					(name "~"
						(effects
							(font
								(size 1.27 1.27)
							)
						)
					)
					(number "6"
						(effects
							(font
								(size 1.27 1.27)
							)
						)
					)
				)
				(pin passive line
					(at 10.16 -7.62 180)
					(length 2.54)
					(name "~"
						(effects
							(font
								(size 1.27 1.27)
							)
						)
					)
					(number "8"
						(effects
							(font
								(size 1.27 1.27)
							)
						)
					)
				)
				(pin passive line
					(at 10.16 -10.16 180)
					(length 2.54)
					(name "~"
						(effects
							(font
								(size 1.27 1.27)
							)
						)
					)
					(number "10"
						(effects
							(font
								(size 1.27 1.27)
							)
						)
					)
				)
				(pin passive line
					(at 10.16 -12.7 180)
					(length 2.54)
					(name "~"
						(effects
							(font
								(size 1.27 1.27)
							)
						)
					)
					(number "12"
						(effects
							(font
								(size 1.27 1.27)
							)
						)
					)
				)
				(pin passive line
					(at 10.16 -15.24 180)
					(length 2.54)
					(name "~"
						(effects
							(font
								(size 1.27 1.27)
							)
						)
					)
					(number "14"
						(effects
							(font
								(size 1.27 1.27)
							)
						)
					)
				)
			)
		)
	(symbol "antmicroGenericPinSockets:PinSocket_2x6_P2.54mm_Drill1.02mm_PMOD"
			(exclude_from_sim no)
			(in_bom yes)
			(on_board yes)
			(property "Reference" "J"
				(at 25.4 -5.08 0)
				(effects
					(font
						(size 1.27 1.27)
						(thickness 0.15)
					)
					(justify left bottom)
				)
			)
			(property "Value" "PinSocket_2x6_P2.54mm_Drill1.02mm_PMOD"
				(at 25.4 -7.62 0)
				(effects
					(font
						(size 1.27 1.27)
						(thickness 0.15)
					)
					(justify left bottom)
					(hide yes)
				)
			)
			(property "Footprint" "antmicro-footprints:PinSocket_2x6_P2.54mm_Drill1.02mm_PMOD"
				(at 25.4 -10.16 0)
				(effects
					(font
						(size 1.27 1.27)
						(thickness 0.15)
					)
					(justify left bottom)
					(hide yes)
				)
			)
			(property "Datasheet" "https://cdn.harwin.com/pdfs/M20-783.pdf"
				(at 25.4 -12.7 0)
				(effects
					(font
						(size 1.27 1.27)
						(thickness 0.15)
					)
					(justify left bottom)
					(hide yes)
				)
			)
			(property "Description" "PCB Receptacle, Board-to-Board, 2.54 mm, 2 Rows, 12 Contacts, Through Hole Mount, M20"
				(at 25.4 -25.4 0)
				(effects
					(font
						(size 1.27 1.27)
					)
					(justify left bottom)
					(hide yes)
				)
			)
			(property "MPN" "M20-7830642"
				(at 25.4 -15.24 0)
				(effects
					(font
						(size 1.27 1.27)
						(thickness 0.15)
					)
					(justify left bottom)
				)
			)
			(property "Manufacturer" "Harwin"
				(at 25.4 -17.78 0)
				(effects
					(font
						(size 1.27 1.27)
						(thickness 0.15)
					)
					(justify left bottom)
					(hide yes)
				)
			)
			(property "Author" "Antmicro"
				(at 25.4 -20.32 0)
				(effects
					(font
						(size 1.27 1.27)
						(thickness 0.15)
					)
					(justify left bottom)
					(hide yes)
				)
			)
			(property "License" "Apache-2.0"
				(at 25.4 -22.86 0)
				(effects
					(font
						(size 1.27 1.27)
						(thickness 0.15)
					)
					(justify left bottom)
					(hide yes)
				)
			)
			(property "ki_keywords" "CONNECTOR, HEADER"
				(at 0 0 0)
				(effects
					(font
						(size 1.27 1.27)
					)
					(hide yes)
				)
			)
			(symbol "PinSocket_2x6_P2.54mm_Drill1.02mm_PMOD_0_1"
				(rectangle
					(start 3.556 0.254)
					(end 4.064 -0.254)
					(stroke
						(width 0)
						(type default)
					)
					(fill
						(type outline)
					)
				)
				(rectangle
					(start 3.556 -2.286)
					(end 4.064 -2.794)
					(stroke
						(width 0)
						(type default)
					)
					(fill
						(type outline)
					)
				)
				(rectangle
					(start 3.556 -4.826)
					(end 4.064 -5.334)
					(stroke
						(width 0)
						(type default)
					)
					(fill
						(type outline)
					)
				)
				(rectangle
					(start 3.556 -7.366)
					(end 4.064 -7.874)
					(stroke
						(width 0)
						(type default)
					)
					(fill
						(type outline)
					)
				)
				(rectangle
					(start 3.556 -9.906)
					(end 4.064 -10.414)
					(stroke
						(width 0)
						(type default)
					)
					(fill
						(type outline)
					)
				)
				(rectangle
					(start 3.556 -12.446)
					(end 4.064 -12.954)
					(stroke
						(width 0)
						(type default)
					)
					(fill
						(type outline)
					)
				)
				(rectangle
					(start 5.842 0.254)
					(end 6.35 -0.254)
					(stroke
						(width 0)
						(type default)
					)
					(fill
						(type outline)
					)
				)
				(rectangle
					(start 5.842 -2.286)
					(end 6.35 -2.794)
					(stroke
						(width 0)
						(type default)
					)
					(fill
						(type outline)
					)
				)
				(rectangle
					(start 5.842 -4.826)
					(end 6.35 -5.334)
					(stroke
						(width 0)
						(type default)
					)
					(fill
						(type outline)
					)
				)
				(rectangle
					(start 5.842 -7.366)
					(end 6.35 -7.874)
					(stroke
						(width 0)
						(type default)
					)
					(fill
						(type outline)
					)
				)
				(rectangle
					(start 5.842 -9.906)
					(end 6.35 -10.414)
					(stroke
						(width 0)
						(type default)
					)
					(fill
						(type outline)
					)
				)
				(rectangle
					(start 5.842 -12.446)
					(end 6.35 -12.954)
					(stroke
						(width 0)
						(type default)
					)
					(fill
						(type outline)
					)
				)
			)
			(symbol "PinSocket_2x6_P2.54mm_Drill1.02mm_PMOD_1_1"
				(rectangle
					(start 2.54 1.27)
					(end 7.62 -13.97)
					(stroke
						(width 0.254)
						(type default)
					)
					(fill
						(type background)
					)
				)
				(pin passive line
					(at 0 0 0)
					(length 2.54)
					(name "~"
						(effects
							(font
								(size 1.27 1.27)
							)
						)
					)
					(number "1"
						(effects
							(font
								(size 1.27 1.27)
							)
						)
					)
				)
				(pin passive line
					(at 0 -2.54 0)
					(length 2.54)
					(name "~"
						(effects
							(font
								(size 1.27 1.27)
							)
						)
					)
					(number "2"
						(effects
							(font
								(size 1.27 1.27)
							)
						)
					)
				)
				(pin passive line
					(at 0 -5.08 0)
					(length 2.54)
					(name "~"
						(effects
							(font
								(size 1.27 1.27)
							)
						)
					)
					(number "3"
						(effects
							(font
								(size 1.27 1.27)
							)
						)
					)
				)
				(pin passive line
					(at 0 -7.62 0)
					(length 2.54)
					(name "~"
						(effects
							(font
								(size 1.27 1.27)
							)
						)
					)
					(number "4"
						(effects
							(font
								(size 1.27 1.27)
							)
						)
					)
				)
				(pin passive line
					(at 0 -10.16 0)
					(length 2.54)
					(name "~"
						(effects
							(font
								(size 1.27 1.27)
							)
						)
					)
					(number "5"
						(effects
							(font
								(size 1.27 1.27)
							)
						)
					)
				)
				(pin passive line
					(at 0 -12.7 0)
					(length 2.54)
					(name "~"
						(effects
							(font
								(size 1.27 1.27)
							)
						)
					)
					(number "6"
						(effects
							(font
								(size 1.27 1.27)
							)
						)
					)
				)
				(pin passive line
					(at 10.16 0 180)
					(length 2.54)
					(name "~"
						(effects
							(font
								(size 1.27 1.27)
							)
						)
					)
					(number "7"
						(effects
							(font
								(size 1.27 1.27)
							)
						)
					)
				)
				(pin passive line
					(at 10.16 -2.54 180)
					(length 2.54)
					(name "~"
						(effects
							(font
								(size 1.27 1.27)
							)
						)
					)
					(number "8"
						(effects
							(font
								(size 1.27 1.27)
							)
						)
					)
				)
				(pin passive line
					(at 10.16 -5.08 180)
					(length 2.54)
					(name "~"
						(effects
							(font
								(size 1.27 1.27)
							)
						)
					)
					(number "9"
						(effects
							(font
								(size 1.27 1.27)
							)
						)
					)
				)
				(pin passive line
					(at 10.16 -7.62 180)
					(length 2.54)
					(name "~"
						(effects
							(font
								(size 1.27 1.27)
							)
						)
					)
					(number "10"
						(effects
							(font
								(size 1.27 1.27)
							)
						)
					)
				)
				(pin passive line
					(at 10.16 -10.16 180)
					(length 2.54)
					(name "~"
						(effects
							(font
								(size 1.27 1.27)
							)
						)
					)
					(number "11"
						(effects
							(font
								(size 1.27 1.27)
							)
						)
					)
				)
				(pin passive line
					(at 10.16 -12.7 180)
					(length 2.54)
					(name "~"
						(effects
							(font
								(size 1.27 1.27)
							)
						)
					)
					(number "12"
						(effects
							(font
								(size 1.27 1.27)
							)
						)
					)
				)
			)
		)
	(symbol "antmicroInterfaceControllers:FT4232H_QFN"
			(exclude_from_sim no)
			(in_bom yes)
			(on_board yes)
			(property "Reference" "U"
				(at 43.18 -2.54 0)
				(effects
					(font
						(size 1.27 1.27)
						(thickness 0.15)
					)
					(justify left bottom)
				)
			)
			(property "Value" "FT4232H_QFN"
				(at 43.18 -7.62 0)
				(effects
					(font
						(size 1.27 1.27)
						(thickness 0.15)
					)
					(justify left bottom)
					(hide yes)
				)
			)
			(property "Footprint" "antmicro-footprints:QFN-64-1EP_9x9mm_P0.5mm"
				(at 43.18 -10.16 0)
				(effects
					(font
						(size 1.27 1.27)
						(thickness 0.15)
					)
					(justify left bottom)
					(hide yes)
				)
			)
			(property "Datasheet" "https://www.ftdichip.com/Support/Documents/DataSheets/ICs/DS_FT4232H.pdf"
				(at 43.18 -12.7 0)
				(effects
					(font
						(size 1.27 1.27)
						(thickness 0.15)
					)
					(justify left bottom)
					(hide yes)
				)
			)
			(property "Description" "Interface Bridges, USB to UART, MPSSE, 1.62 V, 1.98 V, QFN, 64 Pins, -40 °C"
				(at 43.18 -22.86 0)
				(effects
					(font
						(size 1.27 1.27)
					)
					(justify left bottom)
					(hide yes)
				)
			)
			(property "Manufacturer" "FTDI Chip"
				(at 43.18 -15.24 0)
				(effects
					(font
						(size 1.27 1.27)
						(thickness 0.15)
					)
					(justify left bottom)
					(hide yes)
				)
			)
			(property "MPN" "FT4232HQ-TRAY"
				(at 43.18 -5.08 0)
				(effects
					(font
						(size 1.27 1.27)
						(thickness 0.15)
					)
					(justify left bottom)
				)
			)
			(property "Author" "Antmicro"
				(at 43.18 -17.78 0)
				(effects
					(font
						(size 1.27 1.27)
						(thickness 0.15)
					)
					(justify left bottom)
					(hide yes)
				)
			)
			(property "License" "Apache-2.0"
				(at 43.18 -20.32 0)
				(effects
					(font
						(size 1.27 1.27)
						(thickness 0.15)
					)
					(justify left bottom)
					(hide yes)
				)
			)
			(property "ki_keywords" "SMT, INTERFACE, IC, CONTROLLER, USB, UART, I2C, SPI, JTAG"
				(at 0 0 0)
				(effects
					(font
						(size 1.27 1.27)
					)
					(hide yes)
				)
			)
			(symbol "FT4232H_QFN_1_1"
				(rectangle
					(start 2.54 3.81)
					(end 25.4 -100.33)
					(stroke
						(width 0.254)
						(type default)
					)
					(fill
						(type background)
					)
				)
				(pin power_in line
					(at 0 0 0)
					(length 2.54)
					(name "V_{PHY}"
						(effects
							(font
								(size 1.27 1.27)
							)
						)
					)
					(number "4"
						(effects
							(font
								(size 1.27 1.27)
							)
						)
					)
				)
				(pin power_in line
					(at 0 -2.54 0)
					(length 2.54)
					(name "V_{PLL}"
						(effects
							(font
								(size 1.27 1.27)
							)
						)
					)
					(number "9"
						(effects
							(font
								(size 1.27 1.27)
							)
						)
					)
				)
				(pin power_in line
					(at 0 -7.62 0)
					(length 2.54)
					(name "V_{REGIN}"
						(effects
							(font
								(size 1.27 1.27)
							)
						)
					)
					(number "50"
						(effects
							(font
								(size 1.27 1.27)
							)
						)
					)
				)
				(pin power_in line
					(at 0 -12.7 0)
					(length 2.54)
					(name "V_{CCIO}"
						(effects
							(font
								(size 1.27 1.27)
							)
						)
					)
					(number "20"
						(effects
							(font
								(size 1.27 1.27)
							)
						)
					)
				)
				(pin passive line
					(at 0 -12.7 0)
					(length 2.54)
					(hide yes)
					(name "V_{CCIO}"
						(effects
							(font
								(size 1.27 1.27)
							)
						)
					)
					(number "31"
						(effects
							(font
								(size 1.27 1.27)
							)
						)
					)
				)
				(pin passive line
					(at 0 -12.7 0)
					(length 2.54)
					(hide yes)
					(name "V_{CCIO}"
						(effects
							(font
								(size 1.27 1.27)
							)
						)
					)
					(number "42"
						(effects
							(font
								(size 1.27 1.27)
							)
						)
					)
				)
				(pin passive line
					(at 0 -12.7 0)
					(length 2.54)
					(hide yes)
					(name "V_{CCIO}"
						(effects
							(font
								(size 1.27 1.27)
							)
						)
					)
					(number "56"
						(effects
							(font
								(size 1.27 1.27)
							)
						)
					)
				)
				(pin power_out line
					(at 0 -22.86 0)
					(length 2.54)
					(name "V_{REGOUT}"
						(effects
							(font
								(size 1.27 1.27)
							)
						)
					)
					(number "49"
						(effects
							(font
								(size 1.27 1.27)
							)
						)
					)
				)
				(pin power_in line
					(at 0 -27.94 0)
					(length 2.54)
					(name "V_{CORE}"
						(effects
							(font
								(size 1.27 1.27)
							)
						)
					)
					(number "12"
						(effects
							(font
								(size 1.27 1.27)
							)
						)
					)
				)
				(pin passive line
					(at 0 -27.94 0)
					(length 2.54)
					(hide yes)
					(name "V_{CORE}"
						(effects
							(font
								(size 1.27 1.27)
							)
						)
					)
					(number "37"
						(effects
							(font
								(size 1.27 1.27)
							)
						)
					)
				)
				(pin passive line
					(at 0 -27.94 0)
					(length 2.54)
					(hide yes)
					(name "V_{CORE}"
						(effects
							(font
								(size 1.27 1.27)
							)
						)
					)
					(number "64"
						(effects
							(font
								(size 1.27 1.27)
							)
						)
					)
				)
				(pin bidirectional line
					(at 0 -48.26 0)
					(length 2.54)
					(name "D+"
						(effects
							(font
								(size 1.27 1.27)
							)
						)
					)
					(number "8"
						(effects
							(font
								(size 1.27 1.27)
							)
						)
					)
				)
				(pin bidirectional line
					(at 0 -50.8 0)
					(length 2.54)
					(name "D-"
						(effects
							(font
								(size 1.27 1.27)
							)
						)
					)
					(number "7"
						(effects
							(font
								(size 1.27 1.27)
							)
						)
					)
				)
				(pin input line
					(at 0 -63.5 0)
					(length 2.54)
					(name "~{RESET}"
						(effects
							(font
								(size 1.27 1.27)
							)
						)
					)
					(number "14"
						(effects
							(font
								(size 1.27 1.27)
							)
						)
					)
				)
				(pin bidirectional line
					(at 0 -69.85 0)
					(length 2.54)
					(name "EECS"
						(effects
							(font
								(size 1.27 1.27)
							)
						)
					)
					(number "63"
						(effects
							(font
								(size 1.27 1.27)
							)
						)
					)
				)
				(pin output line
					(at 0 -72.39 0)
					(length 2.54)
					(name "EECLK"
						(effects
							(font
								(size 1.27 1.27)
							)
						)
					)
					(number "62"
						(effects
							(font
								(size 1.27 1.27)
							)
						)
					)
				)
				(pin bidirectional line
					(at 0 -74.93 0)
					(length 2.54)
					(name "EEDATA"
						(effects
							(font
								(size 1.27 1.27)
							)
						)
					)
					(number "61"
						(effects
							(font
								(size 1.27 1.27)
							)
						)
					)
				)
				(pin input line
					(at 0 -86.36 0)
					(length 2.54)
					(name "OSCI"
						(effects
							(font
								(size 1.27 1.27)
							)
						)
					)
					(number "2"
						(effects
							(font
								(size 1.27 1.27)
							)
						)
					)
				)
				(pin output line
					(at 0 -91.44 0)
					(length 2.54)
					(name "OSCO"
						(effects
							(font
								(size 1.27 1.27)
							)
						)
					)
					(number "3"
						(effects
							(font
								(size 1.27 1.27)
							)
						)
					)
				)
				(pin input line
					(at 0 -93.98 0)
					(length 2.54)
					(name "REF"
						(effects
							(font
								(size 1.27 1.27)
							)
						)
					)
					(number "6"
						(effects
							(font
								(size 1.27 1.27)
							)
						)
					)
				)
				(pin input line
					(at 0 -96.52 0)
					(length 2.54)
					(name "TEST"
						(effects
							(font
								(size 1.27 1.27)
							)
						)
					)
					(number "13"
						(effects
							(font
								(size 1.27 1.27)
							)
						)
					)
				)
				(pin bidirectional line
					(at 27.94 0 180)
					(length 2.54)
					(name "ADBUS0"
						(effects
							(font
								(size 1.27 1.27)
							)
						)
					)
					(number "16"
						(effects
							(font
								(size 1.27 1.27)
							)
						)
					)
				)
				(pin bidirectional line
					(at 27.94 -2.54 180)
					(length 2.54)
					(name "ADBUS1"
						(effects
							(font
								(size 1.27 1.27)
							)
						)
					)
					(number "17"
						(effects
							(font
								(size 1.27 1.27)
							)
						)
					)
				)
				(pin bidirectional line
					(at 27.94 -5.08 180)
					(length 2.54)
					(name "ADBUS2"
						(effects
							(font
								(size 1.27 1.27)
							)
						)
					)
					(number "18"
						(effects
							(font
								(size 1.27 1.27)
							)
						)
					)
				)
				(pin bidirectional line
					(at 27.94 -7.62 180)
					(length 2.54)
					(name "ADBUS3"
						(effects
							(font
								(size 1.27 1.27)
							)
						)
					)
					(number "19"
						(effects
							(font
								(size 1.27 1.27)
							)
						)
					)
				)
				(pin bidirectional line
					(at 27.94 -10.16 180)
					(length 2.54)
					(name "ADBUS4"
						(effects
							(font
								(size 1.27 1.27)
							)
						)
					)
					(number "21"
						(effects
							(font
								(size 1.27 1.27)
							)
						)
					)
				)
				(pin bidirectional line
					(at 27.94 -12.7 180)
					(length 2.54)
					(name "ADBUS5"
						(effects
							(font
								(size 1.27 1.27)
							)
						)
					)
					(number "22"
						(effects
							(font
								(size 1.27 1.27)
							)
						)
					)
				)
				(pin bidirectional line
					(at 27.94 -15.24 180)
					(length 2.54)
					(name "ADBUS6"
						(effects
							(font
								(size 1.27 1.27)
							)
						)
					)
					(number "23"
						(effects
							(font
								(size 1.27 1.27)
							)
						)
					)
				)
				(pin bidirectional line
					(at 27.94 -17.78 180)
					(length 2.54)
					(name "ADBUS7"
						(effects
							(font
								(size 1.27 1.27)
							)
						)
					)
					(number "24"
						(effects
							(font
								(size 1.27 1.27)
							)
						)
					)
				)
				(pin bidirectional line
					(at 27.94 -21.59 180)
					(length 2.54)
					(name "BDBUS0"
						(effects
							(font
								(size 1.27 1.27)
							)
						)
					)
					(number "26"
						(effects
							(font
								(size 1.27 1.27)
							)
						)
					)
				)
				(pin bidirectional line
					(at 27.94 -24.13 180)
					(length 2.54)
					(name "BDBUS1"
						(effects
							(font
								(size 1.27 1.27)
							)
						)
					)
					(number "27"
						(effects
							(font
								(size 1.27 1.27)
							)
						)
					)
				)
				(pin bidirectional line
					(at 27.94 -26.67 180)
					(length 2.54)
					(name "BDBUS2"
						(effects
							(font
								(size 1.27 1.27)
							)
						)
					)
					(number "28"
						(effects
							(font
								(size 1.27 1.27)
							)
						)
					)
				)
				(pin bidirectional line
					(at 27.94 -29.21 180)
					(length 2.54)
					(name "BDBUS3"
						(effects
							(font
								(size 1.27 1.27)
							)
						)
					)
					(number "29"
						(effects
							(font
								(size 1.27 1.27)
							)
						)
					)
				)
				(pin bidirectional line
					(at 27.94 -31.75 180)
					(length 2.54)
					(name "BDBUS4"
						(effects
							(font
								(size 1.27 1.27)
							)
						)
					)
					(number "30"
						(effects
							(font
								(size 1.27 1.27)
							)
						)
					)
				)
				(pin bidirectional line
					(at 27.94 -34.29 180)
					(length 2.54)
					(name "BDBUS5"
						(effects
							(font
								(size 1.27 1.27)
							)
						)
					)
					(number "32"
						(effects
							(font
								(size 1.27 1.27)
							)
						)
					)
				)
				(pin bidirectional line
					(at 27.94 -36.83 180)
					(length 2.54)
					(name "BDBUS6"
						(effects
							(font
								(size 1.27 1.27)
							)
						)
					)
					(number "33"
						(effects
							(font
								(size 1.27 1.27)
							)
						)
					)
				)
				(pin bidirectional line
					(at 27.94 -39.37 180)
					(length 2.54)
					(name "BDBUS7"
						(effects
							(font
								(size 1.27 1.27)
							)
						)
					)
					(number "34"
						(effects
							(font
								(size 1.27 1.27)
							)
						)
					)
				)
				(pin bidirectional line
					(at 27.94 -43.18 180)
					(length 2.54)
					(name "CDBUS0"
						(effects
							(font
								(size 1.27 1.27)
							)
						)
					)
					(number "38"
						(effects
							(font
								(size 1.27 1.27)
							)
						)
					)
				)
				(pin bidirectional line
					(at 27.94 -45.72 180)
					(length 2.54)
					(name "CDBUS1"
						(effects
							(font
								(size 1.27 1.27)
							)
						)
					)
					(number "39"
						(effects
							(font
								(size 1.27 1.27)
							)
						)
					)
				)
				(pin bidirectional line
					(at 27.94 -48.26 180)
					(length 2.54)
					(name "CDBUS2"
						(effects
							(font
								(size 1.27 1.27)
							)
						)
					)
					(number "40"
						(effects
							(font
								(size 1.27 1.27)
							)
						)
					)
				)
				(pin bidirectional line
					(at 27.94 -50.8 180)
					(length 2.54)
					(name "CDBUS3"
						(effects
							(font
								(size 1.27 1.27)
							)
						)
					)
					(number "41"
						(effects
							(font
								(size 1.27 1.27)
							)
						)
					)
				)
				(pin bidirectional line
					(at 27.94 -53.34 180)
					(length 2.54)
					(name "CDBUS4"
						(effects
							(font
								(size 1.27 1.27)
							)
						)
					)
					(number "43"
						(effects
							(font
								(size 1.27 1.27)
							)
						)
					)
				)
				(pin bidirectional line
					(at 27.94 -55.88 180)
					(length 2.54)
					(name "CDBUS5"
						(effects
							(font
								(size 1.27 1.27)
							)
						)
					)
					(number "44"
						(effects
							(font
								(size 1.27 1.27)
							)
						)
					)
				)
				(pin bidirectional line
					(at 27.94 -58.42 180)
					(length 2.54)
					(name "CDBUS6"
						(effects
							(font
								(size 1.27 1.27)
							)
						)
					)
					(number "45"
						(effects
							(font
								(size 1.27 1.27)
							)
						)
					)
				)
				(pin bidirectional line
					(at 27.94 -60.96 180)
					(length 2.54)
					(name "CDBUS7"
						(effects
							(font
								(size 1.27 1.27)
							)
						)
					)
					(number "46"
						(effects
							(font
								(size 1.27 1.27)
							)
						)
					)
				)
				(pin bidirectional line
					(at 27.94 -64.77 180)
					(length 2.54)
					(name "DDBUS0"
						(effects
							(font
								(size 1.27 1.27)
							)
						)
					)
					(number "48"
						(effects
							(font
								(size 1.27 1.27)
							)
						)
					)
				)
				(pin bidirectional line
					(at 27.94 -67.31 180)
					(length 2.54)
					(name "DDBUS1"
						(effects
							(font
								(size 1.27 1.27)
							)
						)
					)
					(number "52"
						(effects
							(font
								(size 1.27 1.27)
							)
						)
					)
				)
				(pin bidirectional line
					(at 27.94 -69.85 180)
					(length 2.54)
					(name "DDBUS2"
						(effects
							(font
								(size 1.27 1.27)
							)
						)
					)
					(number "53"
						(effects
							(font
								(size 1.27 1.27)
							)
						)
					)
				)
				(pin bidirectional line
					(at 27.94 -72.39 180)
					(length 2.54)
					(name "DDBUS3"
						(effects
							(font
								(size 1.27 1.27)
							)
						)
					)
					(number "54"
						(effects
							(font
								(size 1.27 1.27)
							)
						)
					)
				)
				(pin bidirectional line
					(at 27.94 -74.93 180)
					(length 2.54)
					(name "DDBUS4"
						(effects
							(font
								(size 1.27 1.27)
							)
						)
					)
					(number "55"
						(effects
							(font
								(size 1.27 1.27)
							)
						)
					)
				)
				(pin bidirectional line
					(at 27.94 -77.47 180)
					(length 2.54)
					(name "DDBUS5"
						(effects
							(font
								(size 1.27 1.27)
							)
						)
					)
					(number "57"
						(effects
							(font
								(size 1.27 1.27)
							)
						)
					)
				)
				(pin bidirectional line
					(at 27.94 -80.01 180)
					(length 2.54)
					(name "DDBUS6"
						(effects
							(font
								(size 1.27 1.27)
							)
						)
					)
					(number "58"
						(effects
							(font
								(size 1.27 1.27)
							)
						)
					)
				)
				(pin bidirectional line
					(at 27.94 -82.55 180)
					(length 2.54)
					(name "DDBUS7"
						(effects
							(font
								(size 1.27 1.27)
							)
						)
					)
					(number "59"
						(effects
							(font
								(size 1.27 1.27)
							)
						)
					)
				)
				(pin output line
					(at 27.94 -86.36 180)
					(length 2.54)
					(name "PWREN"
						(effects
							(font
								(size 1.27 1.27)
							)
						)
					)
					(number "60"
						(effects
							(font
								(size 1.27 1.27)
							)
						)
					)
				)
				(pin output line
					(at 27.94 -88.9 180)
					(length 2.54)
					(name "SUSPEND"
						(effects
							(font
								(size 1.27 1.27)
							)
						)
					)
					(number "36"
						(effects
							(font
								(size 1.27 1.27)
							)
						)
					)
				)
				(pin power_in line
					(at 27.94 -93.98 180)
					(length 2.54)
					(name "AGND"
						(effects
							(font
								(size 1.27 1.27)
							)
						)
					)
					(number "10"
						(effects
							(font
								(size 1.27 1.27)
							)
						)
					)
				)
				(pin power_in line
					(at 27.94 -96.52 180)
					(length 2.54)
					(name "GND"
						(effects
							(font
								(size 1.27 1.27)
							)
						)
					)
					(number "1"
						(effects
							(font
								(size 1.27 1.27)
							)
						)
					)
				)
				(pin passive line
					(at 27.94 -96.52 180)
					(length 2.54)
					(hide yes)
					(name "GND"
						(effects
							(font
								(size 1.27 1.27)
							)
						)
					)
					(number "11"
						(effects
							(font
								(size 1.27 1.27)
							)
						)
					)
				)
				(pin passive line
					(at 27.94 -96.52 180)
					(length 2.54)
					(hide yes)
					(name "GND"
						(effects
							(font
								(size 1.27 1.27)
							)
						)
					)
					(number "15"
						(effects
							(font
								(size 1.27 1.27)
							)
						)
					)
				)
				(pin passive line
					(at 27.94 -96.52 180)
					(length 2.54)
					(hide yes)
					(name "GND"
						(effects
							(font
								(size 1.27 1.27)
							)
						)
					)
					(number "25"
						(effects
							(font
								(size 1.27 1.27)
							)
						)
					)
				)
				(pin passive line
					(at 27.94 -96.52 180)
					(length 2.54)
					(hide yes)
					(name "GND"
						(effects
							(font
								(size 1.27 1.27)
							)
						)
					)
					(number "35"
						(effects
							(font
								(size 1.27 1.27)
							)
						)
					)
				)
				(pin passive line
					(at 27.94 -96.52 180)
					(length 2.54)
					(hide yes)
					(name "GND"
						(effects
							(font
								(size 1.27 1.27)
							)
						)
					)
					(number "47"
						(effects
							(font
								(size 1.27 1.27)
							)
						)
					)
				)
				(pin passive line
					(at 27.94 -96.52 180)
					(length 2.54)
					(hide yes)
					(name "GND"
						(effects
							(font
								(size 1.27 1.27)
							)
						)
					)
					(number "5"
						(effects
							(font
								(size 1.27 1.27)
							)
						)
					)
				)
				(pin passive line
					(at 27.94 -96.52 180)
					(length 2.54)
					(hide yes)
					(name "GND"
						(effects
							(font
								(size 1.27 1.27)
							)
						)
					)
					(number "51"
						(effects
							(font
								(size 1.27 1.27)
							)
						)
					)
				)
				(pin passive line
					(at 27.94 -96.52 180)
					(length 2.54)
					(hide yes)
					(name "GND"
						(effects
							(font
								(size 1.27 1.27)
							)
						)
					)
					(number "65"
						(effects
							(font
								(size 1.27 1.27)
							)
						)
					)
				)
			)
		)
	(symbol "antmicroInterfaceControllers:KSZ9031RNXCA"
			(exclude_from_sim no)
			(in_bom yes)
			(on_board yes)
			(property "Reference" "U"
				(at 76.2 -5.08 0)
				(effects
					(font
						(size 1.27 1.27)
						(thickness 0.15)
					)
					(justify left bottom)
				)
			)
			(property "Value" "KSZ9031RNXCA"
				(at 76.2 -7.62 0)
				(effects
					(font
						(size 1.27 1.27)
						(thickness 0.15)
					)
					(justify left bottom)
					(hide yes)
				)
			)
			(property "Footprint" "antmicro-footprints:QFN-48-1EP_7x7x0.9mm_P0.5mm_EP3.5x3.5mm"
				(at 76.2 -10.16 0)
				(effects
					(font
						(size 1.27 1.27)
						(thickness 0.15)
					)
					(justify left bottom)
					(hide yes)
				)
			)
			(property "Datasheet" "http://ww1.microchip.com/downloads/en/DeviceDoc/00002117F.pdf"
				(at 76.2 -12.7 0)
				(effects
					(font
						(size 1.27 1.27)
						(thickness 0.15)
					)
					(justify left bottom)
					(hide yes)
				)
			)
			(property "Description" "Ethernet Controller, 1000 Mbps, IEEE 802.3, 1.14 V, 3.465 V, QFN, 48 Pins"
				(at 76.2 -25.4 0)
				(effects
					(font
						(size 1.27 1.27)
					)
					(justify left bottom)
					(hide yes)
				)
			)
			(property "Manufacturer" "Microchip Technology"
				(at 76.2 -15.24 0)
				(effects
					(font
						(size 1.27 1.27)
						(thickness 0.15)
					)
					(justify left bottom)
					(hide yes)
				)
			)
			(property "MPN" "KSZ9031RNXCA"
				(at 76.2 -17.78 0)
				(effects
					(font
						(size 1.27 1.27)
						(thickness 0.15)
					)
					(justify left bottom)
				)
			)
			(property "Author" "Antmicro"
				(at 76.2 -20.32 0)
				(effects
					(font
						(size 1.27 1.27)
						(thickness 0.15)
					)
					(justify left bottom)
					(hide yes)
				)
			)
			(property "License" "Apache-2.0"
				(at 76.2 -22.86 0)
				(effects
					(font
						(size 1.27 1.27)
						(thickness 0.15)
					)
					(justify left bottom)
					(hide yes)
				)
			)
			(property "ki_keywords" "SMT, TRANSCEIVER, IC, ETHERNET, PHY"
				(at 0 0 0)
				(effects
					(font
						(size 1.27 1.27)
					)
					(hide yes)
				)
			)
			(symbol "KSZ9031RNXCA_1_1"
				(rectangle
					(start 2.54 2.54)
					(end 41.91 -62.23)
					(stroke
						(width 0.254)
						(type default)
					)
					(fill
						(type background)
					)
				)
				(text "10/100/1000"
					(at 21.59 -1.27 0)
					(effects
						(font
							(size 1.27 1.27)
							(thickness 0.15)
						)
						(justify bottom)
					)
				)
				(text "Ethernet PHY"
					(at 21.59 -3.81 0)
					(effects
						(font
							(size 1.27 1.27)
							(thickness 0.15)
						)
						(justify bottom)
					)
				)
				(pin power_in line
					(at 0 0 0)
					(length 2.54)
					(name "DVDDH"
						(effects
							(font
								(size 1.27 1.27)
							)
						)
					)
					(number "16"
						(effects
							(font
								(size 1.27 1.27)
							)
						)
					)
				)
				(pin passive line
					(at 0 0 0)
					(length 2.54)
					(hide yes)
					(name "DVDDH"
						(effects
							(font
								(size 1.27 1.27)
							)
						)
					)
					(number "34"
						(effects
							(font
								(size 1.27 1.27)
							)
						)
					)
				)
				(pin passive line
					(at 0 0 0)
					(length 2.54)
					(hide yes)
					(name "DVDDH"
						(effects
							(font
								(size 1.27 1.27)
							)
						)
					)
					(number "40"
						(effects
							(font
								(size 1.27 1.27)
							)
						)
					)
				)
				(pin power_in line
					(at 0 -3.81 0)
					(length 2.54)
					(name "AVDDH"
						(effects
							(font
								(size 1.27 1.27)
							)
						)
					)
					(number "1"
						(effects
							(font
								(size 1.27 1.27)
							)
						)
					)
				)
				(pin passive line
					(at 0 -3.81 0)
					(length 2.54)
					(hide yes)
					(name "AVDDH"
						(effects
							(font
								(size 1.27 1.27)
							)
						)
					)
					(number "12"
						(effects
							(font
								(size 1.27 1.27)
							)
						)
					)
				)
				(pin input line
					(at 0 -7.62 0)
					(length 2.54)
					(name "~{RESET}"
						(effects
							(font
								(size 1.27 1.27)
							)
						)
					)
					(number "42"
						(effects
							(font
								(size 1.27 1.27)
							)
						)
					)
				)
				(pin input line
					(at 0 -10.16 0)
					(length 2.54)
					(name "~{INT/PME}"
						(effects
							(font
								(size 1.27 1.27)
							)
						)
					)
					(number "38"
						(effects
							(font
								(size 1.27 1.27)
							)
						)
					)
				)
				(pin input line
					(at 0 -13.97 0)
					(length 2.54)
					(name "MDC"
						(effects
							(font
								(size 1.27 1.27)
							)
						)
					)
					(number "36"
						(effects
							(font
								(size 1.27 1.27)
							)
						)
					)
				)
				(pin input line
					(at 0 -16.51 0)
					(length 2.54)
					(name "MDIO"
						(effects
							(font
								(size 1.27 1.27)
							)
						)
					)
					(number "37"
						(effects
							(font
								(size 1.27 1.27)
							)
						)
					)
				)
				(pin input line
					(at 0 -20.32 0)
					(length 2.54)
					(name "TX_EN"
						(effects
							(font
								(size 1.27 1.27)
							)
						)
					)
					(number "25"
						(effects
							(font
								(size 1.27 1.27)
							)
						)
					)
				)
				(pin input line
					(at 0 -22.86 0)
					(length 2.54)
					(name "TXD0"
						(effects
							(font
								(size 1.27 1.27)
							)
						)
					)
					(number "19"
						(effects
							(font
								(size 1.27 1.27)
							)
						)
					)
				)
				(pin input line
					(at 0 -25.4 0)
					(length 2.54)
					(name "TXD1"
						(effects
							(font
								(size 1.27 1.27)
							)
						)
					)
					(number "20"
						(effects
							(font
								(size 1.27 1.27)
							)
						)
					)
				)
				(pin input line
					(at 0 -27.94 0)
					(length 2.54)
					(name "TXD2"
						(effects
							(font
								(size 1.27 1.27)
							)
						)
					)
					(number "21"
						(effects
							(font
								(size 1.27 1.27)
							)
						)
					)
				)
				(pin input line
					(at 0 -30.48 0)
					(length 2.54)
					(name "TXD3"
						(effects
							(font
								(size 1.27 1.27)
							)
						)
					)
					(number "22"
						(effects
							(font
								(size 1.27 1.27)
							)
						)
					)
				)
				(pin input clock
					(at 0 -33.02 0)
					(length 2.54)
					(name "GTX_CLK"
						(effects
							(font
								(size 1.27 1.27)
							)
						)
					)
					(number "24"
						(effects
							(font
								(size 1.27 1.27)
							)
						)
					)
				)
				(pin input line
					(at 0 -36.83 0)
					(length 2.54)
					(name "RX_DV/CLK125_EN"
						(effects
							(font
								(size 1.27 1.27)
							)
						)
					)
					(number "33"
						(effects
							(font
								(size 1.27 1.27)
							)
						)
					)
				)
				(pin input line
					(at 0 -39.37 0)
					(length 2.54)
					(name "RXD0/MODE0"
						(effects
							(font
								(size 1.27 1.27)
							)
						)
					)
					(number "32"
						(effects
							(font
								(size 1.27 1.27)
							)
						)
					)
				)
				(pin input line
					(at 0 -41.91 0)
					(length 2.54)
					(name "RXD1/MODE1"
						(effects
							(font
								(size 1.27 1.27)
							)
						)
					)
					(number "31"
						(effects
							(font
								(size 1.27 1.27)
							)
						)
					)
				)
				(pin input line
					(at 0 -44.45 0)
					(length 2.54)
					(name "RXD2/MODE2"
						(effects
							(font
								(size 1.27 1.27)
							)
						)
					)
					(number "28"
						(effects
							(font
								(size 1.27 1.27)
							)
						)
					)
				)
				(pin input line
					(at 0 -46.99 0)
					(length 2.54)
					(name "RXD3/MODE3"
						(effects
							(font
								(size 1.27 1.27)
							)
						)
					)
					(number "27"
						(effects
							(font
								(size 1.27 1.27)
							)
						)
					)
				)
				(pin input clock
					(at 0 -49.53 0)
					(length 2.54)
					(name "RX_CLK/PHYAD2"
						(effects
							(font
								(size 1.27 1.27)
							)
						)
					)
					(number "35"
						(effects
							(font
								(size 1.27 1.27)
							)
						)
					)
				)
				(pin input clock
					(at 0 -53.34 0)
					(length 2.54)
					(name "CLK125_NDO/LED_MODE"
						(effects
							(font
								(size 1.27 1.27)
							)
						)
					)
					(number "41"
						(effects
							(font
								(size 1.27 1.27)
							)
						)
					)
				)
				(pin input line
					(at 0 -57.15 0)
					(length 2.54)
					(name "XI"
						(effects
							(font
								(size 1.27 1.27)
							)
						)
					)
					(number "46"
						(effects
							(font
								(size 1.27 1.27)
							)
						)
					)
				)
				(pin input line
					(at 0 -59.69 0)
					(length 2.54)
					(name "XO"
						(effects
							(font
								(size 1.27 1.27)
							)
						)
					)
					(number "45"
						(effects
							(font
								(size 1.27 1.27)
							)
						)
					)
				)
				(pin no_connect line
					(at 41.91 -52.07 180)
					(length 2.54)
					(hide yes)
					(name "NC"
						(effects
							(font
								(size 1.27 1.27)
							)
						)
					)
					(number "47"
						(effects
							(font
								(size 1.27 1.27)
							)
						)
					)
				)
				(pin no_connect line
					(at 41.91 -53.34 180)
					(length 2.54)
					(hide yes)
					(name "NC"
						(effects
							(font
								(size 1.27 1.27)
							)
						)
					)
					(number "13"
						(effects
							(font
								(size 1.27 1.27)
							)
						)
					)
				)
				(pin power_in line
					(at 44.45 0 180)
					(length 2.54)
					(name "DVDDL"
						(effects
							(font
								(size 1.27 1.27)
							)
						)
					)
					(number "14"
						(effects
							(font
								(size 1.27 1.27)
							)
						)
					)
				)
				(pin passive line
					(at 44.45 0 180)
					(length 2.54)
					(hide yes)
					(name "DVDDL"
						(effects
							(font
								(size 1.27 1.27)
							)
						)
					)
					(number "18"
						(effects
							(font
								(size 1.27 1.27)
							)
						)
					)
				)
				(pin passive line
					(at 44.45 0 180)
					(length 2.54)
					(hide yes)
					(name "DVDDL"
						(effects
							(font
								(size 1.27 1.27)
							)
						)
					)
					(number "23"
						(effects
							(font
								(size 1.27 1.27)
							)
						)
					)
				)
				(pin passive line
					(at 44.45 0 180)
					(length 2.54)
					(hide yes)
					(name "DVDDL"
						(effects
							(font
								(size 1.27 1.27)
							)
						)
					)
					(number "26"
						(effects
							(font
								(size 1.27 1.27)
							)
						)
					)
				)
				(pin passive line
					(at 44.45 0 180)
					(length 2.54)
					(hide yes)
					(name "DVDDL"
						(effects
							(font
								(size 1.27 1.27)
							)
						)
					)
					(number "30"
						(effects
							(font
								(size 1.27 1.27)
							)
						)
					)
				)
				(pin passive line
					(at 44.45 0 180)
					(length 2.54)
					(hide yes)
					(name "DVDDL"
						(effects
							(font
								(size 1.27 1.27)
							)
						)
					)
					(number "39"
						(effects
							(font
								(size 1.27 1.27)
							)
						)
					)
				)
				(pin power_in line
					(at 44.45 -3.81 180)
					(length 2.54)
					(name "AVDDL"
						(effects
							(font
								(size 1.27 1.27)
							)
						)
					)
					(number "4"
						(effects
							(font
								(size 1.27 1.27)
							)
						)
					)
				)
				(pin passive line
					(at 44.45 -3.81 180)
					(length 2.54)
					(hide yes)
					(name "AVDDL"
						(effects
							(font
								(size 1.27 1.27)
							)
						)
					)
					(number "9"
						(effects
							(font
								(size 1.27 1.27)
							)
						)
					)
				)
				(pin power_in line
					(at 44.45 -6.35 180)
					(length 2.54)
					(name "AVDDL_PLL"
						(effects
							(font
								(size 1.27 1.27)
							)
						)
					)
					(number "44"
						(effects
							(font
								(size 1.27 1.27)
							)
						)
					)
				)
				(pin input line
					(at 44.45 -8.89 180)
					(length 2.54)
					(name "LDO_O"
						(effects
							(font
								(size 1.27 1.27)
							)
						)
					)
					(number "43"
						(effects
							(font
								(size 1.27 1.27)
							)
						)
					)
				)
				(pin bidirectional line
					(at 44.45 -13.97 180)
					(length 2.54)
					(name "TXRXP_A"
						(effects
							(font
								(size 1.27 1.27)
							)
						)
					)
					(number "2"
						(effects
							(font
								(size 1.27 1.27)
							)
						)
					)
				)
				(pin bidirectional line
					(at 44.45 -16.51 180)
					(length 2.54)
					(name "TXRXM_A"
						(effects
							(font
								(size 1.27 1.27)
							)
						)
					)
					(number "3"
						(effects
							(font
								(size 1.27 1.27)
							)
						)
					)
				)
				(pin bidirectional line
					(at 44.45 -20.32 180)
					(length 2.54)
					(name "TXRXP_B"
						(effects
							(font
								(size 1.27 1.27)
							)
						)
					)
					(number "5"
						(effects
							(font
								(size 1.27 1.27)
							)
						)
					)
				)
				(pin bidirectional line
					(at 44.45 -22.86 180)
					(length 2.54)
					(name "TXRXM_B"
						(effects
							(font
								(size 1.27 1.27)
							)
						)
					)
					(number "6"
						(effects
							(font
								(size 1.27 1.27)
							)
						)
					)
				)
				(pin bidirectional line
					(at 44.45 -26.67 180)
					(length 2.54)
					(name "TXRXP_C"
						(effects
							(font
								(size 1.27 1.27)
							)
						)
					)
					(number "7"
						(effects
							(font
								(size 1.27 1.27)
							)
						)
					)
				)
				(pin bidirectional line
					(at 44.45 -29.21 180)
					(length 2.54)
					(name "TXRXM_C"
						(effects
							(font
								(size 1.27 1.27)
							)
						)
					)
					(number "8"
						(effects
							(font
								(size 1.27 1.27)
							)
						)
					)
				)
				(pin bidirectional line
					(at 44.45 -33.02 180)
					(length 2.54)
					(name "TXRXP_D"
						(effects
							(font
								(size 1.27 1.27)
							)
						)
					)
					(number "10"
						(effects
							(font
								(size 1.27 1.27)
							)
						)
					)
				)
				(pin bidirectional line
					(at 44.45 -35.56 180)
					(length 2.54)
					(name "TXRXM_D"
						(effects
							(font
								(size 1.27 1.27)
							)
						)
					)
					(number "11"
						(effects
							(font
								(size 1.27 1.27)
							)
						)
					)
				)
				(pin bidirectional line
					(at 44.45 -41.91 180)
					(length 2.54)
					(name "LED1/PHYAD0/PME_N1"
						(effects
							(font
								(size 1.27 1.27)
							)
						)
					)
					(number "17"
						(effects
							(font
								(size 1.27 1.27)
							)
						)
					)
				)
				(pin bidirectional line
					(at 44.45 -44.45 180)
					(length 2.54)
					(name "LED2/PHYAD1"
						(effects
							(font
								(size 1.27 1.27)
							)
						)
					)
					(number "15"
						(effects
							(font
								(size 1.27 1.27)
							)
						)
					)
				)
				(pin output line
					(at 44.45 -49.53 180)
					(length 2.54)
					(name "ISET"
						(effects
							(font
								(size 1.27 1.27)
							)
						)
					)
					(number "48"
						(effects
							(font
								(size 1.27 1.27)
							)
						)
					)
				)
				(pin power_in line
					(at 44.45 -57.15 180)
					(length 2.54)
					(name "PAD_GND"
						(effects
							(font
								(size 1.27 1.27)
							)
						)
					)
					(number "49"
						(effects
							(font
								(size 1.27 1.27)
							)
						)
					)
				)
				(pin power_in line
					(at 44.45 -59.69 180)
					(length 2.54)
					(name "VSS"
						(effects
							(font
								(size 1.27 1.27)
							)
						)
					)
					(number "29"
						(effects
							(font
								(size 1.27 1.27)
							)
						)
					)
				)
			)
		)
	(symbol "antmicroInterfaceControllers:USB3300-EZK-TR"
			(pin_names
				(offset 1.016)
			)
			(exclude_from_sim no)
			(in_bom yes)
			(on_board yes)
			(property "Reference" "U"
				(at 38.1 -2.54 0)
				(effects
					(font
						(size 1.27 1.27)
						(thickness 0.15)
					)
					(justify left bottom)
				)
			)
			(property "Value" "USB3300-EZK-TR"
				(at 38.1 -5.08 0)
				(effects
					(font
						(size 1.27 1.27)
						(thickness 0.15)
					)
					(justify left bottom)
					(hide yes)
				)
			)
			(property "Footprint" "antmicro-footprints:QFN-32-1EP_5x5mm"
				(at 38.1 -7.62 0)
				(effects
					(font
						(size 1.27 1.27)
						(thickness 0.15)
					)
					(justify left bottom)
					(hide yes)
				)
			)
			(property "Datasheet" "https://ww1.microchip.com/downloads/en/DeviceDoc/00001783C.pdf"
				(at 38.1 -10.16 0)
				(effects
					(font
						(size 1.27 1.27)
						(thickness 0.15)
					)
					(justify left bottom)
					(hide yes)
				)
			)
			(property "Description" "USB Interface, USB Host Controller, USB 2.0 OTG, 3 V, 3.6 V, VQFN, 32 Pins"
				(at 38.1 -22.86 0)
				(effects
					(font
						(size 1.27 1.27)
					)
					(justify left bottom)
					(hide yes)
				)
			)
			(property "Manufacturer" "Microchip Technology"
				(at 38.1 -12.7 0)
				(effects
					(font
						(size 1.27 1.27)
						(thickness 0.15)
					)
					(justify left bottom)
					(hide yes)
				)
			)
			(property "MPN" "USB3300-EZK-TR"
				(at 38.1 -15.24 0)
				(effects
					(font
						(size 1.27 1.27)
						(thickness 0.15)
					)
					(justify left bottom)
				)
			)
			(property "Author" "Antmicro"
				(at 38.1 -17.78 0)
				(effects
					(font
						(size 1.27 1.27)
						(thickness 0.15)
					)
					(justify left bottom)
					(hide yes)
				)
			)
			(property "License" "Apache-2.0"
				(at 38.1 -20.32 0)
				(effects
					(font
						(size 1.27 1.27)
						(thickness 0.15)
					)
					(justify left bottom)
					(hide yes)
				)
			)
			(property "ki_keywords" "SMT, INTERFACE, CONTROLLER, IC, USB"
				(at 0 0 0)
				(effects
					(font
						(size 1.27 1.27)
					)
					(hide yes)
				)
			)
			(symbol "USB3300-EZK-TR_0_0"
				(rectangle
					(start 2.54 2.54)
					(end 21.59 -45.72)
					(stroke
						(width 0)
						(type default)
					)
					(fill
						(type background)
					)
				)
				(pin passive line
					(at 0 0 0)
					(length 2.54)
					(hide yes)
					(name "VDD3.3"
						(effects
							(font
								(size 1.27 1.27)
							)
						)
					)
					(number "16"
						(effects
							(font
								(size 1.27 1.27)
							)
						)
					)
				)
				(pin passive line
					(at 0 0 0)
					(length 2.54)
					(hide yes)
					(name "VDD3.3"
						(effects
							(font
								(size 1.27 1.27)
							)
						)
					)
					(number "25"
						(effects
							(font
								(size 1.27 1.27)
							)
						)
					)
				)
				(pin passive line
					(at 0 0 0)
					(length 2.54)
					(hide yes)
					(name "VDD3.3"
						(effects
							(font
								(size 1.27 1.27)
							)
						)
					)
					(number "30"
						(effects
							(font
								(size 1.27 1.27)
							)
						)
					)
				)
				(pin power_in line
					(at 0 0 0)
					(length 2.54)
					(name "VDD3.3"
						(effects
							(font
								(size 1.27 1.27)
							)
						)
					)
					(number "6"
						(effects
							(font
								(size 1.27 1.27)
							)
						)
					)
				)
				(pin bidirectional line
					(at 0 -2.54 0)
					(length 2.54)
					(name "REG_EN"
						(effects
							(font
								(size 1.27 1.27)
							)
						)
					)
					(number "31"
						(effects
							(font
								(size 1.27 1.27)
							)
						)
					)
				)
				(pin bidirectional line
					(at 0 -7.62 0)
					(length 2.54)
					(name "DM"
						(effects
							(font
								(size 1.27 1.27)
							)
						)
					)
					(number "8"
						(effects
							(font
								(size 1.27 1.27)
							)
						)
					)
				)
				(pin bidirectional line
					(at 0 -10.16 0)
					(length 2.54)
					(name "DP"
						(effects
							(font
								(size 1.27 1.27)
							)
						)
					)
					(number "7"
						(effects
							(font
								(size 1.27 1.27)
							)
						)
					)
				)
				(pin input line
					(at 0 -15.24 0)
					(length 2.54)
					(name "ID"
						(effects
							(font
								(size 1.27 1.27)
							)
						)
					)
					(number "5"
						(effects
							(font
								(size 1.27 1.27)
							)
						)
					)
				)
				(pin bidirectional line
					(at 0 -17.78 0)
					(length 2.54)
					(name "VBUS"
						(effects
							(font
								(size 1.27 1.27)
							)
						)
					)
					(number "4"
						(effects
							(font
								(size 1.27 1.27)
							)
						)
					)
				)
				(pin output line
					(at 0 -20.32 0)
					(length 2.54)
					(name "CPEN"
						(effects
							(font
								(size 1.27 1.27)
							)
						)
					)
					(number "3"
						(effects
							(font
								(size 1.27 1.27)
							)
						)
					)
				)
				(pin input line
					(at 0 -22.86 0)
					(length 2.54)
					(name "EXTVBUS"
						(effects
							(font
								(size 1.27 1.27)
							)
						)
					)
					(number "10"
						(effects
							(font
								(size 1.27 1.27)
							)
						)
					)
				)
				(pin output line
					(at 0 -34.29 0)
					(length 2.54)
					(name "XO"
						(effects
							(font
								(size 1.27 1.27)
							)
						)
					)
					(number "27"
						(effects
							(font
								(size 1.27 1.27)
							)
						)
					)
				)
				(pin input line
					(at 0 -36.83 0)
					(length 2.54)
					(name "XI"
						(effects
							(font
								(size 1.27 1.27)
							)
						)
					)
					(number "28"
						(effects
							(font
								(size 1.27 1.27)
							)
						)
					)
				)
				(pin bidirectional line
					(at 0 -40.64 0)
					(length 2.54)
					(name "RBIAS"
						(effects
							(font
								(size 1.27 1.27)
							)
						)
					)
					(number "32"
						(effects
							(font
								(size 1.27 1.27)
							)
						)
					)
				)
				(pin power_in line
					(at 0 -43.18 0)
					(length 2.54)
					(name "GND"
						(effects
							(font
								(size 1.27 1.27)
							)
						)
					)
					(number "1"
						(effects
							(font
								(size 1.27 1.27)
							)
						)
					)
				)
				(pin passive line
					(at 0 -43.18 0)
					(length 2.54)
					(hide yes)
					(name "GND"
						(effects
							(font
								(size 1.27 1.27)
							)
						)
					)
					(number "2"
						(effects
							(font
								(size 1.27 1.27)
							)
						)
					)
				)
				(pin passive line
					(at 0 -43.18 0)
					(length 2.54)
					(hide yes)
					(name "EP"
						(effects
							(font
								(size 1.27 1.27)
							)
						)
					)
					(number "33"
						(effects
							(font
								(size 1.27 1.27)
							)
						)
					)
				)
				(pin power_in line
					(at 24.13 0 180)
					(length 2.54)
					(name "VDD1.8"
						(effects
							(font
								(size 1.27 1.27)
							)
						)
					)
					(number "15"
						(effects
							(font
								(size 1.27 1.27)
							)
						)
					)
				)
				(pin passive line
					(at 24.13 0 180)
					(length 2.54)
					(hide yes)
					(name "VDD1.8"
						(effects
							(font
								(size 1.27 1.27)
							)
						)
					)
					(number "26"
						(effects
							(font
								(size 1.27 1.27)
							)
						)
					)
				)
				(pin power_in line
					(at 24.13 -2.54 180)
					(length 2.54)
					(name "VDDA1.8"
						(effects
							(font
								(size 1.27 1.27)
							)
						)
					)
					(number "29"
						(effects
							(font
								(size 1.27 1.27)
							)
						)
					)
				)
				(pin bidirectional line
					(at 24.13 -7.62 180)
					(length 2.54)
					(name "DATA[0]"
						(effects
							(font
								(size 1.27 1.27)
							)
						)
					)
					(number "24"
						(effects
							(font
								(size 1.27 1.27)
							)
						)
					)
				)
				(pin bidirectional line
					(at 24.13 -10.16 180)
					(length 2.54)
					(name "DATA[1]"
						(effects
							(font
								(size 1.27 1.27)
							)
						)
					)
					(number "23"
						(effects
							(font
								(size 1.27 1.27)
							)
						)
					)
				)
				(pin bidirectional line
					(at 24.13 -12.7 180)
					(length 2.54)
					(name "DATA[2]"
						(effects
							(font
								(size 1.27 1.27)
							)
						)
					)
					(number "22"
						(effects
							(font
								(size 1.27 1.27)
							)
						)
					)
				)
				(pin bidirectional line
					(at 24.13 -15.24 180)
					(length 2.54)
					(name "DATA[3]"
						(effects
							(font
								(size 1.27 1.27)
							)
						)
					)
					(number "21"
						(effects
							(font
								(size 1.27 1.27)
							)
						)
					)
				)
				(pin bidirectional line
					(at 24.13 -17.78 180)
					(length 2.54)
					(name "DATA[4]"
						(effects
							(font
								(size 1.27 1.27)
							)
						)
					)
					(number "20"
						(effects
							(font
								(size 1.27 1.27)
							)
						)
					)
				)
				(pin bidirectional line
					(at 24.13 -20.32 180)
					(length 2.54)
					(name "DATA[5]"
						(effects
							(font
								(size 1.27 1.27)
							)
						)
					)
					(number "19"
						(effects
							(font
								(size 1.27 1.27)
							)
						)
					)
				)
				(pin bidirectional line
					(at 24.13 -22.86 180)
					(length 2.54)
					(name "DATA[6]"
						(effects
							(font
								(size 1.27 1.27)
							)
						)
					)
					(number "18"
						(effects
							(font
								(size 1.27 1.27)
							)
						)
					)
				)
				(pin bidirectional line
					(at 24.13 -25.4 180)
					(length 2.54)
					(name "DATA[7]"
						(effects
							(font
								(size 1.27 1.27)
							)
						)
					)
					(number "17"
						(effects
							(font
								(size 1.27 1.27)
							)
						)
					)
				)
				(pin output line
					(at 24.13 -30.48 180)
					(length 2.54)
					(name "NXT"
						(effects
							(font
								(size 1.27 1.27)
							)
						)
					)
					(number "11"
						(effects
							(font
								(size 1.27 1.27)
							)
						)
					)
				)
				(pin output line
					(at 24.13 -33.02 180)
					(length 2.54)
					(name "DIR"
						(effects
							(font
								(size 1.27 1.27)
							)
						)
					)
					(number "12"
						(effects
							(font
								(size 1.27 1.27)
							)
						)
					)
				)
				(pin input line
					(at 24.13 -35.56 180)
					(length 2.54)
					(name "STP"
						(effects
							(font
								(size 1.27 1.27)
							)
						)
					)
					(number "13"
						(effects
							(font
								(size 1.27 1.27)
							)
						)
					)
				)
				(pin output clock
					(at 24.13 -38.1 180)
					(length 2.54)
					(name "CLKOUT"
						(effects
							(font
								(size 1.27 1.27)
							)
						)
					)
					(number "14"
						(effects
							(font
								(size 1.27 1.27)
							)
						)
					)
				)
				(pin input line
					(at 24.13 -40.64 180)
					(length 2.54)
					(name "RESET"
						(effects
							(font
								(size 1.27 1.27)
							)
						)
					)
					(number "9"
						(effects
							(font
								(size 1.27 1.27)
							)
						)
					)
				)
			)
		)
	(symbol "antmicroLEDIndicationDiscrete:LED_G_0603_KP-1608CGCK"
			(pin_numbers
				(hide yes)
			)
			(pin_names
				(hide yes)
			)
			(exclude_from_sim no)
			(in_bom yes)
			(on_board yes)
			(property "Reference" "D"
				(at 22.86 -2.54 0)
				(effects
					(font
						(size 1.27 1.27)
						(thickness 0.15)
					)
					(justify left bottom)
				)
			)
			(property "Value" "LED_G_0603_KP-1608CGCK"
				(at 22.86 -7.62 0)
				(effects
					(font
						(size 1.27 1.27)
						(thickness 0.15)
					)
					(justify left bottom)
					(hide yes)
				)
			)
			(property "Footprint" "antmicro-footprints:LED_0603_1608Metric_G"
				(at 22.86 -10.16 0)
				(effects
					(font
						(size 1.27 1.27)
						(thickness 0.15)
					)
					(justify left bottom)
					(hide yes)
				)
			)
			(property "Datasheet" "http://www.kingbright.com/attachments/file/psearch//000/00/00/KP-1608CGCK(Ver.23B).pdf"
				(at 22.86 -12.7 0)
				(effects
					(font
						(size 1.27 1.27)
						(thickness 0.15)
					)
					(justify left bottom)
					(hide yes)
				)
			)
			(property "Description" "LED, Green, SMD, 0603, 20 mA, 2.1 V, 570 nm"
				(at 22.86 -25.4 0)
				(effects
					(font
						(size 1.27 1.27)
					)
					(justify left bottom)
					(hide yes)
				)
			)
			(property "MPN" "KP-1608CGCK"
				(at 22.86 -15.24 0)
				(effects
					(font
						(size 1.27 1.27)
						(thickness 0.15)
					)
					(justify left bottom)
					(hide yes)
				)
			)
			(property "Manufacturer" "Kingbright"
				(at 22.86 -17.78 0)
				(effects
					(font
						(size 1.27 1.27)
						(thickness 0.15)
					)
					(justify left bottom)
					(hide yes)
				)
			)
			(property "Color" "Green"
				(at 22.86 -5.08 0)
				(effects
					(font
						(size 1.27 1.27)
					)
					(justify left bottom)
				)
			)
			(property "Author" "Antmicro"
				(at 22.86 -20.32 0)
				(effects
					(font
						(size 1.27 1.27)
						(thickness 0.15)
					)
					(justify left bottom)
					(hide yes)
				)
			)
			(property "License" "Apache-2.0"
				(at 22.86 -22.86 0)
				(effects
					(font
						(size 1.27 1.27)
						(thickness 0.15)
					)
					(justify left bottom)
					(hide yes)
				)
			)
			(property "ki_keywords" "SMT, DIODE, SEMICONDUCTOR, LED"
				(at 0 0 0)
				(effects
					(font
						(size 1.27 1.27)
					)
					(hide yes)
				)
			)
			(symbol "LED_G_0603_KP-1608CGCK_0_1"
				(polyline
					(pts
						(xy 1.905 0) (xy 0.635 0)
					)
					(stroke
						(width 0)
						(type default)
					)
					(fill
						(type none)
					)
				)
				(polyline
					(pts
						(xy 4.445 0) (xy 3.175 0)
					)
					(stroke
						(width 0)
						(type default)
					)
					(fill
						(type none)
					)
				)
			)
			(symbol "LED_G_0603_KP-1608CGCK_1_1"
				(polyline
					(pts
						(xy 1.143 2.286) (xy 1.143 1.778) (xy 1.143 2.286) (xy 1.651 2.286) (xy 1.143 2.286) (xy 2.159 1.27)
					)
					(stroke
						(width 0.254)
						(type default)
					)
					(fill
						(type none)
					)
				)
				(polyline
					(pts
						(xy 1.778 1.016) (xy 1.778 -1.016)
					)
					(stroke
						(width 0.254)
						(type default)
					)
					(fill
						(type none)
					)
				)
				(polyline
					(pts
						(xy 2.159 2.54) (xy 2.159 2.032) (xy 2.159 2.54) (xy 2.667 2.54) (xy 2.159 2.54) (xy 3.048 1.651)
					)
					(stroke
						(width 0.254)
						(type default)
					)
					(fill
						(type none)
					)
				)
				(polyline
					(pts
						(xy 3.302 1.016) (xy 3.302 -1.016) (xy 1.778 0) (xy 3.302 1.016)
					)
					(stroke
						(width 0.254)
						(type default)
					)
					(fill
						(type outline)
					)
				)
				(pin passive line
					(at 0 0 0)
					(length 0.635)
					(name "C"
						(effects
							(font
								(size 1.27 1.27)
							)
						)
					)
					(number "1"
						(effects
							(font
								(size 1.27 1.27)
							)
						)
					)
				)
				(pin passive line
					(at 5.08 0 180)
					(length 0.635)
					(name "A"
						(effects
							(font
								(size 1.27 1.27)
							)
						)
					)
					(number "2"
						(effects
							(font
								(size 1.27 1.27)
							)
						)
					)
				)
			)
		)
	(symbol "antmicroLEDIndicationDiscrete:LED_G_0603_LG_L29K-G2J1-24-Z"
			(pin_numbers
				(hide yes)
			)
			(pin_names
				(hide yes)
			)
			(exclude_from_sim no)
			(in_bom yes)
			(on_board yes)
			(property "Reference" "D"
				(at 20.32 -2.54 0)
				(effects
					(font
						(size 1.27 1.27)
						(thickness 0.15)
					)
					(justify left bottom)
				)
			)
			(property "Value" "LED_G_0603_LG_L29K-G2J1-24-Z"
				(at 20.32 -7.62 0)
				(effects
					(font
						(size 1.27 1.27)
						(thickness 0.15)
					)
					(justify left bottom)
					(hide yes)
				)
			)
			(property "Footprint" "antmicro-footprints:LED_0603_1608Metric_G"
				(at 20.32 -10.16 0)
				(effects
					(font
						(size 1.27 1.27)
						(thickness 0.15)
					)
					(justify left bottom)
					(hide yes)
				)
			)
			(property "Datasheet" "https://look.ams-osram.com/m/19ee86b3ae0ee95b/original/LG-L29K.pdf"
				(at 20.32 -12.7 0)
				(effects
					(font
						(size 1.27 1.27)
						(thickness 0.15)
					)
					(justify left bottom)
					(hide yes)
				)
			)
			(property "Description" "LED, Green, SMD, 0603, 20 mA, 1.7 V, 570 nm"
				(at 20.32 -25.4 0)
				(effects
					(font
						(size 1.27 1.27)
					)
					(justify left bottom)
					(hide yes)
				)
			)
			(property "MPN" "LG L29K-G2J1-24-Z"
				(at 20.32 -15.24 0)
				(effects
					(font
						(size 1.27 1.27)
						(thickness 0.15)
					)
					(justify left bottom)
					(hide yes)
				)
			)
			(property "Manufacturer" "OSRAM"
				(at 20.32 -17.78 0)
				(effects
					(font
						(size 1.27 1.27)
						(thickness 0.15)
					)
					(justify left bottom)
					(hide yes)
				)
			)
			(property "Color" "Green"
				(at 20.32 -5.08 0)
				(effects
					(font
						(size 1.27 1.27)
					)
					(justify left bottom)
				)
			)
			(property "Author" "Antmicro"
				(at 20.32 -20.32 0)
				(effects
					(font
						(size 1.27 1.27)
						(thickness 0.15)
					)
					(justify left bottom)
					(hide yes)
				)
			)
			(property "License" "Apache-2.0"
				(at 20.32 -22.86 0)
				(effects
					(font
						(size 1.27 1.27)
						(thickness 0.15)
					)
					(justify left bottom)
					(hide yes)
				)
			)
			(property "ki_keywords" "SMT, DIODE, SEMICONDUCTOR, LED"
				(at 0 0 0)
				(effects
					(font
						(size 1.27 1.27)
					)
					(hide yes)
				)
			)
			(symbol "LED_G_0603_LG_L29K-G2J1-24-Z_0_1"
				(polyline
					(pts
						(xy 1.905 0) (xy 0.635 0)
					)
					(stroke
						(width 0)
						(type default)
					)
					(fill
						(type none)
					)
				)
				(polyline
					(pts
						(xy 4.445 0) (xy 3.175 0)
					)
					(stroke
						(width 0)
						(type default)
					)
					(fill
						(type none)
					)
				)
			)
			(symbol "LED_G_0603_LG_L29K-G2J1-24-Z_1_1"
				(polyline
					(pts
						(xy 1.143 2.286) (xy 1.143 1.778) (xy 1.143 2.286) (xy 1.651 2.286) (xy 1.143 2.286) (xy 2.159 1.27)
					)
					(stroke
						(width 0.254)
						(type default)
					)
					(fill
						(type none)
					)
				)
				(polyline
					(pts
						(xy 1.778 1.016) (xy 1.778 -1.016)
					)
					(stroke
						(width 0.254)
						(type default)
					)
					(fill
						(type none)
					)
				)
				(polyline
					(pts
						(xy 2.159 2.54) (xy 2.159 2.032) (xy 2.159 2.54) (xy 2.667 2.54) (xy 2.159 2.54) (xy 3.048 1.651)
					)
					(stroke
						(width 0.254)
						(type default)
					)
					(fill
						(type none)
					)
				)
				(polyline
					(pts
						(xy 3.302 1.016) (xy 3.302 -1.016) (xy 1.778 0) (xy 3.302 1.016)
					)
					(stroke
						(width 0.254)
						(type default)
					)
					(fill
						(type outline)
					)
				)
				(pin passive line
					(at 0 0 0)
					(length 0.635)
					(name "C"
						(effects
							(font
								(size 1.27 1.27)
							)
						)
					)
					(number "1"
						(effects
							(font
								(size 1.27 1.27)
							)
						)
					)
				)
				(pin passive line
					(at 5.08 0 180)
					(length 0.635)
					(name "A"
						(effects
							(font
								(size 1.27 1.27)
							)
						)
					)
					(number "2"
						(effects
							(font
								(size 1.27 1.27)
							)
						)
					)
				)
			)
		)
	(symbol "antmicroLogicTranslatorsLevelShifters:LSF0101DRYR"
			(pin_names
				(offset 1.016)
			)
			(exclude_from_sim no)
			(in_bom yes)
			(on_board yes)
			(property "Reference" "U"
				(at 33.02 -2.54 0)
				(effects
					(font
						(size 1.27 1.27)
						(thickness 0.15)
					)
					(justify left bottom)
				)
			)
			(property "Value" "LSF0101DRYR"
				(at 33.02 -5.08 0)
				(effects
					(font
						(size 1.27 1.27)
						(thickness 0.15)
					)
					(justify left bottom)
					(hide yes)
				)
			)
			(property "Footprint" "antmicro-footprints:USON-6_1.45x1.0mm_P0.5mm_Texas_DRY6"
				(at 33.02 -7.62 0)
				(effects
					(font
						(size 1.27 1.27)
						(thickness 0.15)
					)
					(justify left bottom)
					(hide yes)
				)
			)
			(property "Datasheet" "https://www.ti.com/lit/ds/symlink/lsf0101.pdf?ts=1686656250822&ref_url=https%253A%252F%252Fwww.ti.com%252Fproduct%252FLSF0101%252Fpart-details%252FLSF0101DRYR"
				(at 33.02 -10.16 0)
				(effects
					(font
						(size 1.27 1.27)
						(thickness 0.15)
					)
					(justify left bottom)
					(hide yes)
				)
			)
			(property "Description" "Voltage Level Translator, 1 Input, 1.5 ns, 0 V to 5 V, SON-6"
				(at 33.02 -22.86 0)
				(effects
					(font
						(size 1.27 1.27)
					)
					(justify left bottom)
					(hide yes)
				)
			)
			(property "MPN" "LSF0101DRYR"
				(at 33.02 -12.7 0)
				(effects
					(font
						(size 1.27 1.27)
						(thickness 0.15)
					)
					(justify left bottom)
				)
			)
			(property "Manufacturer" "Texas Instruments"
				(at 33.02 -15.24 0)
				(effects
					(font
						(size 1.27 1.27)
						(thickness 0.15)
					)
					(justify left bottom)
					(hide yes)
				)
			)
			(property "Author" "Antmicro"
				(at 33.02 -17.78 0)
				(effects
					(font
						(size 1.27 1.27)
						(thickness 0.15)
					)
					(justify left bottom)
					(hide yes)
				)
			)
			(property "License" "Apache-2.0"
				(at 33.02 -20.32 0)
				(effects
					(font
						(size 1.27 1.27)
						(thickness 0.15)
					)
					(justify left bottom)
					(hide yes)
				)
			)
			(property "ki_keywords" "SMT, LOGIC, IC, LEVEL-SHIFTER, VOLTAGE"
				(at 0 0 0)
				(effects
					(font
						(size 1.27 1.27)
					)
					(hide yes)
				)
			)
			(symbol "LSF0101DRYR_0_0"
				(rectangle
					(start 2.54 2.54)
					(end 16.51 -12.7)
					(stroke
						(width 0)
						(type default)
					)
					(fill
						(type background)
					)
				)
				(pin input line
					(at 0 0 0)
					(length 2.54)
					(name "VREF_{A}"
						(effects
							(font
								(size 1.27 1.27)
							)
						)
					)
					(number "2"
						(effects
							(font
								(size 1.27 1.27)
							)
						)
					)
				)
				(pin bidirectional line
					(at 0 -6.35 0)
					(length 2.54)
					(name "A1"
						(effects
							(font
								(size 1.27 1.27)
							)
						)
					)
					(number "3"
						(effects
							(font
								(size 1.27 1.27)
							)
						)
					)
				)
				(pin input line
					(at 19.05 0 180)
					(length 2.54)
					(name "VREF_{B}"
						(effects
							(font
								(size 1.27 1.27)
							)
						)
					)
					(number "5"
						(effects
							(font
								(size 1.27 1.27)
							)
						)
					)
				)
				(pin input line
					(at 19.05 -2.54 180)
					(length 2.54)
					(name "EN"
						(effects
							(font
								(size 1.27 1.27)
							)
						)
					)
					(number "6"
						(effects
							(font
								(size 1.27 1.27)
							)
						)
					)
				)
				(pin bidirectional line
					(at 19.05 -6.35 180)
					(length 2.54)
					(name "B1"
						(effects
							(font
								(size 1.27 1.27)
							)
						)
					)
					(number "4"
						(effects
							(font
								(size 1.27 1.27)
							)
						)
					)
				)
				(pin power_in line
					(at 19.05 -10.16 180)
					(length 2.54)
					(name "GND"
						(effects
							(font
								(size 1.27 1.27)
							)
						)
					)
					(number "1"
						(effects
							(font
								(size 1.27 1.27)
							)
						)
					)
				)
			)
		)
	(symbol "antmicroLogicTranslatorsLevelShifters:LSF0108RKSR"
			(pin_names
				(offset 1.016)
			)
			(exclude_from_sim no)
			(in_bom yes)
			(on_board yes)
			(property "Reference" "U"
				(at 33.02 -2.54 0)
				(effects
					(font
						(size 1.27 1.27)
						(thickness 0.15)
					)
					(justify left bottom)
				)
			)
			(property "Value" "LSF0108RKSR"
				(at 33.02 -5.08 0)
				(effects
					(font
						(size 1.27 1.27)
						(thickness 0.15)
					)
					(justify left bottom)
					(hide yes)
				)
			)
			(property "Footprint" "antmicro-footprints:VQFN-20_1EP_4.5x2.5mm_P0.5mm"
				(at 33.02 -7.62 0)
				(effects
					(font
						(size 1.27 1.27)
						(thickness 0.15)
					)
					(justify left bottom)
					(hide yes)
				)
			)
			(property "Datasheet" "https://www.ti.com/lit/ds/symlink/lsf0108.pdf?ts=1686550470995&ref_url=https%253A%252F%252Fwww.ti.com%252Fproduct%252FLSF0108%252Fpart-details%252FLSF0108RKSR"
				(at 33.02 -10.16 0)
				(effects
					(font
						(size 1.27 1.27)
						(thickness 0.15)
					)
					(justify left bottom)
					(hide yes)
				)
			)
			(property "Description" "Voltage Level Translator, 8 Input, 1.5 ns, 0 V to 5 V, VQFN-20"
				(at 33.02 -22.86 0)
				(effects
					(font
						(size 1.27 1.27)
					)
					(justify left bottom)
					(hide yes)
				)
			)
			(property "Manufacturer" "Texas Instruments"
				(at 33.02 -12.7 0)
				(effects
					(font
						(size 1.27 1.27)
						(thickness 0.15)
					)
					(justify left bottom)
					(hide yes)
				)
			)
			(property "MPN" "LSF0108RKSR"
				(at 33.02 -15.24 0)
				(effects
					(font
						(size 1.27 1.27)
						(thickness 0.15)
					)
					(justify left bottom)
				)
			)
			(property "Author" "Antmicro"
				(at 33.02 -17.78 0)
				(effects
					(font
						(size 1.27 1.27)
						(thickness 0.15)
					)
					(justify left bottom)
					(hide yes)
				)
			)
			(property "License" "Apache-2.0"
				(at 33.02 -20.32 0)
				(effects
					(font
						(size 1.27 1.27)
						(thickness 0.15)
					)
					(justify left bottom)
					(hide yes)
				)
			)
			(property "ki_keywords" "SMT, LOGIC, IC, LEVEL-SHIFTER, VOLTAGE"
				(at 0 0 0)
				(effects
					(font
						(size 1.27 1.27)
					)
					(hide yes)
				)
			)
			(symbol "LSF0108RKSR_0_0"
				(rectangle
					(start 2.54 2.54)
					(end 16.51 -33.02)
					(stroke
						(width 0)
						(type default)
					)
					(fill
						(type background)
					)
				)
				(pin power_in line
					(at 0 0 0)
					(length 2.54)
					(name "VREF_{A}"
						(effects
							(font
								(size 1.27 1.27)
							)
						)
					)
					(number "2"
						(effects
							(font
								(size 1.27 1.27)
							)
						)
					)
				)
				(pin bidirectional line
					(at 0 -6.35 0)
					(length 2.54)
					(name "A1"
						(effects
							(font
								(size 1.27 1.27)
							)
						)
					)
					(number "3"
						(effects
							(font
								(size 1.27 1.27)
							)
						)
					)
				)
				(pin bidirectional line
					(at 0 -8.89 0)
					(length 2.54)
					(name "A2"
						(effects
							(font
								(size 1.27 1.27)
							)
						)
					)
					(number "4"
						(effects
							(font
								(size 1.27 1.27)
							)
						)
					)
				)
				(pin bidirectional line
					(at 0 -11.43 0)
					(length 2.54)
					(name "A3"
						(effects
							(font
								(size 1.27 1.27)
							)
						)
					)
					(number "5"
						(effects
							(font
								(size 1.27 1.27)
							)
						)
					)
				)
				(pin bidirectional line
					(at 0 -13.97 0)
					(length 2.54)
					(name "A4"
						(effects
							(font
								(size 1.27 1.27)
							)
						)
					)
					(number "6"
						(effects
							(font
								(size 1.27 1.27)
							)
						)
					)
				)
				(pin bidirectional line
					(at 0 -16.51 0)
					(length 2.54)
					(name "A5"
						(effects
							(font
								(size 1.27 1.27)
							)
						)
					)
					(number "7"
						(effects
							(font
								(size 1.27 1.27)
							)
						)
					)
				)
				(pin bidirectional line
					(at 0 -19.05 0)
					(length 2.54)
					(name "A6"
						(effects
							(font
								(size 1.27 1.27)
							)
						)
					)
					(number "8"
						(effects
							(font
								(size 1.27 1.27)
							)
						)
					)
				)
				(pin bidirectional line
					(at 0 -21.59 0)
					(length 2.54)
					(name "A7"
						(effects
							(font
								(size 1.27 1.27)
							)
						)
					)
					(number "9"
						(effects
							(font
								(size 1.27 1.27)
							)
						)
					)
				)
				(pin bidirectional line
					(at 0 -24.13 0)
					(length 2.54)
					(name "A8"
						(effects
							(font
								(size 1.27 1.27)
							)
						)
					)
					(number "10"
						(effects
							(font
								(size 1.27 1.27)
							)
						)
					)
				)
				(pin power_in line
					(at 19.05 0 180)
					(length 2.54)
					(name "VREF_{B}"
						(effects
							(font
								(size 1.27 1.27)
							)
						)
					)
					(number "19"
						(effects
							(font
								(size 1.27 1.27)
							)
						)
					)
				)
				(pin input line
					(at 19.05 -2.54 180)
					(length 2.54)
					(name "EN"
						(effects
							(font
								(size 1.27 1.27)
							)
						)
					)
					(number "20"
						(effects
							(font
								(size 1.27 1.27)
							)
						)
					)
				)
				(pin bidirectional line
					(at 19.05 -6.35 180)
					(length 2.54)
					(name "B1"
						(effects
							(font
								(size 1.27 1.27)
							)
						)
					)
					(number "18"
						(effects
							(font
								(size 1.27 1.27)
							)
						)
					)
				)
				(pin bidirectional line
					(at 19.05 -8.89 180)
					(length 2.54)
					(name "B2"
						(effects
							(font
								(size 1.27 1.27)
							)
						)
					)
					(number "17"
						(effects
							(font
								(size 1.27 1.27)
							)
						)
					)
				)
				(pin bidirectional line
					(at 19.05 -11.43 180)
					(length 2.54)
					(name "B3"
						(effects
							(font
								(size 1.27 1.27)
							)
						)
					)
					(number "16"
						(effects
							(font
								(size 1.27 1.27)
							)
						)
					)
				)
				(pin bidirectional line
					(at 19.05 -13.97 180)
					(length 2.54)
					(name "B4"
						(effects
							(font
								(size 1.27 1.27)
							)
						)
					)
					(number "15"
						(effects
							(font
								(size 1.27 1.27)
							)
						)
					)
				)
				(pin bidirectional line
					(at 19.05 -16.51 180)
					(length 2.54)
					(name "B5"
						(effects
							(font
								(size 1.27 1.27)
							)
						)
					)
					(number "14"
						(effects
							(font
								(size 1.27 1.27)
							)
						)
					)
				)
				(pin bidirectional line
					(at 19.05 -19.05 180)
					(length 2.54)
					(name "B6"
						(effects
							(font
								(size 1.27 1.27)
							)
						)
					)
					(number "13"
						(effects
							(font
								(size 1.27 1.27)
							)
						)
					)
				)
				(pin bidirectional line
					(at 19.05 -21.59 180)
					(length 2.54)
					(name "B7"
						(effects
							(font
								(size 1.27 1.27)
							)
						)
					)
					(number "12"
						(effects
							(font
								(size 1.27 1.27)
							)
						)
					)
				)
				(pin bidirectional line
					(at 19.05 -24.13 180)
					(length 2.54)
					(name "B8"
						(effects
							(font
								(size 1.27 1.27)
							)
						)
					)
					(number "11"
						(effects
							(font
								(size 1.27 1.27)
							)
						)
					)
				)
				(pin power_in line
					(at 19.05 -27.94 180)
					(length 2.54)
					(name "GND"
						(effects
							(font
								(size 1.27 1.27)
							)
						)
					)
					(number "1"
						(effects
							(font
								(size 1.27 1.27)
							)
						)
					)
				)
				(pin power_in line
					(at 19.05 -30.48 180)
					(length 2.54)
					(name "EP"
						(effects
							(font
								(size 1.27 1.27)
							)
						)
					)
					(number "21"
						(effects
							(font
								(size 1.27 1.27)
							)
						)
					)
				)
			)
		)
	(symbol "antmicroLogicTranslatorsLevelShifters:NVT2008BQ,115"
			(pin_names
				(offset 1.016)
			)
			(exclude_from_sim no)
			(in_bom yes)
			(on_board yes)
			(property "Reference" "U"
				(at 35.56 -2.54 0)
				(effects
					(font
						(size 1.27 1.27)
						(thickness 0.15)
					)
					(justify left bottom)
				)
			)
			(property "Value" "NVT2008BQ,115"
				(at 35.56 -5.08 0)
				(effects
					(font
						(size 1.27 1.27)
						(thickness 0.15)
					)
					(justify left bottom)
					(hide yes)
				)
			)
			(property "Footprint" "antmicro-footprints:VQFN-20_1EP_4.5x2.5mm_P0.5mm"
				(at 35.56 -7.62 0)
				(effects
					(font
						(size 1.27 1.27)
						(thickness 0.15)
					)
					(justify left bottom)
					(hide yes)
				)
			)
			(property "Datasheet" "https://www.nxp.com/docs/en/data-sheet/NVT2008_NVT2010.pdf"
				(at 35.56 -10.16 0)
				(effects
					(font
						(size 1.27 1.27)
						(thickness 0.15)
					)
					(justify left bottom)
					(hide yes)
				)
			)
			(property "Description" "Bidirectional Voltage Level Translator, 8 Inputs, 1.5ns, 1.8V to 5.5V, DHVQFN-20"
				(at 35.56 -22.86 0)
				(effects
					(font
						(size 1.27 1.27)
					)
					(justify left bottom)
					(hide yes)
				)
			)
			(property "MPN" "NVT2008BQ,115"
				(at 35.56 -12.7 0)
				(effects
					(font
						(size 1.27 1.27)
						(thickness 0.15)
					)
					(justify left bottom)
				)
			)
			(property "Manufacturer" "NXP"
				(at 35.56 -15.24 0)
				(effects
					(font
						(size 1.27 1.27)
						(thickness 0.15)
					)
					(justify left bottom)
					(hide yes)
				)
			)
			(property "Author" "Antmicro"
				(at 35.56 -17.78 0)
				(effects
					(font
						(size 1.27 1.27)
						(thickness 0.15)
					)
					(justify left bottom)
					(hide yes)
				)
			)
			(property "License" "Apache-2.0"
				(at 35.56 -20.32 0)
				(effects
					(font
						(size 1.27 1.27)
						(thickness 0.15)
					)
					(justify left bottom)
					(hide yes)
				)
			)
			(property "ki_keywords" "SMT, LEVEL-SHIFTER, IC, LOGIC"
				(at 0 0 0)
				(effects
					(font
						(size 1.27 1.27)
					)
					(hide yes)
				)
			)
			(symbol "NVT2008BQ,115_0_1"
				(rectangle
					(start 2.54 2.54)
					(end 17.78 -34.29)
					(stroke
						(width 0)
						(type default)
					)
					(fill
						(type background)
					)
				)
			)
			(symbol "NVT2008BQ,115_1_1"
				(pin power_in line
					(at 0 0 0)
					(length 2.54)
					(name "VREFA"
						(effects
							(font
								(size 1.27 1.27)
							)
						)
					)
					(number "2"
						(effects
							(font
								(size 1.27 1.27)
							)
						)
					)
				)
				(pin bidirectional line
					(at 0 -7.62 0)
					(length 2.54)
					(name "A1"
						(effects
							(font
								(size 1.27 1.27)
							)
						)
					)
					(number "3"
						(effects
							(font
								(size 1.27 1.27)
							)
						)
					)
				)
				(pin bidirectional line
					(at 0 -10.16 0)
					(length 2.54)
					(name "A2"
						(effects
							(font
								(size 1.27 1.27)
							)
						)
					)
					(number "4"
						(effects
							(font
								(size 1.27 1.27)
							)
						)
					)
				)
				(pin bidirectional line
					(at 0 -12.7 0)
					(length 2.54)
					(name "A3"
						(effects
							(font
								(size 1.27 1.27)
							)
						)
					)
					(number "5"
						(effects
							(font
								(size 1.27 1.27)
							)
						)
					)
				)
				(pin bidirectional line
					(at 0 -15.24 0)
					(length 2.54)
					(name "A4"
						(effects
							(font
								(size 1.27 1.27)
							)
						)
					)
					(number "6"
						(effects
							(font
								(size 1.27 1.27)
							)
						)
					)
				)
				(pin bidirectional line
					(at 0 -17.78 0)
					(length 2.54)
					(name "A5"
						(effects
							(font
								(size 1.27 1.27)
							)
						)
					)
					(number "7"
						(effects
							(font
								(size 1.27 1.27)
							)
						)
					)
				)
				(pin bidirectional line
					(at 0 -20.32 0)
					(length 2.54)
					(name "A6"
						(effects
							(font
								(size 1.27 1.27)
							)
						)
					)
					(number "8"
						(effects
							(font
								(size 1.27 1.27)
							)
						)
					)
				)
				(pin bidirectional line
					(at 0 -22.86 0)
					(length 2.54)
					(name "A7"
						(effects
							(font
								(size 1.27 1.27)
							)
						)
					)
					(number "9"
						(effects
							(font
								(size 1.27 1.27)
							)
						)
					)
				)
				(pin bidirectional line
					(at 0 -25.4 0)
					(length 2.54)
					(name "A8"
						(effects
							(font
								(size 1.27 1.27)
							)
						)
					)
					(number "10"
						(effects
							(font
								(size 1.27 1.27)
							)
						)
					)
				)
				(pin power_in line
					(at 0 -29.21 0)
					(length 2.54)
					(name "EP"
						(effects
							(font
								(size 1.27 1.27)
							)
						)
					)
					(number "21"
						(effects
							(font
								(size 1.27 1.27)
							)
						)
					)
				)
				(pin power_in line
					(at 0 -31.75 0)
					(length 2.54)
					(name "GND"
						(effects
							(font
								(size 1.27 1.27)
							)
						)
					)
					(number "1"
						(effects
							(font
								(size 1.27 1.27)
							)
						)
					)
				)
				(pin power_in line
					(at 20.32 0 180)
					(length 2.54)
					(name "VREFB"
						(effects
							(font
								(size 1.27 1.27)
							)
						)
					)
					(number "19"
						(effects
							(font
								(size 1.27 1.27)
							)
						)
					)
				)
				(pin input line
					(at 20.32 -2.54 180)
					(length 2.54)
					(name "EN"
						(effects
							(font
								(size 1.27 1.27)
							)
						)
					)
					(number "20"
						(effects
							(font
								(size 1.27 1.27)
							)
						)
					)
				)
				(pin bidirectional line
					(at 20.32 -7.62 180)
					(length 2.54)
					(name "B1"
						(effects
							(font
								(size 1.27 1.27)
							)
						)
					)
					(number "18"
						(effects
							(font
								(size 1.27 1.27)
							)
						)
					)
				)
				(pin bidirectional line
					(at 20.32 -10.16 180)
					(length 2.54)
					(name "B2"
						(effects
							(font
								(size 1.27 1.27)
							)
						)
					)
					(number "17"
						(effects
							(font
								(size 1.27 1.27)
							)
						)
					)
				)
				(pin bidirectional line
					(at 20.32 -12.7 180)
					(length 2.54)
					(name "B3"
						(effects
							(font
								(size 1.27 1.27)
							)
						)
					)
					(number "16"
						(effects
							(font
								(size 1.27 1.27)
							)
						)
					)
				)
				(pin bidirectional line
					(at 20.32 -15.24 180)
					(length 2.54)
					(name "B4"
						(effects
							(font
								(size 1.27 1.27)
							)
						)
					)
					(number "15"
						(effects
							(font
								(size 1.27 1.27)
							)
						)
					)
				)
				(pin bidirectional line
					(at 20.32 -17.78 180)
					(length 2.54)
					(name "B5"
						(effects
							(font
								(size 1.27 1.27)
							)
						)
					)
					(number "14"
						(effects
							(font
								(size 1.27 1.27)
							)
						)
					)
				)
				(pin bidirectional line
					(at 20.32 -20.32 180)
					(length 2.54)
					(name "B6"
						(effects
							(font
								(size 1.27 1.27)
							)
						)
					)
					(number "13"
						(effects
							(font
								(size 1.27 1.27)
							)
						)
					)
				)
				(pin bidirectional line
					(at 20.32 -22.86 180)
					(length 2.54)
					(name "B7"
						(effects
							(font
								(size 1.27 1.27)
							)
						)
					)
					(number "12"
						(effects
							(font
								(size 1.27 1.27)
							)
						)
					)
				)
				(pin bidirectional line
					(at 20.32 -25.4 180)
					(length 2.54)
					(name "B8"
						(effects
							(font
								(size 1.27 1.27)
							)
						)
					)
					(number "11"
						(effects
							(font
								(size 1.27 1.27)
							)
						)
					)
				)
			)
		)
	(symbol "antmicroMechanicalParts:MP_Pad5.5mm_Drill2.9mm"
			(pin_names
				(hide yes)
			)
			(exclude_from_sim no)
			(in_bom no)
			(on_board yes)
			(property "Reference" "MP"
				(at 15.24 -5.08 0)
				(effects
					(font
						(size 1.27 1.27)
						(thickness 0.15)
					)
					(justify left bottom)
				)
			)
			(property "Value" "MP_Pad5.5mm_Drill2.9mm"
				(at 15.24 -7.62 0)
				(effects
					(font
						(size 1.27 1.27)
						(thickness 0.15)
					)
					(justify left bottom)
				)
			)
			(property "Footprint" "antmicro-footprints:MP_Pad5.5mm_Drill2.9mm"
				(at 15.24 -10.16 0)
				(effects
					(font
						(size 1.27 1.27)
						(thickness 0.15)
					)
					(justify left bottom)
					(hide yes)
				)
			)
			(property "Datasheet" ""
				(at 16.84 -15.57 0)
				(effects
					(font
						(size 1.27 1.27)
						(thickness 0.15)
					)
					(justify left bottom)
					(hide yes)
				)
			)
			(property "Description" "PCB mounting point"
				(at 15.24 -20.32 0)
				(effects
					(font
						(size 1.27 1.27)
					)
					(justify left bottom)
					(hide yes)
				)
			)
			(property "Author" "Antmicro"
				(at 15.24 -15.24 0)
				(effects
					(font
						(size 1.27 1.27)
						(thickness 0.15)
					)
					(justify left bottom)
					(hide yes)
				)
			)
			(property "License" "Apache-2.0"
				(at 15.24 -17.78 0)
				(effects
					(font
						(size 1.27 1.27)
						(thickness 0.15)
					)
					(justify left bottom)
					(hide yes)
				)
			)
			(property "ki_keywords" "MECHANICAL"
				(at 0 0 0)
				(effects
					(font
						(size 1.27 1.27)
					)
					(hide yes)
				)
			)
			(symbol "MP_Pad5.5mm_Drill2.9mm_1_1"
				(circle
					(center 5.08 0)
					(radius 1.27)
					(stroke
						(width 0.254)
						(type default)
					)
					(fill
						(type background)
					)
				)
				(circle
					(center 5.08 0)
					(radius 2.54)
					(stroke
						(width 0.254)
						(type default)
					)
					(fill
						(type background)
					)
				)
				(pin passive line
					(at 0 0 0)
					(length 2.54)
					(name "~"
						(effects
							(font
								(size 1.27 1.27)
							)
						)
					)
					(number "1"
						(effects
							(font
								(size 1.27 1.27)
							)
						)
					)
				)
			)
		)
	(symbol "antmicroMechanicalParts:Spacer_Drill3.7mm_H2.5mm_9774025151R"
			(exclude_from_sim no)
			(in_bom yes)
			(on_board yes)
			(property "Reference" "H"
				(at 22.86 -2.54 0)
				(effects
					(font
						(size 1.27 1.27)
						(thickness 0.15)
					)
					(justify left bottom)
				)
			)
			(property "Value" "Spacer_Drill3.7mm_H2.5mm_9774025151R"
				(at 22.86 -5.08 0)
				(effects
					(font
						(size 1.27 1.27)
						(thickness 0.15)
					)
					(justify left bottom)
				)
			)
			(property "Footprint" "antmicro-footprints:Spacer_Drill3.7mm_H2.5mm_9774025151R"
				(at 22.86 -7.62 0)
				(effects
					(font
						(size 1.27 1.27)
						(thickness 0.15)
					)
					(justify left bottom)
					(hide yes)
				)
			)
			(property "Datasheet" "https://www.we-online.com/components/products/datasheet/9774025151R.pdf"
				(at 22.86 -10.16 0)
				(effects
					(font
						(size 1.27 1.27)
						(thickness 0.15)
					)
					(justify left bottom)
					(hide yes)
				)
			)
			(property "Description" "Spacer, SMT, Non Stop, Steel, Swage Round, 5.1 mm x 2.5 mm, M2.5 Thread, WA-SMSI Series"
				(at 22.86 -22.86 0)
				(effects
					(font
						(size 1.27 1.27)
					)
					(justify left bottom)
					(hide yes)
				)
			)
			(property "Manufacturer" "Würth Elektronik"
				(at 22.86 -12.7 0)
				(effects
					(font
						(size 1.27 1.27)
						(thickness 0.15)
					)
					(justify left bottom)
					(hide yes)
				)
			)
			(property "MPN" "9774025151R"
				(at 22.86 -15.24 0)
				(effects
					(font
						(size 1.27 1.27)
						(thickness 0.15)
					)
					(justify left bottom)
					(hide yes)
				)
			)
			(property "Author" "Antmicro"
				(at 22.86 -17.78 0)
				(effects
					(font
						(size 1.27 1.27)
						(thickness 0.15)
					)
					(justify left bottom)
					(hide yes)
				)
			)
			(property "License" "Apache-2.0"
				(at 22.86 -20.32 0)
				(effects
					(font
						(size 1.27 1.27)
						(thickness 0.15)
					)
					(justify left bottom)
					(hide yes)
				)
			)
			(property "ki_keywords" "MECHANICAL, SPACER"
				(at 0 0 0)
				(effects
					(font
						(size 1.27 1.27)
					)
					(hide yes)
				)
			)
			(symbol "Spacer_Drill3.7mm_H2.5mm_9774025151R_1_1"
				(rectangle
					(start 2.54 -2.54)
					(end 7.62 2.54)
					(stroke
						(width 0.254)
						(type default)
					)
					(fill
						(type background)
					)
				)
				(rectangle
					(start 3.81 -1.27)
					(end 6.35 1.27)
					(stroke
						(width 0.254)
						(type default)
					)
					(fill
						(type background)
					)
				)
				(pin passive line
					(at 0 0 0)
					(length 2.54)
					(name "~"
						(effects
							(font
								(size 1.27 1.27)
							)
						)
					)
					(number "1"
						(effects
							(font
								(size 1.27 1.27)
							)
						)
					)
				)
			)
		)
	(symbol "antmicroMechanicalParts:Spacer_Drill3.7mm_H4mm_9774040151R"
			(exclude_from_sim no)
			(in_bom yes)
			(on_board yes)
			(property "Reference" "H"
				(at 22.86 -2.54 0)
				(effects
					(font
						(size 1.27 1.27)
						(thickness 0.15)
					)
					(justify left bottom)
				)
			)
			(property "Value" "Spacer_Drill3.7mm_H4mm_9774040151R"
				(at 22.86 -5.08 0)
				(effects
					(font
						(size 1.27 1.27)
						(thickness 0.15)
					)
					(justify left bottom)
				)
			)
			(property "Footprint" "antmicro-footprints:Spacer_Drill3.7mm_H4mm_9774040151R"
				(at 22.86 -7.62 0)
				(effects
					(font
						(size 1.27 1.27)
						(thickness 0.15)
					)
					(justify left bottom)
					(hide yes)
				)
			)
			(property "Datasheet" "https://www.we-online.com/components/products/datasheet/9774040151R.pdf"
				(at 22.86 -10.16 0)
				(effects
					(font
						(size 1.27 1.27)
						(thickness 0.15)
					)
					(justify left bottom)
					(hide yes)
				)
			)
			(property "Description" "Round Standoff Threaded M2.5x0.45 Steel 0.157\" (4.00mm)"
				(at 22.86 -22.86 0)
				(effects
					(font
						(size 1.27 1.27)
					)
					(justify left bottom)
					(hide yes)
				)
			)
			(property "Manufacturer" "Würth Elektronik"
				(at 22.86 -12.7 0)
				(effects
					(font
						(size 1.27 1.27)
						(thickness 0.15)
					)
					(justify left bottom)
					(hide yes)
				)
			)
			(property "MPN" "9774040151R"
				(at 22.86 -15.24 0)
				(effects
					(font
						(size 1.27 1.27)
						(thickness 0.15)
					)
					(justify left bottom)
					(hide yes)
				)
			)
			(property "Author" "Antmicro"
				(at 22.86 -17.78 0)
				(effects
					(font
						(size 1.27 1.27)
						(thickness 0.15)
					)
					(justify left bottom)
					(hide yes)
				)
			)
			(property "License" "Apache-2.0"
				(at 22.86 -20.32 0)
				(effects
					(font
						(size 1.27 1.27)
						(thickness 0.15)
					)
					(justify left bottom)
					(hide yes)
				)
			)
			(property "ki_keywords" "SPACER"
				(at 0 0 0)
				(effects
					(font
						(size 1.27 1.27)
					)
					(hide yes)
				)
			)
			(symbol "Spacer_Drill3.7mm_H4mm_9774040151R_1_1"
				(rectangle
					(start 2.54 -2.54)
					(end 7.62 2.54)
					(stroke
						(width 0.254)
						(type default)
					)
					(fill
						(type background)
					)
				)
				(rectangle
					(start 3.81 -1.27)
					(end 6.35 1.27)
					(stroke
						(width 0.254)
						(type default)
					)
					(fill
						(type background)
					)
				)
				(pin passive line
					(at 0 0 0)
					(length 2.54)
					(name "~"
						(effects
							(font
								(size 1.27 1.27)
							)
						)
					)
					(number "1"
						(effects
							(font
								(size 1.27 1.27)
							)
						)
					)
				)
			)
		)
	(symbol "antmicroMemory:AS4C256M16D3"
			(pin_names
				(offset 1.016)
			)
			(exclude_from_sim no)
			(in_bom yes)
			(on_board yes)
			(property "Reference" "U"
				(at 50.8 0 0)
				(effects
					(font
						(size 1.27 1.27)
						(thickness 0.15)
					)
					(justify left bottom)
				)
			)
			(property "Value" "AS4C256M16D3"
				(at 50.8 -2.54 0)
				(effects
					(font
						(size 1.27 1.27)
						(thickness 0.15)
					)
					(justify left bottom)
					(hide yes)
				)
			)
			(property "Footprint" "antmicro-footprints:BGA-96-48_7.5x13.5mm_Layout9x16_P0.8mm"
				(at 50.8 -5.08 0)
				(effects
					(font
						(size 1.27 1.27)
						(thickness 0.15)
					)
					(justify left bottom)
					(hide yes)
				)
			)
			(property "Datasheet" "https://www.alliancememory.com/wp-content/uploads/AllianceMemory_4G_DDR3L_AS4C256M16D3LC_March2020_Rev1.0.pdf"
				(at 50.8 -7.62 0)
				(effects
					(font
						(size 1.27 1.27)
						(thickness 0.15)
					)
					(justify left bottom)
					(hide yes)
				)
			)
			(property "Description" "SDRAM - DDR3 Memory IC 4Gbit Parallel 800 MHz 20 ns 96-FBGA (9x13)"
				(at 50.8 -20.32 0)
				(effects
					(font
						(size 1.27 1.27)
					)
					(justify left bottom)
					(hide yes)
				)
			)
			(property "Manufacturer" "Alliance Memory"
				(at 50.8 -10.16 0)
				(effects
					(font
						(size 1.27 1.27)
						(thickness 0.15)
					)
					(justify left bottom)
					(hide yes)
				)
			)
			(property "MPN" "AS4C256M16D3LC-12BCN"
				(at 50.8 -12.7 0)
				(effects
					(font
						(size 1.27 1.27)
						(thickness 0.15)
					)
					(justify left bottom)
				)
			)
			(property "Author" "Antmicro"
				(at 50.8 -15.24 0)
				(effects
					(font
						(size 1.27 1.27)
						(thickness 0.15)
					)
					(justify left bottom)
					(hide yes)
				)
			)
			(property "License" "Apache-2.0"
				(at 50.8 -17.78 0)
				(effects
					(font
						(size 1.27 1.27)
						(thickness 0.15)
					)
					(justify left bottom)
					(hide yes)
				)
			)
			(property "ki_keywords" "SMT, MEMORY, IC, DDR, SYNCHRONOUS"
				(at 0 0 0)
				(effects
					(font
						(size 1.27 1.27)
					)
					(hide yes)
				)
			)
			(symbol "AS4C256M16D3_1_1"
				(rectangle
					(start 2.54 2.54)
					(end 33.02 -88.9)
					(stroke
						(width 0.254)
						(type default)
					)
					(fill
						(type background)
					)
				)
				(text "256Mx16 DDR3"
					(at 17.78 -44.45 900)
					(effects
						(font
							(size 1.27 1.27)
							(thickness 0.15)
						)
						(justify left bottom)
					)
				)
				(pin power_in line
					(at 0 0 0)
					(length 2.54)
					(name "VDD"
						(effects
							(font
								(size 1.27 1.27)
							)
						)
					)
					(number "B2"
						(effects
							(font
								(size 1.27 1.27)
							)
						)
					)
				)
				(pin passive line
					(at 0 0 0)
					(length 2.54)
					(hide yes)
					(name "VDD"
						(effects
							(font
								(size 1.27 1.27)
							)
						)
					)
					(number "D9"
						(effects
							(font
								(size 1.27 1.27)
							)
						)
					)
				)
				(pin passive line
					(at 0 0 0)
					(length 2.54)
					(hide yes)
					(name "VDD"
						(effects
							(font
								(size 1.27 1.27)
							)
						)
					)
					(number "G7"
						(effects
							(font
								(size 1.27 1.27)
							)
						)
					)
				)
				(pin passive line
					(at 0 0 0)
					(length 2.54)
					(hide yes)
					(name "VDD"
						(effects
							(font
								(size 1.27 1.27)
							)
						)
					)
					(number "K2"
						(effects
							(font
								(size 1.27 1.27)
							)
						)
					)
				)
				(pin passive line
					(at 0 0 0)
					(length 2.54)
					(hide yes)
					(name "VDD"
						(effects
							(font
								(size 1.27 1.27)
							)
						)
					)
					(number "K8"
						(effects
							(font
								(size 1.27 1.27)
							)
						)
					)
				)
				(pin passive line
					(at 0 0 0)
					(length 2.54)
					(hide yes)
					(name "VDD"
						(effects
							(font
								(size 1.27 1.27)
							)
						)
					)
					(number "N1"
						(effects
							(font
								(size 1.27 1.27)
							)
						)
					)
				)
				(pin passive line
					(at 0 0 0)
					(length 2.54)
					(hide yes)
					(name "VDD"
						(effects
							(font
								(size 1.27 1.27)
							)
						)
					)
					(number "N9"
						(effects
							(font
								(size 1.27 1.27)
							)
						)
					)
				)
				(pin passive line
					(at 0 0 0)
					(length 2.54)
					(hide yes)
					(name "VDD"
						(effects
							(font
								(size 1.27 1.27)
							)
						)
					)
					(number "R1"
						(effects
							(font
								(size 1.27 1.27)
							)
						)
					)
				)
				(pin passive line
					(at 0 0 0)
					(length 2.54)
					(hide yes)
					(name "VDD"
						(effects
							(font
								(size 1.27 1.27)
							)
						)
					)
					(number "R9"
						(effects
							(font
								(size 1.27 1.27)
							)
						)
					)
				)
				(pin power_in line
					(at 0 -2.54 0)
					(length 2.54)
					(name "VDDQ"
						(effects
							(font
								(size 1.27 1.27)
							)
						)
					)
					(number "A1"
						(effects
							(font
								(size 1.27 1.27)
							)
						)
					)
				)
				(pin passive line
					(at 0 -2.54 0)
					(length 2.54)
					(hide yes)
					(name "VDDQ"
						(effects
							(font
								(size 1.27 1.27)
							)
						)
					)
					(number "A8"
						(effects
							(font
								(size 1.27 1.27)
							)
						)
					)
				)
				(pin passive line
					(at 0 -2.54 0)
					(length 2.54)
					(hide yes)
					(name "VDDQ"
						(effects
							(font
								(size 1.27 1.27)
							)
						)
					)
					(number "C1"
						(effects
							(font
								(size 1.27 1.27)
							)
						)
					)
				)
				(pin passive line
					(at 0 -2.54 0)
					(length 2.54)
					(hide yes)
					(name "VDDQ"
						(effects
							(font
								(size 1.27 1.27)
							)
						)
					)
					(number "C9"
						(effects
							(font
								(size 1.27 1.27)
							)
						)
					)
				)
				(pin passive line
					(at 0 -2.54 0)
					(length 2.54)
					(hide yes)
					(name "VDDQ"
						(effects
							(font
								(size 1.27 1.27)
							)
						)
					)
					(number "D2"
						(effects
							(font
								(size 1.27 1.27)
							)
						)
					)
				)
				(pin passive line
					(at 0 -2.54 0)
					(length 2.54)
					(hide yes)
					(name "VDDQ"
						(effects
							(font
								(size 1.27 1.27)
							)
						)
					)
					(number "E9"
						(effects
							(font
								(size 1.27 1.27)
							)
						)
					)
				)
				(pin passive line
					(at 0 -2.54 0)
					(length 2.54)
					(hide yes)
					(name "VDDQ"
						(effects
							(font
								(size 1.27 1.27)
							)
						)
					)
					(number "F1"
						(effects
							(font
								(size 1.27 1.27)
							)
						)
					)
				)
				(pin passive line
					(at 0 -2.54 0)
					(length 2.54)
					(hide yes)
					(name "VDDQ"
						(effects
							(font
								(size 1.27 1.27)
							)
						)
					)
					(number "H2"
						(effects
							(font
								(size 1.27 1.27)
							)
						)
					)
				)
				(pin passive line
					(at 0 -2.54 0)
					(length 2.54)
					(hide yes)
					(name "VDDQ"
						(effects
							(font
								(size 1.27 1.27)
							)
						)
					)
					(number "H9"
						(effects
							(font
								(size 1.27 1.27)
							)
						)
					)
				)
				(pin input line
					(at 0 -7.62 0)
					(length 2.54)
					(name "~{RESET}"
						(effects
							(font
								(size 1.27 1.27)
							)
						)
					)
					(number "T2"
						(effects
							(font
								(size 1.27 1.27)
							)
						)
					)
				)
				(pin input line
					(at 0 -10.16 0)
					(length 2.54)
					(name "~{RAS}"
						(effects
							(font
								(size 1.27 1.27)
							)
						)
					)
					(number "J3"
						(effects
							(font
								(size 1.27 1.27)
							)
						)
					)
				)
				(pin input line
					(at 0 -12.7 0)
					(length 2.54)
					(name "~{CAS}"
						(effects
							(font
								(size 1.27 1.27)
							)
						)
					)
					(number "K3"
						(effects
							(font
								(size 1.27 1.27)
							)
						)
					)
				)
				(pin input line
					(at 0 -15.24 0)
					(length 2.54)
					(name "~{WE}"
						(effects
							(font
								(size 1.27 1.27)
							)
						)
					)
					(number "L3"
						(effects
							(font
								(size 1.27 1.27)
							)
						)
					)
				)
				(pin input line
					(at 0 -17.78 0)
					(length 2.54)
					(name "~{CS}"
						(effects
							(font
								(size 1.27 1.27)
							)
						)
					)
					(number "L2"
						(effects
							(font
								(size 1.27 1.27)
							)
						)
					)
				)
				(pin input line
					(at 0 -22.86 0)
					(length 2.54)
					(name "ODT"
						(effects
							(font
								(size 1.27 1.27)
							)
						)
					)
					(number "K1"
						(effects
							(font
								(size 1.27 1.27)
							)
						)
					)
				)
				(pin input line
					(at 0 -25.4 0)
					(length 2.54)
					(name "LDM"
						(effects
							(font
								(size 1.27 1.27)
							)
						)
					)
					(number "E7"
						(effects
							(font
								(size 1.27 1.27)
							)
						)
					)
				)
				(pin input line
					(at 0 -27.94 0)
					(length 2.54)
					(name "UDM"
						(effects
							(font
								(size 1.27 1.27)
							)
						)
					)
					(number "D3"
						(effects
							(font
								(size 1.27 1.27)
							)
						)
					)
				)
				(pin input line
					(at 0 -33.02 0)
					(length 2.54)
					(name "CKE"
						(effects
							(font
								(size 1.27 1.27)
							)
						)
					)
					(number "K9"
						(effects
							(font
								(size 1.27 1.27)
							)
						)
					)
				)
				(pin input clock
					(at 0 -35.56 0)
					(length 2.54)
					(name "CK"
						(effects
							(font
								(size 1.27 1.27)
							)
						)
					)
					(number "J7"
						(effects
							(font
								(size 1.27 1.27)
							)
						)
					)
				)
				(pin input clock
					(at 0 -38.1 0)
					(length 2.54)
					(name "~{CK}"
						(effects
							(font
								(size 1.27 1.27)
							)
						)
					)
					(number "K7"
						(effects
							(font
								(size 1.27 1.27)
							)
						)
					)
				)
				(pin input line
					(at 0 -43.18 0)
					(length 2.54)
					(name "A0"
						(effects
							(font
								(size 1.27 1.27)
							)
						)
					)
					(number "N3"
						(effects
							(font
								(size 1.27 1.27)
							)
						)
					)
				)
				(pin input line
					(at 0 -45.72 0)
					(length 2.54)
					(name "A1"
						(effects
							(font
								(size 1.27 1.27)
							)
						)
					)
					(number "P7"
						(effects
							(font
								(size 1.27 1.27)
							)
						)
					)
				)
				(pin input line
					(at 0 -48.26 0)
					(length 2.54)
					(name "A2"
						(effects
							(font
								(size 1.27 1.27)
							)
						)
					)
					(number "P3"
						(effects
							(font
								(size 1.27 1.27)
							)
						)
					)
				)
				(pin input line
					(at 0 -50.8 0)
					(length 2.54)
					(name "A3"
						(effects
							(font
								(size 1.27 1.27)
							)
						)
					)
					(number "N2"
						(effects
							(font
								(size 1.27 1.27)
							)
						)
					)
				)
				(pin input line
					(at 0 -53.34 0)
					(length 2.54)
					(name "A4"
						(effects
							(font
								(size 1.27 1.27)
							)
						)
					)
					(number "P8"
						(effects
							(font
								(size 1.27 1.27)
							)
						)
					)
				)
				(pin input line
					(at 0 -55.88 0)
					(length 2.54)
					(name "A5"
						(effects
							(font
								(size 1.27 1.27)
							)
						)
					)
					(number "P2"
						(effects
							(font
								(size 1.27 1.27)
							)
						)
					)
				)
				(pin input line
					(at 0 -58.42 0)
					(length 2.54)
					(name "A6"
						(effects
							(font
								(size 1.27 1.27)
							)
						)
					)
					(number "R8"
						(effects
							(font
								(size 1.27 1.27)
							)
						)
					)
				)
				(pin input line
					(at 0 -60.96 0)
					(length 2.54)
					(name "A7"
						(effects
							(font
								(size 1.27 1.27)
							)
						)
					)
					(number "R2"
						(effects
							(font
								(size 1.27 1.27)
							)
						)
					)
				)
				(pin input line
					(at 0 -63.5 0)
					(length 2.54)
					(name "A8"
						(effects
							(font
								(size 1.27 1.27)
							)
						)
					)
					(number "T8"
						(effects
							(font
								(size 1.27 1.27)
							)
						)
					)
				)
				(pin input line
					(at 0 -66.04 0)
					(length 2.54)
					(name "A9"
						(effects
							(font
								(size 1.27 1.27)
							)
						)
					)
					(number "R3"
						(effects
							(font
								(size 1.27 1.27)
							)
						)
					)
				)
				(pin input line
					(at 0 -68.58 0)
					(length 2.54)
					(name "A10/AP"
						(effects
							(font
								(size 1.27 1.27)
							)
						)
					)
					(number "L7"
						(effects
							(font
								(size 1.27 1.27)
							)
						)
					)
				)
				(pin input line
					(at 0 -71.12 0)
					(length 2.54)
					(name "A11"
						(effects
							(font
								(size 1.27 1.27)
							)
						)
					)
					(number "R7"
						(effects
							(font
								(size 1.27 1.27)
							)
						)
					)
				)
				(pin input line
					(at 0 -73.66 0)
					(length 2.54)
					(name "A12/~{BC}"
						(effects
							(font
								(size 1.27 1.27)
							)
						)
					)
					(number "N7"
						(effects
							(font
								(size 1.27 1.27)
							)
						)
					)
				)
				(pin input line
					(at 0 -76.2 0)
					(length 2.54)
					(name "A13"
						(effects
							(font
								(size 1.27 1.27)
							)
						)
					)
					(number "T3"
						(effects
							(font
								(size 1.27 1.27)
							)
						)
					)
				)
				(pin input line
					(at 0 -78.74 0)
					(length 2.54)
					(name "A14"
						(effects
							(font
								(size 1.27 1.27)
							)
						)
					)
					(number "T7"
						(effects
							(font
								(size 1.27 1.27)
							)
						)
					)
				)
				(pin input line
					(at 0 -81.28 0)
					(length 2.54)
					(name "BA0"
						(effects
							(font
								(size 1.27 1.27)
							)
						)
					)
					(number "M2"
						(effects
							(font
								(size 1.27 1.27)
							)
						)
					)
				)
				(pin input line
					(at 0 -83.82 0)
					(length 2.54)
					(name "BA1"
						(effects
							(font
								(size 1.27 1.27)
							)
						)
					)
					(number "N8"
						(effects
							(font
								(size 1.27 1.27)
							)
						)
					)
				)
				(pin input line
					(at 0 -86.36 0)
					(length 2.54)
					(name "BA2"
						(effects
							(font
								(size 1.27 1.27)
							)
						)
					)
					(number "M3"
						(effects
							(font
								(size 1.27 1.27)
							)
						)
					)
				)
				(pin no_connect line
					(at 33.02 -62.23 180)
					(length 2.54)
					(hide yes)
					(name "NC"
						(effects
							(font
								(size 1.27 1.27)
							)
						)
					)
					(number "J1"
						(effects
							(font
								(size 1.27 1.27)
							)
						)
					)
				)
				(pin no_connect line
					(at 33.02 -62.23 180)
					(length 2.54)
					(hide yes)
					(name "NC"
						(effects
							(font
								(size 1.27 1.27)
							)
						)
					)
					(number "J9"
						(effects
							(font
								(size 1.27 1.27)
							)
						)
					)
				)
				(pin no_connect line
					(at 33.02 -62.23 180)
					(length 2.54)
					(hide yes)
					(name "NC"
						(effects
							(font
								(size 1.27 1.27)
							)
						)
					)
					(number "L1"
						(effects
							(font
								(size 1.27 1.27)
							)
						)
					)
				)
				(pin no_connect line
					(at 33.02 -62.23 180)
					(length 2.54)
					(hide yes)
					(name "NC"
						(effects
							(font
								(size 1.27 1.27)
							)
						)
					)
					(number "L9"
						(effects
							(font
								(size 1.27 1.27)
							)
						)
					)
				)
				(pin no_connect line
					(at 33.02 -62.23 180)
					(length 2.54)
					(hide yes)
					(name "NC"
						(effects
							(font
								(size 1.27 1.27)
							)
						)
					)
					(number "M7"
						(effects
							(font
								(size 1.27 1.27)
							)
						)
					)
				)
				(pin power_in line
					(at 35.56 0 180)
					(length 2.54)
					(name "VREF_DQ"
						(effects
							(font
								(size 1.27 1.27)
							)
						)
					)
					(number "H1"
						(effects
							(font
								(size 1.27 1.27)
							)
						)
					)
				)
				(pin power_in line
					(at 35.56 -2.54 180)
					(length 2.54)
					(name "VREF_CA"
						(effects
							(font
								(size 1.27 1.27)
							)
						)
					)
					(number "M8"
						(effects
							(font
								(size 1.27 1.27)
							)
						)
					)
				)
				(pin bidirectional line
					(at 35.56 -7.62 180)
					(length 2.54)
					(name "LDQS"
						(effects
							(font
								(size 1.27 1.27)
							)
						)
					)
					(number "F3"
						(effects
							(font
								(size 1.27 1.27)
							)
						)
					)
				)
				(pin bidirectional line
					(at 35.56 -10.16 180)
					(length 2.54)
					(name "~{LDQS}"
						(effects
							(font
								(size 1.27 1.27)
							)
						)
					)
					(number "G3"
						(effects
							(font
								(size 1.27 1.27)
							)
						)
					)
				)
				(pin bidirectional line
					(at 35.56 -12.7 180)
					(length 2.54)
					(name "UDQS"
						(effects
							(font
								(size 1.27 1.27)
							)
						)
					)
					(number "C7"
						(effects
							(font
								(size 1.27 1.27)
							)
						)
					)
				)
				(pin bidirectional line
					(at 35.56 -15.24 180)
					(length 2.54)
					(name "~{UDQS}"
						(effects
							(font
								(size 1.27 1.27)
							)
						)
					)
					(number "B7"
						(effects
							(font
								(size 1.27 1.27)
							)
						)
					)
				)
				(pin bidirectional line
					(at 35.56 -20.32 180)
					(length 2.54)
					(name "DQ0"
						(effects
							(font
								(size 1.27 1.27)
							)
						)
					)
					(number "E3"
						(effects
							(font
								(size 1.27 1.27)
							)
						)
					)
				)
				(pin bidirectional line
					(at 35.56 -22.86 180)
					(length 2.54)
					(name "DQ1"
						(effects
							(font
								(size 1.27 1.27)
							)
						)
					)
					(number "F7"
						(effects
							(font
								(size 1.27 1.27)
							)
						)
					)
				)
				(pin bidirectional line
					(at 35.56 -25.4 180)
					(length 2.54)
					(name "DQ2"
						(effects
							(font
								(size 1.27 1.27)
							)
						)
					)
					(number "F2"
						(effects
							(font
								(size 1.27 1.27)
							)
						)
					)
				)
				(pin bidirectional line
					(at 35.56 -27.94 180)
					(length 2.54)
					(name "DQ3"
						(effects
							(font
								(size 1.27 1.27)
							)
						)
					)
					(number "F8"
						(effects
							(font
								(size 1.27 1.27)
							)
						)
					)
				)
				(pin bidirectional line
					(at 35.56 -30.48 180)
					(length 2.54)
					(name "DQ4"
						(effects
							(font
								(size 1.27 1.27)
							)
						)
					)
					(number "H3"
						(effects
							(font
								(size 1.27 1.27)
							)
						)
					)
				)
				(pin bidirectional line
					(at 35.56 -33.02 180)
					(length 2.54)
					(name "DQ5"
						(effects
							(font
								(size 1.27 1.27)
							)
						)
					)
					(number "H8"
						(effects
							(font
								(size 1.27 1.27)
							)
						)
					)
				)
				(pin bidirectional line
					(at 35.56 -35.56 180)
					(length 2.54)
					(name "DQ6"
						(effects
							(font
								(size 1.27 1.27)
							)
						)
					)
					(number "G2"
						(effects
							(font
								(size 1.27 1.27)
							)
						)
					)
				)
				(pin bidirectional line
					(at 35.56 -38.1 180)
					(length 2.54)
					(name "DQ7"
						(effects
							(font
								(size 1.27 1.27)
							)
						)
					)
					(number "H7"
						(effects
							(font
								(size 1.27 1.27)
							)
						)
					)
				)
				(pin bidirectional line
					(at 35.56 -40.64 180)
					(length 2.54)
					(name "DQ8"
						(effects
							(font
								(size 1.27 1.27)
							)
						)
					)
					(number "D7"
						(effects
							(font
								(size 1.27 1.27)
							)
						)
					)
				)
				(pin bidirectional line
					(at 35.56 -43.18 180)
					(length 2.54)
					(name "DQ9"
						(effects
							(font
								(size 1.27 1.27)
							)
						)
					)
					(number "C3"
						(effects
							(font
								(size 1.27 1.27)
							)
						)
					)
				)
				(pin bidirectional line
					(at 35.56 -45.72 180)
					(length 2.54)
					(name "DQ10"
						(effects
							(font
								(size 1.27 1.27)
							)
						)
					)
					(number "C8"
						(effects
							(font
								(size 1.27 1.27)
							)
						)
					)
				)
				(pin bidirectional line
					(at 35.56 -48.26 180)
					(length 2.54)
					(name "DQ11"
						(effects
							(font
								(size 1.27 1.27)
							)
						)
					)
					(number "C2"
						(effects
							(font
								(size 1.27 1.27)
							)
						)
					)
				)
				(pin bidirectional line
					(at 35.56 -50.8 180)
					(length 2.54)
					(name "DQ12"
						(effects
							(font
								(size 1.27 1.27)
							)
						)
					)
					(number "A7"
						(effects
							(font
								(size 1.27 1.27)
							)
						)
					)
				)
				(pin bidirectional line
					(at 35.56 -53.34 180)
					(length 2.54)
					(name "DQ13"
						(effects
							(font
								(size 1.27 1.27)
							)
						)
					)
					(number "A2"
						(effects
							(font
								(size 1.27 1.27)
							)
						)
					)
				)
				(pin bidirectional line
					(at 35.56 -55.88 180)
					(length 2.54)
					(name "DQ14"
						(effects
							(font
								(size 1.27 1.27)
							)
						)
					)
					(number "B8"
						(effects
							(font
								(size 1.27 1.27)
							)
						)
					)
				)
				(pin bidirectional line
					(at 35.56 -58.42 180)
					(length 2.54)
					(name "DQ15"
						(effects
							(font
								(size 1.27 1.27)
							)
						)
					)
					(number "A3"
						(effects
							(font
								(size 1.27 1.27)
							)
						)
					)
				)
				(pin passive line
					(at 35.56 -76.2 180)
					(length 2.54)
					(name "ZQ"
						(effects
							(font
								(size 1.27 1.27)
							)
						)
					)
					(number "L8"
						(effects
							(font
								(size 1.27 1.27)
							)
						)
					)
				)
				(pin power_in line
					(at 35.56 -83.82 180)
					(length 2.54)
					(name "VSS"
						(effects
							(font
								(size 1.27 1.27)
							)
						)
					)
					(number "A9"
						(effects
							(font
								(size 1.27 1.27)
							)
						)
					)
				)
				(pin passive line
					(at 35.56 -83.82 180)
					(length 2.54)
					(hide yes)
					(name "VSS"
						(effects
							(font
								(size 1.27 1.27)
							)
						)
					)
					(number "B3"
						(effects
							(font
								(size 1.27 1.27)
							)
						)
					)
				)
				(pin passive line
					(at 35.56 -83.82 180)
					(length 2.54)
					(hide yes)
					(name "VSS"
						(effects
							(font
								(size 1.27 1.27)
							)
						)
					)
					(number "E1"
						(effects
							(font
								(size 1.27 1.27)
							)
						)
					)
				)
				(pin passive line
					(at 35.56 -83.82 180)
					(length 2.54)
					(hide yes)
					(name "VSS"
						(effects
							(font
								(size 1.27 1.27)
							)
						)
					)
					(number "G8"
						(effects
							(font
								(size 1.27 1.27)
							)
						)
					)
				)
				(pin passive line
					(at 35.56 -83.82 180)
					(length 2.54)
					(hide yes)
					(name "VSS"
						(effects
							(font
								(size 1.27 1.27)
							)
						)
					)
					(number "J2"
						(effects
							(font
								(size 1.27 1.27)
							)
						)
					)
				)
				(pin passive line
					(at 35.56 -83.82 180)
					(length 2.54)
					(hide yes)
					(name "VSS"
						(effects
							(font
								(size 1.27 1.27)
							)
						)
					)
					(number "J8"
						(effects
							(font
								(size 1.27 1.27)
							)
						)
					)
				)
				(pin passive line
					(at 35.56 -83.82 180)
					(length 2.54)
					(hide yes)
					(name "VSS"
						(effects
							(font
								(size 1.27 1.27)
							)
						)
					)
					(number "M1"
						(effects
							(font
								(size 1.27 1.27)
							)
						)
					)
				)
				(pin passive line
					(at 35.56 -83.82 180)
					(length 2.54)
					(hide yes)
					(name "VSS"
						(effects
							(font
								(size 1.27 1.27)
							)
						)
					)
					(number "M9"
						(effects
							(font
								(size 1.27 1.27)
							)
						)
					)
				)
				(pin passive line
					(at 35.56 -83.82 180)
					(length 2.54)
					(hide yes)
					(name "VSS"
						(effects
							(font
								(size 1.27 1.27)
							)
						)
					)
					(number "P1"
						(effects
							(font
								(size 1.27 1.27)
							)
						)
					)
				)
				(pin passive line
					(at 35.56 -83.82 180)
					(length 2.54)
					(hide yes)
					(name "VSS"
						(effects
							(font
								(size 1.27 1.27)
							)
						)
					)
					(number "P9"
						(effects
							(font
								(size 1.27 1.27)
							)
						)
					)
				)
				(pin passive line
					(at 35.56 -83.82 180)
					(length 2.54)
					(hide yes)
					(name "VSS"
						(effects
							(font
								(size 1.27 1.27)
							)
						)
					)
					(number "T1"
						(effects
							(font
								(size 1.27 1.27)
							)
						)
					)
				)
				(pin passive line
					(at 35.56 -83.82 180)
					(length 2.54)
					(hide yes)
					(name "VSS"
						(effects
							(font
								(size 1.27 1.27)
							)
						)
					)
					(number "T9"
						(effects
							(font
								(size 1.27 1.27)
							)
						)
					)
				)
				(pin power_in line
					(at 35.56 -86.36 180)
					(length 2.54)
					(name "VSSQ"
						(effects
							(font
								(size 1.27 1.27)
							)
						)
					)
					(number "B1"
						(effects
							(font
								(size 1.27 1.27)
							)
						)
					)
				)
				(pin passive line
					(at 35.56 -86.36 180)
					(length 2.54)
					(hide yes)
					(name "VSSQ"
						(effects
							(font
								(size 1.27 1.27)
							)
						)
					)
					(number "B9"
						(effects
							(font
								(size 1.27 1.27)
							)
						)
					)
				)
				(pin passive line
					(at 35.56 -86.36 180)
					(length 2.54)
					(hide yes)
					(name "VSSQ"
						(effects
							(font
								(size 1.27 1.27)
							)
						)
					)
					(number "D1"
						(effects
							(font
								(size 1.27 1.27)
							)
						)
					)
				)
				(pin passive line
					(at 35.56 -86.36 180)
					(length 2.54)
					(hide yes)
					(name "VSSQ"
						(effects
							(font
								(size 1.27 1.27)
							)
						)
					)
					(number "D8"
						(effects
							(font
								(size 1.27 1.27)
							)
						)
					)
				)
				(pin passive line
					(at 35.56 -86.36 180)
					(length 2.54)
					(hide yes)
					(name "VSSQ"
						(effects
							(font
								(size 1.27 1.27)
							)
						)
					)
					(number "E2"
						(effects
							(font
								(size 1.27 1.27)
							)
						)
					)
				)
				(pin passive line
					(at 35.56 -86.36 180)
					(length 2.54)
					(hide yes)
					(name "VSSQ"
						(effects
							(font
								(size 1.27 1.27)
							)
						)
					)
					(number "E8"
						(effects
							(font
								(size 1.27 1.27)
							)
						)
					)
				)
				(pin passive line
					(at 35.56 -86.36 180)
					(length 2.54)
					(hide yes)
					(name "VSSQ"
						(effects
							(font
								(size 1.27 1.27)
							)
						)
					)
					(number "F9"
						(effects
							(font
								(size 1.27 1.27)
							)
						)
					)
				)
				(pin passive line
					(at 35.56 -86.36 180)
					(length 2.54)
					(hide yes)
					(name "VSSQ"
						(effects
							(font
								(size 1.27 1.27)
							)
						)
					)
					(number "G1"
						(effects
							(font
								(size 1.27 1.27)
							)
						)
					)
				)
				(pin passive line
					(at 35.56 -86.36 180)
					(length 2.54)
					(hide yes)
					(name "VSSQ"
						(effects
							(font
								(size 1.27 1.27)
							)
						)
					)
					(number "G9"
						(effects
							(font
								(size 1.27 1.27)
							)
						)
					)
				)
			)
		)
	(symbol "antmicroMemory:MTFC16GAPALNA-AIT"
			(pin_names
				(offset 1.016)
			)
			(exclude_from_sim no)
			(in_bom yes)
			(on_board yes)
			(property "Reference" "U"
				(at 33.02 -2.54 0)
				(effects
					(font
						(size 1.27 1.27)
						(thickness 0.15)
					)
					(justify left bottom)
				)
			)
			(property "Value" "MTFC16GAPALNA-AIT"
				(at 33.02 -5.08 0)
				(effects
					(font
						(size 1.27 1.27)
						(thickness 0.15)
					)
					(justify left bottom)
					(hide yes)
				)
			)
			(property "Footprint" "antmicro-footprints:BGA-170-100_18x14mm_Layout17x10_P1mm"
				(at 33.02 -7.62 0)
				(effects
					(font
						(size 1.27 1.27)
						(thickness 0.15)
					)
					(justify left bottom)
					(hide yes)
				)
			)
			(property "Datasheet" "https://www.mouser.com/datasheet/2/671/micron_technology_mict-s-a0006806196-1-1759129.pdf"
				(at 33.02 -10.16 0)
				(effects
					(font
						(size 1.27 1.27)
						(thickness 0.15)
					)
					(justify left bottom)
					(hide yes)
				)
			)
			(property "Description" "Managed NAND Flash Serial e-MMC 3.3V 128G-bit 128G/32G/16G x 1/4-bit/8-bit Automotive AEC-Q100 100-Pin TBGA Tray"
				(at 33.02 -22.86 0)
				(effects
					(font
						(size 1.27 1.27)
					)
					(justify left bottom)
					(hide yes)
				)
			)
			(property "Manufacturer" "Micron Technology"
				(at 33.02 -12.7 0)
				(effects
					(font
						(size 1.27 1.27)
						(thickness 0.15)
					)
					(justify left bottom)
					(hide yes)
				)
			)
			(property "MPN" "MTFC16GAPALNA-AIT"
				(at 33.02 -15.24 0)
				(effects
					(font
						(size 1.27 1.27)
						(thickness 0.15)
					)
					(justify left bottom)
				)
			)
			(property "Author" "Antmicro"
				(at 33.02 -17.78 0)
				(effects
					(font
						(size 1.27 1.27)
						(thickness 0.15)
					)
					(justify left bottom)
					(hide yes)
				)
			)
			(property "License" "Apache-2.0"
				(at 33.02 -20.32 0)
				(effects
					(font
						(size 1.27 1.27)
						(thickness 0.15)
					)
					(justify left bottom)
					(hide yes)
				)
			)
			(property "ki_keywords" "SMT, FLASH, IC"
				(at 0 0 0)
				(effects
					(font
						(size 1.27 1.27)
					)
					(hide yes)
				)
			)
			(symbol "MTFC16GAPALNA-AIT_0_0"
				(rectangle
					(start 2.54 2.54)
					(end 17.78 -27.94)
					(stroke
						(width 0.254)
						(type default)
					)
					(fill
						(type background)
					)
				)
				(pin input clock
					(at 0 0 0)
					(length 2.54)
					(name "CLK"
						(effects
							(font
								(size 1.27 1.27)
							)
						)
					)
					(number "P6"
						(effects
							(font
								(size 1.27 1.27)
							)
						)
					)
				)
				(pin input line
					(at 0 -2.54 0)
					(length 2.54)
					(name "RST_N"
						(effects
							(font
								(size 1.27 1.27)
							)
						)
					)
					(number "M5"
						(effects
							(font
								(size 1.27 1.27)
							)
						)
					)
				)
				(pin bidirectional line
					(at 0 -5.08 0)
					(length 2.54)
					(name "CMD"
						(effects
							(font
								(size 1.27 1.27)
							)
						)
					)
					(number "P5"
						(effects
							(font
								(size 1.27 1.27)
							)
						)
					)
				)
				(pin bidirectional line
					(at 0 -7.62 0)
					(length 2.54)
					(name "DAT0"
						(effects
							(font
								(size 1.27 1.27)
							)
						)
					)
					(number "K2"
						(effects
							(font
								(size 1.27 1.27)
							)
						)
					)
				)
				(pin bidirectional line
					(at 0 -10.16 0)
					(length 2.54)
					(name "DAT1"
						(effects
							(font
								(size 1.27 1.27)
							)
						)
					)
					(number "N2"
						(effects
							(font
								(size 1.27 1.27)
							)
						)
					)
				)
				(pin bidirectional line
					(at 0 -12.7 0)
					(length 2.54)
					(name "DAT2"
						(effects
							(font
								(size 1.27 1.27)
							)
						)
					)
					(number "K3"
						(effects
							(font
								(size 1.27 1.27)
							)
						)
					)
				)
				(pin bidirectional line
					(at 0 -15.24 0)
					(length 2.54)
					(name "DAT3"
						(effects
							(font
								(size 1.27 1.27)
							)
						)
					)
					(number "N3"
						(effects
							(font
								(size 1.27 1.27)
							)
						)
					)
				)
				(pin bidirectional line
					(at 0 -17.78 0)
					(length 2.54)
					(name "DAT4"
						(effects
							(font
								(size 1.27 1.27)
							)
						)
					)
					(number "N8"
						(effects
							(font
								(size 1.27 1.27)
							)
						)
					)
				)
				(pin bidirectional line
					(at 0 -20.32 0)
					(length 2.54)
					(name "DAT5"
						(effects
							(font
								(size 1.27 1.27)
							)
						)
					)
					(number "K8"
						(effects
							(font
								(size 1.27 1.27)
							)
						)
					)
				)
				(pin bidirectional line
					(at 0 -22.86 0)
					(length 2.54)
					(name "DAT6"
						(effects
							(font
								(size 1.27 1.27)
							)
						)
					)
					(number "N9"
						(effects
							(font
								(size 1.27 1.27)
							)
						)
					)
				)
				(pin bidirectional line
					(at 0 -25.4 0)
					(length 2.54)
					(name "DAT7"
						(effects
							(font
								(size 1.27 1.27)
							)
						)
					)
					(number "K9"
						(effects
							(font
								(size 1.27 1.27)
							)
						)
					)
				)
				(pin no_connect line
					(at 7.62 1.27 0)
					(length 2.54)
					(hide yes)
					(name "NC"
						(effects
							(font
								(size 1.27 1.27)
							)
						)
					)
					(number "A1"
						(effects
							(font
								(size 1.27 1.27)
							)
						)
					)
				)
				(pin no_connect line
					(at 7.62 -1.27 0)
					(length 2.54)
					(hide yes)
					(name "NC"
						(effects
							(font
								(size 1.27 1.27)
							)
						)
					)
					(number "A2"
						(effects
							(font
								(size 1.27 1.27)
							)
						)
					)
				)
				(pin no_connect line
					(at 7.62 -3.81 0)
					(length 2.54)
					(hide yes)
					(name "NC"
						(effects
							(font
								(size 1.27 1.27)
							)
						)
					)
					(number "A9"
						(effects
							(font
								(size 1.27 1.27)
							)
						)
					)
				)
				(pin no_connect line
					(at 7.62 -6.35 0)
					(length 2.54)
					(hide yes)
					(name "NC"
						(effects
							(font
								(size 1.27 1.27)
							)
						)
					)
					(number "A10"
						(effects
							(font
								(size 1.27 1.27)
							)
						)
					)
				)
				(pin no_connect line
					(at 7.62 -8.89 0)
					(length 2.54)
					(hide yes)
					(name "NC"
						(effects
							(font
								(size 1.27 1.27)
							)
						)
					)
					(number "B1"
						(effects
							(font
								(size 1.27 1.27)
							)
						)
					)
				)
				(pin no_connect line
					(at 7.62 -11.43 0)
					(length 2.54)
					(hide yes)
					(name "NC"
						(effects
							(font
								(size 1.27 1.27)
							)
						)
					)
					(number "B10"
						(effects
							(font
								(size 1.27 1.27)
							)
						)
					)
				)
				(pin no_connect line
					(at 7.62 -13.97 0)
					(length 2.54)
					(hide yes)
					(name "NC"
						(effects
							(font
								(size 1.27 1.27)
							)
						)
					)
					(number "T1"
						(effects
							(font
								(size 1.27 1.27)
							)
						)
					)
				)
				(pin no_connect line
					(at 7.62 -16.51 0)
					(length 2.54)
					(hide yes)
					(name "NC"
						(effects
							(font
								(size 1.27 1.27)
							)
						)
					)
					(number "T10"
						(effects
							(font
								(size 1.27 1.27)
							)
						)
					)
				)
				(pin no_connect line
					(at 7.62 -19.05 0)
					(length 2.54)
					(hide yes)
					(name "NC"
						(effects
							(font
								(size 1.27 1.27)
							)
						)
					)
					(number "U1"
						(effects
							(font
								(size 1.27 1.27)
							)
						)
					)
				)
				(pin no_connect line
					(at 7.62 -21.59 0)
					(length 2.54)
					(hide yes)
					(name "NC"
						(effects
							(font
								(size 1.27 1.27)
							)
						)
					)
					(number "U2"
						(effects
							(font
								(size 1.27 1.27)
							)
						)
					)
				)
				(pin no_connect line
					(at 7.62 -24.13 0)
					(length 2.54)
					(hide yes)
					(name "NC"
						(effects
							(font
								(size 1.27 1.27)
							)
						)
					)
					(number "U9"
						(effects
							(font
								(size 1.27 1.27)
							)
						)
					)
				)
				(pin no_connect line
					(at 7.62 -26.67 0)
					(length 2.54)
					(hide yes)
					(name "NC"
						(effects
							(font
								(size 1.27 1.27)
							)
						)
					)
					(number "U10"
						(effects
							(font
								(size 1.27 1.27)
							)
						)
					)
				)
				(pin no_connect line
					(at 8.89 1.27 0)
					(length 2.54)
					(hide yes)
					(name "RFU"
						(effects
							(font
								(size 1.27 1.27)
							)
						)
					)
					(number "E2"
						(effects
							(font
								(size 1.27 1.27)
							)
						)
					)
				)
				(pin no_connect line
					(at 8.89 -1.27 0)
					(length 2.54)
					(hide yes)
					(name "RFU"
						(effects
							(font
								(size 1.27 1.27)
							)
						)
					)
					(number "E3"
						(effects
							(font
								(size 1.27 1.27)
							)
						)
					)
				)
				(pin no_connect line
					(at 8.89 -3.81 0)
					(length 2.54)
					(hide yes)
					(name "RFU"
						(effects
							(font
								(size 1.27 1.27)
							)
						)
					)
					(number "E5"
						(effects
							(font
								(size 1.27 1.27)
							)
						)
					)
				)
				(pin no_connect line
					(at 8.89 -6.35 0)
					(length 2.54)
					(hide yes)
					(name "RFU"
						(effects
							(font
								(size 1.27 1.27)
							)
						)
					)
					(number "E6"
						(effects
							(font
								(size 1.27 1.27)
							)
						)
					)
				)
				(pin no_connect line
					(at 8.89 -8.89 0)
					(length 2.54)
					(hide yes)
					(name "RFU"
						(effects
							(font
								(size 1.27 1.27)
							)
						)
					)
					(number "E7"
						(effects
							(font
								(size 1.27 1.27)
							)
						)
					)
				)
				(pin no_connect line
					(at 8.89 -11.43 0)
					(length 2.54)
					(hide yes)
					(name "RFU"
						(effects
							(font
								(size 1.27 1.27)
							)
						)
					)
					(number "E8"
						(effects
							(font
								(size 1.27 1.27)
							)
						)
					)
				)
				(pin no_connect line
					(at 8.89 -13.97 0)
					(length 2.54)
					(hide yes)
					(name "RFU"
						(effects
							(font
								(size 1.27 1.27)
							)
						)
					)
					(number "E9"
						(effects
							(font
								(size 1.27 1.27)
							)
						)
					)
				)
				(pin no_connect line
					(at 8.89 -16.51 0)
					(length 2.54)
					(hide yes)
					(name "RFU"
						(effects
							(font
								(size 1.27 1.27)
							)
						)
					)
					(number "H4"
						(effects
							(font
								(size 1.27 1.27)
							)
						)
					)
				)
				(pin no_connect line
					(at 8.89 -19.05 0)
					(length 2.54)
					(hide yes)
					(name "RFU"
						(effects
							(font
								(size 1.27 1.27)
							)
						)
					)
					(number "H5"
						(effects
							(font
								(size 1.27 1.27)
							)
						)
					)
				)
				(pin no_connect line
					(at 8.89 -21.59 0)
					(length 2.54)
					(hide yes)
					(name "RFU"
						(effects
							(font
								(size 1.27 1.27)
							)
						)
					)
					(number "H6"
						(effects
							(font
								(size 1.27 1.27)
							)
						)
					)
				)
				(pin no_connect line
					(at 8.89 -24.13 0)
					(length 2.54)
					(hide yes)
					(name "RFU"
						(effects
							(font
								(size 1.27 1.27)
							)
						)
					)
					(number "H7"
						(effects
							(font
								(size 1.27 1.27)
							)
						)
					)
				)
				(pin no_connect line
					(at 8.89 -26.67 0)
					(length 2.54)
					(hide yes)
					(name "RFU"
						(effects
							(font
								(size 1.27 1.27)
							)
						)
					)
					(number "J2"
						(effects
							(font
								(size 1.27 1.27)
							)
						)
					)
				)
				(pin no_connect line
					(at 10.16 1.27 0)
					(length 2.54)
					(hide yes)
					(name "RFU"
						(effects
							(font
								(size 1.27 1.27)
							)
						)
					)
					(number "J3"
						(effects
							(font
								(size 1.27 1.27)
							)
						)
					)
				)
				(pin no_connect line
					(at 10.16 -1.27 0)
					(length 2.54)
					(hide yes)
					(name "RFU"
						(effects
							(font
								(size 1.27 1.27)
							)
						)
					)
					(number "J4"
						(effects
							(font
								(size 1.27 1.27)
							)
						)
					)
				)
				(pin no_connect line
					(at 10.16 -3.81 0)
					(length 2.54)
					(hide yes)
					(name "RFU"
						(effects
							(font
								(size 1.27 1.27)
							)
						)
					)
					(number "J6"
						(effects
							(font
								(size 1.27 1.27)
							)
						)
					)
				)
				(pin no_connect line
					(at 10.16 -6.35 0)
					(length 2.54)
					(hide yes)
					(name "RFU"
						(effects
							(font
								(size 1.27 1.27)
							)
						)
					)
					(number "J7"
						(effects
							(font
								(size 1.27 1.27)
							)
						)
					)
				)
				(pin no_connect line
					(at 10.16 -8.89 0)
					(length 2.54)
					(hide yes)
					(name "RFU"
						(effects
							(font
								(size 1.27 1.27)
							)
						)
					)
					(number "J8"
						(effects
							(font
								(size 1.27 1.27)
							)
						)
					)
				)
				(pin no_connect line
					(at 10.16 -11.43 0)
					(length 2.54)
					(hide yes)
					(name "RFU"
						(effects
							(font
								(size 1.27 1.27)
							)
						)
					)
					(number "J9"
						(effects
							(font
								(size 1.27 1.27)
							)
						)
					)
				)
				(pin no_connect line
					(at 10.16 -13.97 0)
					(length 2.54)
					(hide yes)
					(name "RFU"
						(effects
							(font
								(size 1.27 1.27)
							)
						)
					)
					(number "K4"
						(effects
							(font
								(size 1.27 1.27)
							)
						)
					)
				)
				(pin no_connect line
					(at 10.16 -16.51 0)
					(length 2.54)
					(hide yes)
					(name "RFU"
						(effects
							(font
								(size 1.27 1.27)
							)
						)
					)
					(number "K6"
						(effects
							(font
								(size 1.27 1.27)
							)
						)
					)
				)
				(pin no_connect line
					(at 10.16 -19.05 0)
					(length 2.54)
					(hide yes)
					(name "RFU"
						(effects
							(font
								(size 1.27 1.27)
							)
						)
					)
					(number "K7"
						(effects
							(font
								(size 1.27 1.27)
							)
						)
					)
				)
				(pin no_connect line
					(at 10.16 -21.59 0)
					(length 2.54)
					(hide yes)
					(name "RFU"
						(effects
							(font
								(size 1.27 1.27)
							)
						)
					)
					(number "L5"
						(effects
							(font
								(size 1.27 1.27)
							)
						)
					)
				)
				(pin no_connect line
					(at 10.16 -24.13 0)
					(length 2.54)
					(hide yes)
					(name "RFU"
						(effects
							(font
								(size 1.27 1.27)
							)
						)
					)
					(number "L6"
						(effects
							(font
								(size 1.27 1.27)
							)
						)
					)
				)
				(pin no_connect line
					(at 10.16 -26.67 0)
					(length 2.54)
					(hide yes)
					(name "RFU"
						(effects
							(font
								(size 1.27 1.27)
							)
						)
					)
					(number "M2"
						(effects
							(font
								(size 1.27 1.27)
							)
						)
					)
				)
				(pin no_connect line
					(at 11.43 1.27 0)
					(length 2.54)
					(hide yes)
					(name "RFU"
						(effects
							(font
								(size 1.27 1.27)
							)
						)
					)
					(number "M3"
						(effects
							(font
								(size 1.27 1.27)
							)
						)
					)
				)
				(pin no_connect line
					(at 11.43 -1.27 0)
					(length 2.54)
					(hide yes)
					(name "RFU"
						(effects
							(font
								(size 1.27 1.27)
							)
						)
					)
					(number "M6"
						(effects
							(font
								(size 1.27 1.27)
							)
						)
					)
				)
				(pin no_connect line
					(at 11.43 -3.81 0)
					(length 2.54)
					(hide yes)
					(name "RFU"
						(effects
							(font
								(size 1.27 1.27)
							)
						)
					)
					(number "M8"
						(effects
							(font
								(size 1.27 1.27)
							)
						)
					)
				)
				(pin no_connect line
					(at 11.43 -6.35 0)
					(length 2.54)
					(hide yes)
					(name "RFU"
						(effects
							(font
								(size 1.27 1.27)
							)
						)
					)
					(number "M9"
						(effects
							(font
								(size 1.27 1.27)
							)
						)
					)
				)
				(pin no_connect line
					(at 11.43 -8.89 0)
					(length 2.54)
					(hide yes)
					(name "RFU"
						(effects
							(font
								(size 1.27 1.27)
							)
						)
					)
					(number "N4"
						(effects
							(font
								(size 1.27 1.27)
							)
						)
					)
				)
				(pin no_connect line
					(at 11.43 -11.43 0)
					(length 2.54)
					(hide yes)
					(name "RFU"
						(effects
							(font
								(size 1.27 1.27)
							)
						)
					)
					(number "N5"
						(effects
							(font
								(size 1.27 1.27)
							)
						)
					)
				)
				(pin no_connect line
					(at 11.43 -13.97 0)
					(length 2.54)
					(hide yes)
					(name "RFU"
						(effects
							(font
								(size 1.27 1.27)
							)
						)
					)
					(number "N6"
						(effects
							(font
								(size 1.27 1.27)
							)
						)
					)
				)
				(pin no_connect line
					(at 11.43 -16.51 0)
					(length 2.54)
					(hide yes)
					(name "RFU"
						(effects
							(font
								(size 1.27 1.27)
							)
						)
					)
					(number "N7"
						(effects
							(font
								(size 1.27 1.27)
							)
						)
					)
				)
				(pin no_connect line
					(at 11.43 -19.05 0)
					(length 2.54)
					(hide yes)
					(name "RFU"
						(effects
							(font
								(size 1.27 1.27)
							)
						)
					)
					(number "P4"
						(effects
							(font
								(size 1.27 1.27)
							)
						)
					)
				)
				(pin no_connect line
					(at 11.43 -21.59 0)
					(length 2.54)
					(hide yes)
					(name "RFU"
						(effects
							(font
								(size 1.27 1.27)
							)
						)
					)
					(number "P7"
						(effects
							(font
								(size 1.27 1.27)
							)
						)
					)
				)
				(pin no_connect line
					(at 12.7 -8.89 0)
					(length 2.54)
					(hide yes)
					(name "VSF1"
						(effects
							(font
								(size 1.27 1.27)
							)
						)
					)
					(number "D2"
						(effects
							(font
								(size 1.27 1.27)
							)
						)
					)
				)
				(pin no_connect line
					(at 12.7 -11.43 0)
					(length 2.54)
					(hide yes)
					(name "VSF2"
						(effects
							(font
								(size 1.27 1.27)
							)
						)
					)
					(number "D3"
						(effects
							(font
								(size 1.27 1.27)
							)
						)
					)
				)
				(pin no_connect line
					(at 12.7 -13.97 0)
					(length 2.54)
					(hide yes)
					(name "VSF3"
						(effects
							(font
								(size 1.27 1.27)
							)
						)
					)
					(number "D4"
						(effects
							(font
								(size 1.27 1.27)
							)
						)
					)
				)
				(pin no_connect line
					(at 12.7 -16.51 0)
					(length 2.54)
					(hide yes)
					(name "VSF4"
						(effects
							(font
								(size 1.27 1.27)
							)
						)
					)
					(number "D5"
						(effects
							(font
								(size 1.27 1.27)
							)
						)
					)
				)
				(pin no_connect line
					(at 12.7 -19.05 0)
					(length 2.54)
					(hide yes)
					(name "VSF5"
						(effects
							(font
								(size 1.27 1.27)
							)
						)
					)
					(number "D6"
						(effects
							(font
								(size 1.27 1.27)
							)
						)
					)
				)
				(pin no_connect line
					(at 12.7 -21.59 0)
					(length 2.54)
					(hide yes)
					(name "VSF6"
						(effects
							(font
								(size 1.27 1.27)
							)
						)
					)
					(number "D7"
						(effects
							(font
								(size 1.27 1.27)
							)
						)
					)
				)
				(pin no_connect line
					(at 12.7 -24.13 0)
					(length 2.54)
					(hide yes)
					(name "VSF7"
						(effects
							(font
								(size 1.27 1.27)
							)
						)
					)
					(number "D8"
						(effects
							(font
								(size 1.27 1.27)
							)
						)
					)
				)
				(pin no_connect line
					(at 12.7 -26.67 0)
					(length 2.54)
					(hide yes)
					(name "VSF8"
						(effects
							(font
								(size 1.27 1.27)
							)
						)
					)
					(number "D9"
						(effects
							(font
								(size 1.27 1.27)
							)
						)
					)
				)
				(pin power_in line
					(at 20.32 0 180)
					(length 2.54)
					(name "VCC"
						(effects
							(font
								(size 1.27 1.27)
							)
						)
					)
					(number "F2"
						(effects
							(font
								(size 1.27 1.27)
							)
						)
					)
				)
				(pin power_in line
					(at 20.32 -2.54 180)
					(length 2.54)
					(name "VCCQ"
						(effects
							(font
								(size 1.27 1.27)
							)
						)
					)
					(number "H3"
						(effects
							(font
								(size 1.27 1.27)
							)
						)
					)
				)
				(pin passive line
					(at 20.32 -2.54 180)
					(length 2.54)
					(hide yes)
					(name "VCCQ"
						(effects
							(font
								(size 1.27 1.27)
							)
						)
					)
					(number "H8"
						(effects
							(font
								(size 1.27 1.27)
							)
						)
					)
				)
				(pin passive line
					(at 20.32 -2.54 180)
					(length 2.54)
					(hide yes)
					(name "VCCQ"
						(effects
							(font
								(size 1.27 1.27)
							)
						)
					)
					(number "L2"
						(effects
							(font
								(size 1.27 1.27)
							)
						)
					)
				)
				(pin passive line
					(at 20.32 -2.54 180)
					(length 2.54)
					(hide yes)
					(name "VCCQ"
						(effects
							(font
								(size 1.27 1.27)
							)
						)
					)
					(number "L4"
						(effects
							(font
								(size 1.27 1.27)
							)
						)
					)
				)
				(pin passive line
					(at 20.32 -2.54 180)
					(length 2.54)
					(hide yes)
					(name "VCCQ"
						(effects
							(font
								(size 1.27 1.27)
							)
						)
					)
					(number "L7"
						(effects
							(font
								(size 1.27 1.27)
							)
						)
					)
				)
				(pin passive line
					(at 20.32 -2.54 180)
					(length 2.54)
					(hide yes)
					(name "VCCQ"
						(effects
							(font
								(size 1.27 1.27)
							)
						)
					)
					(number "L9"
						(effects
							(font
								(size 1.27 1.27)
							)
						)
					)
				)
				(pin passive line
					(at 20.32 -2.54 180)
					(length 2.54)
					(hide yes)
					(name "VCCQ"
						(effects
							(font
								(size 1.27 1.27)
							)
						)
					)
					(number "P3"
						(effects
							(font
								(size 1.27 1.27)
							)
						)
					)
				)
				(pin passive line
					(at 20.32 -2.54 180)
					(length 2.54)
					(hide yes)
					(name "VCCQ"
						(effects
							(font
								(size 1.27 1.27)
							)
						)
					)
					(number "P8"
						(effects
							(font
								(size 1.27 1.27)
							)
						)
					)
				)
				(pin power_in line
					(at 20.32 -5.08 180)
					(length 2.54)
					(name "VDDIM"
						(effects
							(font
								(size 1.27 1.27)
							)
						)
					)
					(number "E4"
						(effects
							(font
								(size 1.27 1.27)
							)
						)
					)
				)
				(pin output line
					(at 20.32 -12.7 180)
					(length 2.54)
					(name "DS"
						(effects
							(font
								(size 1.27 1.27)
							)
						)
					)
					(number "K5"
						(effects
							(font
								(size 1.27 1.27)
							)
						)
					)
				)
				(pin power_in line
					(at 20.32 -25.4 180)
					(length 2.54)
					(name "VSSQ"
						(effects
							(font
								(size 1.27 1.27)
							)
						)
					)
					(number "H2"
						(effects
							(font
								(size 1.27 1.27)
							)
						)
					)
				)
				(pin passive line
					(at 20.32 -25.4 180)
					(length 2.54)
					(hide yes)
					(name "VSSQ"
						(effects
							(font
								(size 1.27 1.27)
							)
						)
					)
					(number "H9"
						(effects
							(font
								(size 1.27 1.27)
							)
						)
					)
				)
				(pin passive line
					(at 20.32 -25.4 180)
					(length 2.54)
					(hide yes)
					(name "VSSQ"
						(effects
							(font
								(size 1.27 1.27)
							)
						)
					)
					(number "L3"
						(effects
							(font
								(size 1.27 1.27)
							)
						)
					)
				)
				(pin passive line
					(at 20.32 -25.4 180)
					(length 2.54)
					(hide yes)
					(name "VSSQ"
						(effects
							(font
								(size 1.27 1.27)
							)
						)
					)
					(number "L8"
						(effects
							(font
								(size 1.27 1.27)
							)
						)
					)
				)
				(pin passive line
					(at 20.32 -25.4 180)
					(length 2.54)
					(hide yes)
					(name "VSSQ"
						(effects
							(font
								(size 1.27 1.27)
							)
						)
					)
					(number "M4"
						(effects
							(font
								(size 1.27 1.27)
							)
						)
					)
				)
				(pin passive line
					(at 20.32 -25.4 180)
					(length 2.54)
					(hide yes)
					(name "VSSQ"
						(effects
							(font
								(size 1.27 1.27)
							)
						)
					)
					(number "M7"
						(effects
							(font
								(size 1.27 1.27)
							)
						)
					)
				)
				(pin passive line
					(at 20.32 -25.4 180)
					(length 2.54)
					(hide yes)
					(name "VSSQ"
						(effects
							(font
								(size 1.27 1.27)
							)
						)
					)
					(number "P2"
						(effects
							(font
								(size 1.27 1.27)
							)
						)
					)
				)
				(pin passive line
					(at 20.32 -25.4 180)
					(length 2.54)
					(hide yes)
					(name "VSSQ"
						(effects
							(font
								(size 1.27 1.27)
							)
						)
					)
					(number "P9"
						(effects
							(font
								(size 1.27 1.27)
							)
						)
					)
				)
			)
			(symbol "MTFC16GAPALNA-AIT_1_1"
				(pin passive line
					(at 20.32 0 180)
					(length 2.54)
					(hide yes)
					(name "VCC"
						(effects
							(font
								(size 1.27 1.27)
							)
						)
					)
					(number "F3"
						(effects
							(font
								(size 1.27 1.27)
							)
						)
					)
				)
				(pin passive line
					(at 20.32 0 180)
					(length 2.54)
					(hide yes)
					(name "VCC"
						(effects
							(font
								(size 1.27 1.27)
							)
						)
					)
					(number "F4"
						(effects
							(font
								(size 1.27 1.27)
							)
						)
					)
				)
				(pin passive line
					(at 20.32 0 180)
					(length 2.54)
					(hide yes)
					(name "VCC"
						(effects
							(font
								(size 1.27 1.27)
							)
						)
					)
					(number "F5"
						(effects
							(font
								(size 1.27 1.27)
							)
						)
					)
				)
				(pin passive line
					(at 20.32 0 180)
					(length 2.54)
					(hide yes)
					(name "VCC"
						(effects
							(font
								(size 1.27 1.27)
							)
						)
					)
					(number "F6"
						(effects
							(font
								(size 1.27 1.27)
							)
						)
					)
				)
				(pin passive line
					(at 20.32 0 180)
					(length 2.54)
					(hide yes)
					(name "VCC"
						(effects
							(font
								(size 1.27 1.27)
							)
						)
					)
					(number "F7"
						(effects
							(font
								(size 1.27 1.27)
							)
						)
					)
				)
				(pin passive line
					(at 20.32 0 180)
					(length 2.54)
					(hide yes)
					(name "VCC"
						(effects
							(font
								(size 1.27 1.27)
							)
						)
					)
					(number "F8"
						(effects
							(font
								(size 1.27 1.27)
							)
						)
					)
				)
				(pin passive line
					(at 20.32 0 180)
					(length 2.54)
					(hide yes)
					(name "VCC"
						(effects
							(font
								(size 1.27 1.27)
							)
						)
					)
					(number "F9"
						(effects
							(font
								(size 1.27 1.27)
							)
						)
					)
				)
				(pin power_in line
					(at 20.32 -22.86 180)
					(length 2.54)
					(name "VSS"
						(effects
							(font
								(size 1.27 1.27)
							)
						)
					)
					(number "G2"
						(effects
							(font
								(size 1.27 1.27)
							)
						)
					)
				)
				(pin passive line
					(at 20.32 -22.86 180)
					(length 2.54)
					(hide yes)
					(name "VSS"
						(effects
							(font
								(size 1.27 1.27)
							)
						)
					)
					(number "G3"
						(effects
							(font
								(size 1.27 1.27)
							)
						)
					)
				)
				(pin passive line
					(at 20.32 -22.86 180)
					(length 2.54)
					(hide yes)
					(name "VSS"
						(effects
							(font
								(size 1.27 1.27)
							)
						)
					)
					(number "G4"
						(effects
							(font
								(size 1.27 1.27)
							)
						)
					)
				)
				(pin passive line
					(at 20.32 -22.86 180)
					(length 2.54)
					(hide yes)
					(name "VSS"
						(effects
							(font
								(size 1.27 1.27)
							)
						)
					)
					(number "G5"
						(effects
							(font
								(size 1.27 1.27)
							)
						)
					)
				)
				(pin passive line
					(at 20.32 -22.86 180)
					(length 2.54)
					(hide yes)
					(name "VSS"
						(effects
							(font
								(size 1.27 1.27)
							)
						)
					)
					(number "G6"
						(effects
							(font
								(size 1.27 1.27)
							)
						)
					)
				)
				(pin passive line
					(at 20.32 -22.86 180)
					(length 2.54)
					(hide yes)
					(name "VSS"
						(effects
							(font
								(size 1.27 1.27)
							)
						)
					)
					(number "G7"
						(effects
							(font
								(size 1.27 1.27)
							)
						)
					)
				)
				(pin passive line
					(at 20.32 -22.86 180)
					(length 2.54)
					(hide yes)
					(name "VSS"
						(effects
							(font
								(size 1.27 1.27)
							)
						)
					)
					(number "G8"
						(effects
							(font
								(size 1.27 1.27)
							)
						)
					)
				)
				(pin passive line
					(at 20.32 -22.86 180)
					(length 2.54)
					(hide yes)
					(name "VSS"
						(effects
							(font
								(size 1.27 1.27)
							)
						)
					)
					(number "G9"
						(effects
							(font
								(size 1.27 1.27)
							)
						)
					)
				)
				(pin passive line
					(at 20.32 -22.86 180)
					(length 2.54)
					(hide yes)
					(name "VSS"
						(effects
							(font
								(size 1.27 1.27)
							)
						)
					)
					(number "J5"
						(effects
							(font
								(size 1.27 1.27)
							)
						)
					)
				)
			)
		)
	(symbol "antmicroMemory:W25Q32JW_SOIC-8"
			(exclude_from_sim no)
			(in_bom yes)
			(on_board yes)
			(property "Reference" "U"
				(at 33.02 -3.81 0)
				(effects
					(font
						(size 1.27 1.27)
						(thickness 0.15)
					)
					(justify left bottom)
				)
			)
			(property "Value" "W25Q32JW_SOIC-8"
				(at 33.02 -6.35 0)
				(effects
					(font
						(size 1.27 1.27)
						(thickness 0.15)
					)
					(justify left bottom)
					(hide yes)
				)
			)
			(property "Footprint" "antmicro-footprints:SOIC-8_5.3x5.3x2mm_P1.27mm"
				(at 33.02 -8.89 0)
				(effects
					(font
						(size 1.27 1.27)
						(thickness 0.15)
					)
					(justify left bottom)
					(hide yes)
				)
			)
			(property "Datasheet" "https://www.mouser.com/datasheet/2/949/w25q32jw_spi_revf_09042018-1489621.pdf"
				(at 33.02 -11.43 0)
				(effects
					(font
						(size 1.27 1.27)
						(thickness 0.15)
					)
					(justify left bottom)
					(hide yes)
				)
			)
			(property "Description" "FLASH - NOR Memory IC 32Mbit SPI - Quad I/O 133 MHz 8-SOIC"
				(at 33.02 -24.13 0)
				(effects
					(font
						(size 1.27 1.27)
					)
					(justify left bottom)
					(hide yes)
				)
			)
			(property "MPN" "W25Q32JWSSIQ"
				(at 33.02 -13.97 0)
				(effects
					(font
						(size 1.27 1.27)
						(thickness 0.15)
					)
					(justify left bottom)
				)
			)
			(property "Manufacturer" "Winbond"
				(at 33.02 -16.51 0)
				(effects
					(font
						(size 1.27 1.27)
						(thickness 0.15)
					)
					(justify left bottom)
					(hide yes)
				)
			)
			(property "Author" "Antmicro"
				(at 33.02 -19.05 0)
				(effects
					(font
						(size 1.27 1.27)
						(thickness 0.15)
					)
					(justify left bottom)
					(hide yes)
				)
			)
			(property "License" "Apache-2.0"
				(at 33.02 -21.59 0)
				(effects
					(font
						(size 1.27 1.27)
						(thickness 0.15)
					)
					(justify left bottom)
					(hide yes)
				)
			)
			(property "ki_keywords" "IC"
				(at 0 0 0)
				(effects
					(font
						(size 1.27 1.27)
					)
					(hide yes)
				)
			)
			(symbol "W25Q32JW_SOIC-8_1_1"
				(rectangle
					(start 2.54 2.54)
					(end 16.51 -15.24)
					(stroke
						(width 0.254)
						(type default)
					)
					(fill
						(type background)
					)
				)
				(pin bidirectional line
					(at 0 0 0)
					(length 2.54)
					(name "SI/IO0"
						(effects
							(font
								(size 1.27 1.27)
							)
						)
					)
					(number "5"
						(effects
							(font
								(size 1.27 1.27)
							)
						)
					)
				)
				(pin bidirectional line
					(at 0 -2.54 0)
					(length 2.54)
					(name "SO/IO1"
						(effects
							(font
								(size 1.27 1.27)
							)
						)
					)
					(number "2"
						(effects
							(font
								(size 1.27 1.27)
							)
						)
					)
				)
				(pin bidirectional line
					(at 0 -5.08 0)
					(length 2.54)
					(name "~{WP}/IO2"
						(effects
							(font
								(size 1.27 1.27)
							)
						)
					)
					(number "3"
						(effects
							(font
								(size 1.27 1.27)
							)
						)
					)
				)
				(pin bidirectional line
					(at 0 -7.62 0)
					(length 2.54)
					(name "~{HOLD}/IO3"
						(effects
							(font
								(size 1.27 1.27)
							)
						)
					)
					(number "7"
						(effects
							(font
								(size 1.27 1.27)
							)
						)
					)
				)
				(pin input line
					(at 0 -10.16 0)
					(length 2.54)
					(name "SCLK"
						(effects
							(font
								(size 1.27 1.27)
							)
						)
					)
					(number "6"
						(effects
							(font
								(size 1.27 1.27)
							)
						)
					)
				)
				(pin input line
					(at 0 -12.7 0)
					(length 2.54)
					(name "~{CS}"
						(effects
							(font
								(size 1.27 1.27)
							)
						)
					)
					(number "1"
						(effects
							(font
								(size 1.27 1.27)
							)
						)
					)
				)
				(pin power_in line
					(at 19.05 0 180)
					(length 2.54)
					(name "VCC"
						(effects
							(font
								(size 1.27 1.27)
							)
						)
					)
					(number "8"
						(effects
							(font
								(size 1.27 1.27)
							)
						)
					)
				)
				(pin power_in line
					(at 19.05 -12.7 180)
					(length 2.54)
					(name "VSS"
						(effects
							(font
								(size 1.27 1.27)
							)
						)
					)
					(number "4"
						(effects
							(font
								(size 1.27 1.27)
							)
						)
					)
				)
			)
		)
	(symbol "antmicroModularConnectorsJacksWithMagnetics:L834-1G1T-S7"
			(exclude_from_sim no)
			(in_bom yes)
			(on_board yes)
			(property "Reference" "J"
				(at 33.02 -2.54 0)
				(effects
					(font
						(size 1.27 1.27)
						(thickness 0.15)
					)
					(justify left bottom)
				)
			)
			(property "Value" "L834-1G1T-S7"
				(at 33.02 -5.08 0)
				(effects
					(font
						(size 1.27 1.27)
						(thickness 0.15)
					)
					(justify left bottom)
					(hide yes)
				)
			)
			(property "Footprint" "antmicro-footprints:RJ45_BEL_L834-1G1T-S7"
				(at 33.02 -7.62 0)
				(effects
					(font
						(size 1.27 1.27)
						(thickness 0.15)
					)
					(justify left bottom)
					(hide yes)
				)
			)
			(property "Datasheet" "https://www.belfuse.com/resources/drawings/magneticsolutions/dr-mag-l834-1g1t-s7.pdf"
				(at 33.02 -10.16 0)
				(effects
					(font
						(size 1.27 1.27)
						(thickness 0.15)
					)
					(justify left bottom)
					(hide yes)
				)
			)
			(property "Description" "Modular connector with magnetics"
				(at 33.02 -22.86 0)
				(effects
					(font
						(size 1.27 1.27)
					)
					(justify left bottom)
					(hide yes)
				)
			)
			(property "MPN" "L834-1G1T-S7"
				(at 33.02 -12.7 0)
				(effects
					(font
						(size 1.27 1.27)
						(thickness 0.15)
					)
					(justify left bottom)
				)
			)
			(property "Manufacturer" "Bel Fuse"
				(at 33.02 -15.24 0)
				(effects
					(font
						(size 1.27 1.27)
						(thickness 0.15)
					)
					(justify left bottom)
					(hide yes)
				)
			)
			(property "Author" "Antmicro"
				(at 33.02 -17.78 0)
				(effects
					(font
						(size 1.27 1.27)
						(thickness 0.15)
					)
					(justify left bottom)
					(hide yes)
				)
			)
			(property "License" "Apache-2.0"
				(at 33.02 -20.32 0)
				(effects
					(font
						(size 1.27 1.27)
						(thickness 0.15)
					)
					(justify left bottom)
					(hide yes)
				)
			)
			(property "ki_keywords" "HORIZONTAL, THT, FILTERED, CONNECTOR, ETHERNET"
				(at 0 0 0)
				(effects
					(font
						(size 1.27 1.27)
					)
					(hide yes)
				)
			)
			(symbol "L834-1G1T-S7_0_0"
				(pin passive line
					(at 0 0 0)
					(length 2.54)
					(name "TRD1+"
						(effects
							(font
								(size 1.27 1.27)
							)
						)
					)
					(number "11"
						(effects
							(font
								(size 1.27 1.27)
							)
						)
					)
				)
				(pin passive line
					(at 0 -2.54 0)
					(length 2.54)
					(name "TRD1-"
						(effects
							(font
								(size 1.27 1.27)
							)
						)
					)
					(number "10"
						(effects
							(font
								(size 1.27 1.27)
							)
						)
					)
				)
				(pin passive line
					(at 0 -6.35 0)
					(length 2.54)
					(name "TRD2+"
						(effects
							(font
								(size 1.27 1.27)
							)
						)
					)
					(number "4"
						(effects
							(font
								(size 1.27 1.27)
							)
						)
					)
				)
				(pin passive line
					(at 0 -8.89 0)
					(length 2.54)
					(name "TRD2-"
						(effects
							(font
								(size 1.27 1.27)
							)
						)
					)
					(number "5"
						(effects
							(font
								(size 1.27 1.27)
							)
						)
					)
				)
				(pin passive line
					(at 0 -12.7 0)
					(length 2.54)
					(name "TRD3+"
						(effects
							(font
								(size 1.27 1.27)
							)
						)
					)
					(number "3"
						(effects
							(font
								(size 1.27 1.27)
							)
						)
					)
				)
				(pin passive line
					(at 0 -15.24 0)
					(length 2.54)
					(name "TRD3-"
						(effects
							(font
								(size 1.27 1.27)
							)
						)
					)
					(number "2"
						(effects
							(font
								(size 1.27 1.27)
							)
						)
					)
				)
				(pin passive line
					(at 0 -19.05 0)
					(length 2.54)
					(name "TRD4+"
						(effects
							(font
								(size 1.27 1.27)
							)
						)
					)
					(number "8"
						(effects
							(font
								(size 1.27 1.27)
							)
						)
					)
				)
				(pin passive line
					(at 0 -21.59 0)
					(length 2.54)
					(name "TRD4-"
						(effects
							(font
								(size 1.27 1.27)
							)
						)
					)
					(number "9"
						(effects
							(font
								(size 1.27 1.27)
							)
						)
					)
				)
				(pin passive line
					(at 0 -25.4 0)
					(length 2.54)
					(name "TRCT1"
						(effects
							(font
								(size 1.27 1.27)
							)
						)
					)
					(number "12"
						(effects
							(font
								(size 1.27 1.27)
							)
						)
					)
				)
				(pin passive line
					(at 0 -27.94 0)
					(length 2.54)
					(name "TRCT2"
						(effects
							(font
								(size 1.27 1.27)
							)
						)
					)
					(number "6"
						(effects
							(font
								(size 1.27 1.27)
							)
						)
					)
				)
				(pin passive line
					(at 0 -30.48 0)
					(length 2.54)
					(name "TRCT3"
						(effects
							(font
								(size 1.27 1.27)
							)
						)
					)
					(number "1"
						(effects
							(font
								(size 1.27 1.27)
							)
						)
					)
				)
				(pin passive line
					(at 0 -33.02 0)
					(length 2.54)
					(name "TRCT4"
						(effects
							(font
								(size 1.27 1.27)
							)
						)
					)
					(number "7"
						(effects
							(font
								(size 1.27 1.27)
							)
						)
					)
				)
				(pin passive line
					(at 17.78 -3.81 180)
					(length 2.54)
					(name "~"
						(effects
							(font
								(size 1.27 1.27)
							)
						)
					)
					(number "14"
						(effects
							(font
								(size 1.27 1.27)
							)
						)
					)
				)
				(pin passive line
					(at 17.78 -7.62 180)
					(length 2.54)
					(name "~"
						(effects
							(font
								(size 1.27 1.27)
							)
						)
					)
					(number "13"
						(effects
							(font
								(size 1.27 1.27)
							)
						)
					)
				)
				(pin passive line
					(at 17.78 -30.48 180)
					(length 2.54)
					(name "SH"
						(effects
							(font
								(size 1.27 1.27)
							)
						)
					)
					(number "SH"
						(effects
							(font
								(size 1.27 1.27)
							)
						)
					)
				)
			)
			(symbol "L834-1G1T-S7_1_1"
				(rectangle
					(start 2.54 2.54)
					(end 15.24 -35.56)
					(stroke
						(width 0.254)
						(type default)
					)
					(fill
						(type background)
					)
				)
				(polyline
					(pts
						(xy 11.43 -15.113) (xy 11.938 -14.859) (xy 11.684 -14.605) (xy 11.43 -15.113)
					)
					(stroke
						(width 0.254)
						(type default)
					)
					(fill
						(type background)
					)
				)
				(polyline
					(pts
						(xy 11.43 -15.875) (xy 11.938 -15.621) (xy 11.684 -15.367) (xy 11.43 -15.875)
					)
					(stroke
						(width 0.254)
						(type default)
					)
					(fill
						(type background)
					)
				)
				(polyline
					(pts
						(xy 11.557 -6.223) (xy 12.065 -5.969) (xy 11.811 -5.715) (xy 11.557 -6.223)
					)
					(stroke
						(width 0.254)
						(type default)
					)
					(fill
						(type background)
					)
				)
				(polyline
					(pts
						(xy 11.557 -6.985) (xy 12.065 -6.731) (xy 11.811 -6.477) (xy 11.557 -6.985)
					)
					(stroke
						(width 0.254)
						(type default)
					)
					(fill
						(type background)
					)
				)
				(polyline
					(pts
						(xy 11.938 -14.605) (xy 11.684 -14.859)
					)
					(stroke
						(width 0.254)
						(type default)
					)
					(fill
						(type background)
					)
				)
				(polyline
					(pts
						(xy 11.938 -15.367) (xy 11.684 -15.621)
					)
					(stroke
						(width 0.254)
						(type default)
					)
					(fill
						(type background)
					)
				)
				(polyline
					(pts
						(xy 12.065 -5.715) (xy 11.811 -5.969)
					)
					(stroke
						(width 0.254)
						(type default)
					)
					(fill
						(type background)
					)
				)
				(polyline
					(pts
						(xy 12.065 -6.477) (xy 11.811 -6.731)
					)
					(stroke
						(width 0.254)
						(type default)
					)
					(fill
						(type background)
					)
				)
				(polyline
					(pts
						(xy 12.192 -14.097) (xy 12.573 -15.113)
					)
					(stroke
						(width 0.254)
						(type default)
					)
					(fill
						(type background)
					)
				)
				(polyline
					(pts
						(xy 12.192 -14.097) (xy 12.954 -14.097)
					)
					(stroke
						(width 0.254)
						(type default)
					)
					(fill
						(type background)
					)
				)
				(polyline
					(pts
						(xy 12.192 -15.113) (xy 12.573 -15.113)
					)
					(stroke
						(width 0.254)
						(type default)
					)
					(fill
						(type background)
					)
				)
				(polyline
					(pts
						(xy 12.319 -5.207) (xy 12.7 -6.223)
					)
					(stroke
						(width 0.254)
						(type default)
					)
					(fill
						(type background)
					)
				)
				(polyline
					(pts
						(xy 12.319 -5.207) (xy 13.081 -5.207)
					)
					(stroke
						(width 0.254)
						(type default)
					)
					(fill
						(type background)
					)
				)
				(polyline
					(pts
						(xy 12.319 -6.223) (xy 12.7 -6.223)
					)
					(stroke
						(width 0.254)
						(type default)
					)
					(fill
						(type background)
					)
				)
				(polyline
					(pts
						(xy 12.446 -15.113) (xy 12.954 -15.113)
					)
					(stroke
						(width 0.254)
						(type default)
					)
					(fill
						(type background)
					)
				)
				(polyline
					(pts
						(xy 12.573 -6.223) (xy 13.081 -6.223)
					)
					(stroke
						(width 0.254)
						(type default)
					)
					(fill
						(type background)
					)
				)
				(polyline
					(pts
						(xy 12.573 -12.7) (xy 15.113 -12.7)
					)
					(stroke
						(width 0.254)
						(type default)
					)
					(fill
						(type background)
					)
				)
				(polyline
					(pts
						(xy 12.573 -13.589) (xy 12.573 -12.7)
					)
					(stroke
						(width 0.254)
						(type default)
					)
					(fill
						(type background)
					)
				)
				(polyline
					(pts
						(xy 12.573 -14.097) (xy 12.573 -13.462)
					)
					(stroke
						(width 0.254)
						(type default)
					)
					(fill
						(type background)
					)
				)
				(polyline
					(pts
						(xy 12.573 -15.113) (xy 12.954 -14.097)
					)
					(stroke
						(width 0.254)
						(type default)
					)
					(fill
						(type background)
					)
				)
				(polyline
					(pts
						(xy 12.573 -15.24) (xy 12.573 -16.002)
					)
					(stroke
						(width 0.254)
						(type default)
					)
					(fill
						(type background)
					)
				)
				(polyline
					(pts
						(xy 12.573 -16.51) (xy 12.573 -15.494)
					)
					(stroke
						(width 0.254)
						(type default)
					)
					(fill
						(type background)
					)
				)
				(polyline
					(pts
						(xy 12.573 -16.51) (xy 15.113 -16.51)
					)
					(stroke
						(width 0.254)
						(type default)
					)
					(fill
						(type background)
					)
				)
				(polyline
					(pts
						(xy 12.7 -3.81) (xy 15.24 -3.81)
					)
					(stroke
						(width 0.254)
						(type default)
					)
					(fill
						(type background)
					)
				)
				(polyline
					(pts
						(xy 12.7 -4.699) (xy 12.7 -3.81)
					)
					(stroke
						(width 0.254)
						(type default)
					)
					(fill
						(type background)
					)
				)
				(polyline
					(pts
						(xy 12.7 -5.207) (xy 12.7 -4.572)
					)
					(stroke
						(width 0.254)
						(type default)
					)
					(fill
						(type background)
					)
				)
				(polyline
					(pts
						(xy 12.7 -6.223) (xy 13.081 -5.207)
					)
					(stroke
						(width 0.254)
						(type default)
					)
					(fill
						(type background)
					)
				)
				(polyline
					(pts
						(xy 12.7 -6.35) (xy 12.7 -7.112)
					)
					(stroke
						(width 0.254)
						(type default)
					)
					(fill
						(type background)
					)
				)
				(polyline
					(pts
						(xy 12.7 -7.62) (xy 12.7 -6.604)
					)
					(stroke
						(width 0.254)
						(type default)
					)
					(fill
						(type background)
					)
				)
				(polyline
					(pts
						(xy 12.7 -7.62) (xy 15.24 -7.62)
					)
					(stroke
						(width 0.254)
						(type default)
					)
					(fill
						(type background)
					)
				)
				(text "G"
					(at 13.208 -15.621 0)
					(effects
						(font
							(size 1.27 1.27)
							(thickness 0.15)
						)
						(justify left bottom)
					)
				)
				(text "G"
					(at 13.335 -6.731 0)
					(effects
						(font
							(size 1.27 1.27)
							(thickness 0.15)
						)
						(justify left bottom)
					)
				)
				(pin passive line
					(at 17.78 -12.7 180)
					(length 2.54)
					(name "~"
						(effects
							(font
								(size 1.27 1.27)
							)
						)
					)
					(number "16"
						(effects
							(font
								(size 1.27 1.27)
							)
						)
					)
				)
				(pin passive line
					(at 17.78 -16.51 180)
					(length 2.54)
					(name "~"
						(effects
							(font
								(size 1.27 1.27)
							)
						)
					)
					(number "15"
						(effects
							(font
								(size 1.27 1.27)
							)
						)
					)
				)
			)
		)
	(symbol "antmicroOscillators:Oscillator_100MHz_AMJMEFB"
			(exclude_from_sim no)
			(in_bom yes)
			(on_board yes)
			(property "Reference" "Y"
				(at 26.035 -1.905 0)
				(effects
					(font
						(size 1.27 1.27)
						(thickness 0.15)
					)
					(justify left bottom)
				)
			)
			(property "Value" "Oscillator_100MHz_AMJMEFB"
				(at 26.035 -12.065 0)
				(effects
					(font
						(size 1.27 1.27)
						(thickness 0.15)
					)
					(justify left bottom)
					(hide yes)
				)
			)
			(property "Footprint" "antmicro-footprints:Oscillator_SMD_Abracon_AMJM_3.2x2.5mm"
				(at 26.035 -14.605 0)
				(effects
					(font
						(size 1.27 1.27)
						(thickness 0.15)
					)
					(justify left bottom)
					(hide yes)
				)
			)
			(property "Datasheet" "https://abracon.com/datasheets/AMJM.pdf"
				(at 26.035 -17.145 0)
				(effects
					(font
						(size 1.27 1.27)
						(thickness 0.15)
					)
					(justify left bottom)
					(hide yes)
				)
			)
			(property "Description" "MEMS Oscillator, 100 MHz, SMT, 3.2mm x 2.5mm, 25 ppm, 2.5 V, AMJM"
				(at 26.035 -24.765 0)
				(effects
					(font
						(size 1.27 1.27)
					)
					(justify left bottom)
					(hide yes)
				)
			)
			(property "MPN" "AMJMEFB-100.0000T"
				(at 26.035 -4.445 0)
				(effects
					(font
						(size 1.27 1.27)
						(thickness 0.15)
					)
					(justify left bottom)
				)
			)
			(property "Manufacturer" "Abracon"
				(at 26.035 -6.985 0)
				(effects
					(font
						(size 1.27 1.27)
						(thickness 0.15)
					)
					(justify left bottom)
					(hide yes)
				)
			)
			(property "Val" "100 MHz"
				(at 26.035 -9.525 0)
				(effects
					(font
						(size 1.27 1.27)
						(thickness 0.15)
					)
					(justify left bottom)
				)
			)
			(property "Author" "Antmicro"
				(at 26.035 -19.685 0)
				(effects
					(font
						(size 1.27 1.27)
						(thickness 0.15)
					)
					(justify left bottom)
					(hide yes)
				)
			)
			(property "License" "Apache-2.0"
				(at 26.035 -22.225 0)
				(effects
					(font
						(size 1.27 1.27)
						(thickness 0.15)
					)
					(justify left bottom)
					(hide yes)
				)
			)
			(property "ki_keywords" "OSCILLATOR, MEMS"
				(at 0 0 0)
				(effects
					(font
						(size 1.27 1.27)
					)
					(hide yes)
				)
			)
			(symbol "Oscillator_100MHz_AMJMEFB_1_1"
				(rectangle
					(start 2.54 2.54)
					(end 16.51 -7.62)
					(stroke
						(width 0.254)
						(type default)
					)
					(fill
						(type background)
					)
				)
				(polyline
					(pts
						(xy 7.62 -1.27) (xy 8.255 -1.27) (xy 8.255 0) (xy 8.89 0) (xy 8.89 -1.27) (xy 9.525 -1.27) (xy 9.525 0)
						(xy 10.16 0) (xy 10.16 -1.27)
					)
					(stroke
						(width 0.254)
						(type default)
					)
					(fill
						(type background)
					)
				)
				(pin power_in line
					(at 0 0 0)
					(length 2.54)
					(name "VDD"
						(effects
							(font
								(size 1.27 1.27)
							)
						)
					)
					(number "4"
						(effects
							(font
								(size 1.27 1.27)
							)
						)
					)
				)
				(pin input line
					(at 0 -2.54 0)
					(length 2.54)
					(name "EN"
						(effects
							(font
								(size 1.27 1.27)
							)
						)
					)
					(number "1"
						(effects
							(font
								(size 1.27 1.27)
							)
						)
					)
				)
				(pin power_in line
					(at 0 -5.08 0)
					(length 2.54)
					(name "GND"
						(effects
							(font
								(size 1.27 1.27)
							)
						)
					)
					(number "2"
						(effects
							(font
								(size 1.27 1.27)
							)
						)
					)
				)
				(pin output line
					(at 19.05 0 180)
					(length 2.54)
					(name "OUT"
						(effects
							(font
								(size 1.27 1.27)
							)
						)
					)
					(number "3"
						(effects
							(font
								(size 1.27 1.27)
							)
						)
					)
				)
			)
		)
	(symbol "antmicroOscillators:Oscillator_24MHz_ASEMB"
			(exclude_from_sim no)
			(in_bom yes)
			(on_board yes)
			(property "Reference" "Y"
				(at 17.78 -5.08 0)
				(effects
					(font
						(size 1.27 1.27)
						(thickness 0.15)
					)
					(justify left bottom)
				)
			)
			(property "Value" "Oscillator_24MHz_ASEMB"
				(at 17.78 -15.24 0)
				(effects
					(font
						(size 1.27 1.27)
						(thickness 0.15)
					)
					(justify left bottom)
					(hide yes)
				)
			)
			(property "Footprint" "antmicro-footprints:Oscillator_SMD_Abracon_ASEMB_3.2x2.5mm"
				(at 17.78 -17.78 0)
				(effects
					(font
						(size 1.27 1.27)
						(thickness 0.15)
					)
					(justify left bottom)
					(hide yes)
				)
			)
			(property "Datasheet" "https://abracon.com/Oscillators/ASEMB.pdf"
				(at 17.78 -20.32 0)
				(effects
					(font
						(size 1.27 1.27)
						(thickness 0.15)
					)
					(justify left bottom)
					(hide yes)
				)
			)
			(property "Description" "MEMS Oscillator, Clock, Pure Silicon&trade;, 24 MHz, SMD, 3.2mm x 2.5mm, 50 ppm, 3.3 V, ASEMB, LVCMOS"
				(at 17.78 -27.94 0)
				(effects
					(font
						(size 1.27 1.27)
					)
					(justify left bottom)
					(hide yes)
				)
			)
			(property "MPN" "ASEMB-24.000MHZ-LC-T"
				(at 17.78 -7.62 0)
				(effects
					(font
						(size 1.27 1.27)
						(thickness 0.15)
					)
					(justify left bottom)
				)
			)
			(property "Manufacturer" "Abracon"
				(at 17.78 -10.16 0)
				(effects
					(font
						(size 1.27 1.27)
						(thickness 0.15)
					)
					(justify left bottom)
					(hide yes)
				)
			)
			(property "Val" "24 MHz"
				(at 17.78 -12.7 0)
				(effects
					(font
						(size 1.27 1.27)
						(thickness 0.15)
					)
					(justify left bottom)
				)
			)
			(property "Author" "Antmicro"
				(at 17.78 -22.86 0)
				(effects
					(font
						(size 1.27 1.27)
						(thickness 0.15)
					)
					(justify left bottom)
					(hide yes)
				)
			)
			(property "License" "Apache-2.0"
				(at 17.78 -25.4 0)
				(effects
					(font
						(size 1.27 1.27)
						(thickness 0.15)
					)
					(justify left bottom)
					(hide yes)
				)
			)
			(property "ki_keywords" "OSCILLATOR, MEMS"
				(at 0 0 0)
				(effects
					(font
						(size 1.27 1.27)
					)
					(hide yes)
				)
			)
			(symbol "Oscillator_24MHz_ASEMB_1_1"
				(rectangle
					(start 2.54 2.54)
					(end 16.51 -7.62)
					(stroke
						(width 0.254)
						(type default)
					)
					(fill
						(type background)
					)
				)
				(polyline
					(pts
						(xy 7.62 -1.27) (xy 8.255 -1.27) (xy 8.255 0) (xy 8.89 0) (xy 8.89 -1.27) (xy 9.525 -1.27) (xy 9.525 0)
						(xy 10.16 0) (xy 10.16 -1.27)
					)
					(stroke
						(width 0.254)
						(type default)
					)
					(fill
						(type background)
					)
				)
				(pin power_in line
					(at 0 0 0)
					(length 2.54)
					(name "VDD"
						(effects
							(font
								(size 1.27 1.27)
							)
						)
					)
					(number "4"
						(effects
							(font
								(size 1.27 1.27)
							)
						)
					)
				)
				(pin input line
					(at 0 -2.54 0)
					(length 2.54)
					(name "EN"
						(effects
							(font
								(size 1.27 1.27)
							)
						)
					)
					(number "1"
						(effects
							(font
								(size 1.27 1.27)
							)
						)
					)
				)
				(pin power_in line
					(at 0 -5.08 0)
					(length 2.54)
					(name "GND"
						(effects
							(font
								(size 1.27 1.27)
							)
						)
					)
					(number "2"
						(effects
							(font
								(size 1.27 1.27)
							)
						)
					)
				)
				(pin output line
					(at 19.05 0 180)
					(length 2.54)
					(name "OUT"
						(effects
							(font
								(size 1.27 1.27)
							)
						)
					)
					(number "3"
						(effects
							(font
								(size 1.27 1.27)
							)
						)
					)
				)
			)
		)
	(symbol "antmicroPMICPowerSequencers:LM3881"
			(exclude_from_sim no)
			(in_bom yes)
			(on_board yes)
			(property "Reference" "U"
				(at 30.48 -2.54 0)
				(effects
					(font
						(size 1.27 1.27)
						(thickness 0.15)
					)
					(justify left bottom)
				)
			)
			(property "Value" "LM3881"
				(at 30.48 -7.62 0)
				(effects
					(font
						(size 1.27 1.27)
						(thickness 0.15)
					)
					(justify left bottom)
					(hide yes)
				)
			)
			(property "Footprint" "antmicro-footprints:VSSOP-8_3x3mm_P0.65mm"
				(at 30.48 -10.16 0)
				(effects
					(font
						(size 1.27 1.27)
						(thickness 0.15)
					)
					(justify left bottom)
					(hide yes)
				)
			)
			(property "Datasheet" "http://www.ti.com/lit/ds/symlink/lm3881.pdf"
				(at 30.48 -12.7 0)
				(effects
					(font
						(size 1.27 1.27)
						(thickness 0.15)
					)
					(justify left bottom)
					(hide yes)
				)
			)
			(property "Description" "Power Sequencer, 3-Monitors, 2.7V-5.5Vin,VSSOP-8"
				(at 30.48 -22.86 0)
				(effects
					(font
						(size 1.27 1.27)
					)
					(justify left bottom)
					(hide yes)
				)
			)
			(property "Manufacturer" "Texas Instruments"
				(at 30.48 -15.24 0)
				(effects
					(font
						(size 1.27 1.27)
						(thickness 0.15)
					)
					(justify left bottom)
					(hide yes)
				)
			)
			(property "MPN" "LM3881MME/NOPB"
				(at 30.48 -5.08 0)
				(effects
					(font
						(size 1.27 1.27)
						(thickness 0.15)
					)
					(justify left bottom)
				)
			)
			(property "Author" "Antmicro"
				(at 30.48 -17.78 0)
				(effects
					(font
						(size 1.27 1.27)
						(thickness 0.15)
					)
					(justify left bottom)
					(hide yes)
				)
			)
			(property "License" "Apache-2.0"
				(at 30.48 -20.32 0)
				(effects
					(font
						(size 1.27 1.27)
						(thickness 0.15)
					)
					(justify left bottom)
					(hide yes)
				)
			)
			(property "ki_keywords" "SMT, PMIC, IC, POWER, SEQUENCER"
				(at 0 0 0)
				(effects
					(font
						(size 1.27 1.27)
					)
					(hide yes)
				)
			)
			(symbol "LM3881_1_1"
				(rectangle
					(start 2.54 2.54)
					(end 13.97 -10.16)
					(stroke
						(width 0.254)
						(type default)
					)
					(fill
						(type background)
					)
				)
				(pin power_in line
					(at 0 0 0)
					(length 2.54)
					(name "VCC"
						(effects
							(font
								(size 1.27 1.27)
							)
						)
					)
					(number "1"
						(effects
							(font
								(size 1.27 1.27)
							)
						)
					)
				)
				(pin passive line
					(at 0 -2.54 0)
					(length 2.54)
					(name "EN"
						(effects
							(font
								(size 1.27 1.27)
							)
						)
					)
					(number "2"
						(effects
							(font
								(size 1.27 1.27)
							)
						)
					)
				)
				(pin input line
					(at 0 -5.08 0)
					(length 2.54)
					(name "INV"
						(effects
							(font
								(size 1.27 1.27)
							)
						)
					)
					(number "4"
						(effects
							(font
								(size 1.27 1.27)
							)
						)
					)
				)
				(pin passive line
					(at 0 -7.62 0)
					(length 2.54)
					(name "TADJ"
						(effects
							(font
								(size 1.27 1.27)
							)
						)
					)
					(number "5"
						(effects
							(font
								(size 1.27 1.27)
							)
						)
					)
				)
				(pin open_collector line
					(at 16.51 0 180)
					(length 2.54)
					(name "FLAG1"
						(effects
							(font
								(size 1.27 1.27)
							)
						)
					)
					(number "8"
						(effects
							(font
								(size 1.27 1.27)
							)
						)
					)
				)
				(pin open_collector line
					(at 16.51 -2.54 180)
					(length 2.54)
					(name "FLAG2"
						(effects
							(font
								(size 1.27 1.27)
							)
						)
					)
					(number "7"
						(effects
							(font
								(size 1.27 1.27)
							)
						)
					)
				)
				(pin open_collector line
					(at 16.51 -5.08 180)
					(length 2.54)
					(name "FLAG3"
						(effects
							(font
								(size 1.27 1.27)
							)
						)
					)
					(number "6"
						(effects
							(font
								(size 1.27 1.27)
							)
						)
					)
				)
				(pin power_in line
					(at 16.51 -7.62 180)
					(length 2.54)
					(name "GND"
						(effects
							(font
								(size 1.27 1.27)
							)
						)
					)
					(number "3"
						(effects
							(font
								(size 1.27 1.27)
							)
						)
					)
				)
			)
		)
	(symbol "antmicroPMICVoltageRegulatorsDCDCSwitchingControllers:TPS51200DRCT"
			(exclude_from_sim no)
			(in_bom yes)
			(on_board yes)
			(property "Reference" "U"
				(at 35.56 -2.54 0)
				(effects
					(font
						(size 1.27 1.27)
						(thickness 0.15)
					)
					(justify left bottom)
				)
			)
			(property "Value" "TPS51200DRCT"
				(at 35.56 -7.62 0)
				(effects
					(font
						(size 1.27 1.27)
						(thickness 0.15)
					)
					(justify left bottom)
					(hide yes)
				)
			)
			(property "Footprint" "antmicro-footprints:VSON-10-1EP_3x3mm"
				(at 35.56 -10.16 0)
				(effects
					(font
						(size 1.27 1.27)
						(thickness 0.15)
					)
					(justify left bottom)
					(hide yes)
				)
			)
			(property "Datasheet" "https://www.ti.com/lit/ds/symlink/tps51200.pdf?ts=1685420125657"
				(at 35.56 -12.7 0)
				(effects
					(font
						(size 1.27 1.27)
						(thickness 0.15)
					)
					(justify left bottom)
					(hide yes)
				)
			)
			(property "Description" "Fixed LDO Voltage Regulator, 2.375 V to 3.5 V, 0.8 V Dropout, 1.25 V / 3 A out, VSON-10"
				(at 35.56 -25.4 0)
				(effects
					(font
						(size 1.27 1.27)
					)
					(justify left bottom)
					(hide yes)
				)
			)
			(property "MPN" "TPS51200DRCT"
				(at 35.56 -5.08 0)
				(effects
					(font
						(size 1.27 1.27)
						(thickness 0.15)
					)
					(justify left bottom)
				)
			)
			(property "Manufacturer" "Texas Instruments"
				(at 35.56 -15.24 0)
				(effects
					(font
						(size 1.27 1.27)
						(thickness 0.15)
					)
					(justify left bottom)
					(hide yes)
				)
			)
			(property "Author" "Antmicro"
				(at 35.56 -20.32 0)
				(effects
					(font
						(size 1.27 1.27)
						(thickness 0.15)
					)
					(justify left bottom)
					(hide yes)
				)
			)
			(property "License" "Apache-2.0"
				(at 35.56 -22.86 0)
				(effects
					(font
						(size 1.27 1.27)
						(thickness 0.15)
					)
					(justify left bottom)
					(hide yes)
				)
			)
			(property "ki_keywords" "SMT, PMIC, IC"
				(at 0 0 0)
				(effects
					(font
						(size 1.27 1.27)
					)
					(hide yes)
				)
			)
			(property "ki_fp_filters" "*VSON?10?1EP?3x3mm?P0.5mm*"
				(at 0 0 0)
				(effects
					(font
						(size 1.27 1.27)
					)
					(hide yes)
				)
			)
			(symbol "TPS51200DRCT_0_1"
				(rectangle
					(start 2.54 2.54)
					(end 17.78 -13.97)
					(stroke
						(width 0.254)
						(type default)
					)
					(fill
						(type background)
					)
				)
				(pin power_in line
					(at 0 0 0)
					(length 2.54)
					(name "VIN"
						(effects
							(font
								(size 1.27 1.27)
							)
						)
					)
					(number "10"
						(effects
							(font
								(size 1.27 1.27)
							)
						)
					)
				)
				(pin open_collector line
					(at 0 -2.54 0)
					(length 2.54)
					(name "PGOOD"
						(effects
							(font
								(size 1.27 1.27)
							)
						)
					)
					(number "9"
						(effects
							(font
								(size 1.27 1.27)
							)
						)
					)
				)
				(pin input line
					(at 0 -5.08 0)
					(length 2.54)
					(name "EN"
						(effects
							(font
								(size 1.27 1.27)
							)
						)
					)
					(number "7"
						(effects
							(font
								(size 1.27 1.27)
							)
						)
					)
				)
				(pin input line
					(at 0 -8.89 0)
					(length 2.54)
					(name "REFIN"
						(effects
							(font
								(size 1.27 1.27)
							)
						)
					)
					(number "1"
						(effects
							(font
								(size 1.27 1.27)
							)
						)
					)
				)
				(pin power_in line
					(at 0 -11.43 0)
					(length 2.54)
					(name "VLDOIN"
						(effects
							(font
								(size 1.27 1.27)
							)
						)
					)
					(number "2"
						(effects
							(font
								(size 1.27 1.27)
							)
						)
					)
				)
				(pin power_out line
					(at 20.32 0 180)
					(length 2.54)
					(name "VO"
						(effects
							(font
								(size 1.27 1.27)
							)
						)
					)
					(number "3"
						(effects
							(font
								(size 1.27 1.27)
							)
						)
					)
				)
				(pin input line
					(at 20.32 -2.54 180)
					(length 2.54)
					(name "VOSNS"
						(effects
							(font
								(size 1.27 1.27)
							)
						)
					)
					(number "5"
						(effects
							(font
								(size 1.27 1.27)
							)
						)
					)
				)
				(pin power_out line
					(at 20.32 -8.89 180)
					(length 2.54)
					(name "REFOUT"
						(effects
							(font
								(size 1.27 1.27)
							)
						)
					)
					(number "6"
						(effects
							(font
								(size 1.27 1.27)
							)
						)
					)
				)
				(pin passive line
					(at 20.32 -11.43 180)
					(length 2.54)
					(hide yes)
					(name "GND"
						(effects
							(font
								(size 1.27 1.27)
							)
						)
					)
					(number "11"
						(effects
							(font
								(size 1.27 1.27)
							)
						)
					)
				)
				(pin passive line
					(at 20.32 -11.43 180)
					(length 2.54)
					(hide yes)
					(name "GND"
						(effects
							(font
								(size 1.27 1.27)
							)
						)
					)
					(number "4"
						(effects
							(font
								(size 1.27 1.27)
							)
						)
					)
				)
				(pin power_in line
					(at 20.32 -11.43 180)
					(length 2.54)
					(name "GND"
						(effects
							(font
								(size 1.27 1.27)
							)
						)
					)
					(number "8"
						(effects
							(font
								(size 1.27 1.27)
							)
						)
					)
				)
			)
		)
	(symbol "antmicroPMICVoltageRegulatorsLinear:TPS54561QDPRRQ1"
			(exclude_from_sim no)
			(in_bom yes)
			(on_board yes)
			(property "Reference" "U"
				(at 38.1 -2.54 0)
				(effects
					(font
						(size 1.27 1.27)
						(thickness 0.15)
					)
					(justify left bottom)
				)
			)
			(property "Value" "TPS54561QDPRRQ1"
				(at 38.1 -7.62 0)
				(effects
					(font
						(size 1.27 1.27)
						(thickness 0.15)
					)
					(justify left bottom)
					(hide yes)
				)
			)
			(property "Footprint" "antmicro-footprints:WSON-10-1EP_4x4mm_P0.8mm_EP2.6x3mm"
				(at 38.1 -10.16 0)
				(effects
					(font
						(size 1.27 1.27)
						(thickness 0.15)
					)
					(justify left bottom)
					(hide yes)
				)
			)
			(property "Datasheet" "https://www.ti.com/lit/ds/symlink/tps54561-q1.pdf?ts=1678720110394&ref_url=https%253A%252F%252Fwww.google.com%252F"
				(at 38.1 -12.7 0)
				(effects
					(font
						(size 1.27 1.27)
						(thickness 0.15)
					)
					(justify left bottom)
					(hide yes)
				)
			)
			(property "Description" "DC/DC converter"
				(at 38.1 -22.86 0)
				(effects
					(font
						(size 1.27 1.27)
					)
					(justify left bottom)
					(hide yes)
				)
			)
			(property "Manufacturer" "Texas Instruments"
				(at 38.1 -15.24 0)
				(effects
					(font
						(size 1.27 1.27)
						(thickness 0.15)
					)
					(justify left bottom)
					(hide yes)
				)
			)
			(property "MPN" "TPS54561QDPRRQ1"
				(at 38.1 -5.08 0)
				(effects
					(font
						(size 1.27 1.27)
						(thickness 0.15)
					)
					(justify left bottom)
				)
			)
			(property "Author" "Antmicro"
				(at 38.1 -17.78 0)
				(effects
					(font
						(size 1.27 1.27)
						(thickness 0.15)
					)
					(justify left bottom)
					(hide yes)
				)
			)
			(property "License" "Apache-2.0"
				(at 38.1 -20.32 0)
				(effects
					(font
						(size 1.27 1.27)
						(thickness 0.15)
					)
					(justify left bottom)
					(hide yes)
				)
			)
			(property "ki_keywords" "SMT, PMIC, IC, SWITCHING, VOLTAGE, REGULATOR, DC-DC"
				(at 0 0 0)
				(effects
					(font
						(size 1.27 1.27)
					)
					(hide yes)
				)
			)
			(symbol "TPS54561QDPRRQ1_1_1"
				(rectangle
					(start 2.54 2.54)
					(end 22.86 -21.59)
					(stroke
						(width 0.254)
						(type default)
					)
					(fill
						(type background)
					)
				)
				(pin power_in line
					(at 0 0 0)
					(length 2.54)
					(name "V_{DD}"
						(effects
							(font
								(size 1.27 1.27)
							)
						)
					)
					(number "2"
						(effects
							(font
								(size 1.27 1.27)
							)
						)
					)
				)
				(pin input line
					(at 0 -2.54 0)
					(length 2.54)
					(name "EN"
						(effects
							(font
								(size 1.27 1.27)
							)
						)
					)
					(number "3"
						(effects
							(font
								(size 1.27 1.27)
							)
						)
					)
				)
				(pin input line
					(at 0 -7.62 0)
					(length 2.54)
					(name "RT/CLK"
						(effects
							(font
								(size 1.27 1.27)
							)
						)
					)
					(number "5"
						(effects
							(font
								(size 1.27 1.27)
							)
						)
					)
				)
				(pin input line
					(at 0 -10.16 0)
					(length 2.54)
					(name "SS/TR"
						(effects
							(font
								(size 1.27 1.27)
							)
						)
					)
					(number "4"
						(effects
							(font
								(size 1.27 1.27)
							)
						)
					)
				)
				(pin passive line
					(at 0 -19.05 0)
					(length 2.54)
					(hide yes)
					(name "GND"
						(effects
							(font
								(size 1.27 1.27)
							)
						)
					)
					(number "11"
						(effects
							(font
								(size 1.27 1.27)
							)
						)
					)
				)
				(pin power_in line
					(at 0 -19.05 0)
					(length 2.54)
					(name "GND"
						(effects
							(font
								(size 1.27 1.27)
							)
						)
					)
					(number "8"
						(effects
							(font
								(size 1.27 1.27)
							)
						)
					)
				)
				(pin output line
					(at 25.4 0 180)
					(length 2.54)
					(name "PWRGD"
						(effects
							(font
								(size 1.27 1.27)
							)
						)
					)
					(number "10"
						(effects
							(font
								(size 1.27 1.27)
							)
						)
					)
				)
				(pin output line
					(at 25.4 -2.54 180)
					(length 2.54)
					(name "BOOT"
						(effects
							(font
								(size 1.27 1.27)
							)
						)
					)
					(number "1"
						(effects
							(font
								(size 1.27 1.27)
							)
						)
					)
				)
				(pin power_out line
					(at 25.4 -7.62 180)
					(length 2.54)
					(name "SW"
						(effects
							(font
								(size 1.27 1.27)
							)
						)
					)
					(number "9"
						(effects
							(font
								(size 1.27 1.27)
							)
						)
					)
				)
				(pin input line
					(at 25.4 -13.97 180)
					(length 2.54)
					(name "FB"
						(effects
							(font
								(size 1.27 1.27)
							)
						)
					)
					(number "6"
						(effects
							(font
								(size 1.27 1.27)
							)
						)
					)
				)
				(pin output line
					(at 25.4 -19.05 180)
					(length 2.54)
					(name "COMP"
						(effects
							(font
								(size 1.27 1.27)
							)
						)
					)
					(number "7"
						(effects
							(font
								(size 1.27 1.27)
							)
						)
					)
				)
			)
		)
	(symbol "antmicroPciConnectors:Bus_M.2_1-2199230-6"
			(exclude_from_sim no)
			(in_bom yes)
			(on_board yes)
			(property "Reference" "J"
				(at 45.72 -2.54 0)
				(effects
					(font
						(size 1.27 1.27)
						(thickness 0.15)
					)
					(justify left bottom)
				)
			)
			(property "Value" "Bus_M.2_1-2199230-6"
				(at 45.72 -7.62 0)
				(effects
					(font
						(size 1.27 1.27)
						(thickness 0.15)
					)
					(justify left bottom)
					(hide yes)
				)
			)
			(property "Footprint" "antmicro-footprints:Bus_M.2_Socket_Key_M_TE_1-2199230-6"
				(at 45.72 -10.16 0)
				(effects
					(font
						(size 1.27 1.27)
						(thickness 0.15)
					)
					(justify left bottom)
					(hide yes)
				)
			)
			(property "Datasheet" "https://www.te.com/commerce/DocumentDelivery/DDEController?Action=srchrtrv&DocNm=2199230&DocType=Customer+Drawing&DocLang=English"
				(at 45.72 -12.7 0)
				(effects
					(font
						(size 1.27 1.27)
						(thickness 0.15)
					)
					(justify left bottom)
					(hide yes)
				)
			)
			(property "Description" "Key M Card Edge Connector, 0, Dual Side, 67 Contacts, Surface Mount, Right Angle, Solder"
				(at 45.72 -22.86 0)
				(effects
					(font
						(size 1.27 1.27)
					)
					(justify left bottom)
					(hide yes)
				)
			)
			(property "Manufacturer" "TE Connectivity"
				(at 45.72 -15.24 0)
				(effects
					(font
						(size 1.27 1.27)
						(thickness 0.15)
					)
					(justify left bottom)
					(hide yes)
				)
			)
			(property "MPN" "1-2199230-6"
				(at 45.72 -5.08 0)
				(effects
					(font
						(size 1.27 1.27)
						(thickness 0.15)
					)
					(justify left bottom)
				)
			)
			(property "Author" "Antmicro"
				(at 45.72 -17.78 0)
				(effects
					(font
						(size 1.27 1.27)
						(thickness 0.15)
					)
					(justify left bottom)
					(hide yes)
				)
			)
			(property "License" "Apache-2.0"
				(at 45.72 -20.32 0)
				(effects
					(font
						(size 1.27 1.27)
						(thickness 0.15)
					)
					(justify left bottom)
					(hide yes)
				)
			)
			(property "ki_keywords" "HORIZONTAL, SMT, PCIE, CONNECTOR"
				(at 0 0 0)
				(effects
					(font
						(size 1.27 1.27)
					)
					(hide yes)
				)
			)
			(symbol "Bus_M.2_1-2199230-6_0_0"
				(text "KEY M"
					(at 15.24 0 0)
					(effects
						(font
							(size 1.27 1.27)
							(bold yes)
						)
					)
				)
			)
			(symbol "Bus_M.2_1-2199230-6_1_1"
				(rectangle
					(start 3.81 2.54)
					(end 26.67 -80.01)
					(stroke
						(width 0.254)
						(type default)
					)
					(fill
						(type background)
					)
				)
				(pin input line
					(at 0 0 0)
					(length 3.81)
					(name "~{PERST}"
						(effects
							(font
								(size 1.27 1.27)
							)
						)
					)
					(number "50"
						(effects
							(font
								(size 1.27 1.27)
							)
						)
					)
				)
				(pin output line
					(at 0 -2.54 0)
					(length 3.81)
					(name "~{CLKREQ}"
						(effects
							(font
								(size 1.27 1.27)
							)
						)
					)
					(number "52"
						(effects
							(font
								(size 1.27 1.27)
							)
						)
					)
				)
				(pin input line
					(at 0 -5.08 0)
					(length 3.81)
					(name "~{PEWAKE}"
						(effects
							(font
								(size 1.27 1.27)
							)
						)
					)
					(number "54"
						(effects
							(font
								(size 1.27 1.27)
							)
						)
					)
				)
				(pin input line
					(at 0 -12.7 0)
					(length 3.81)
					(name "REFCLK_P"
						(effects
							(font
								(size 1.27 1.27)
							)
						)
					)
					(number "55"
						(effects
							(font
								(size 1.27 1.27)
							)
						)
					)
				)
				(pin input line
					(at 0 -15.24 0)
					(length 3.81)
					(name "REFCLK_N"
						(effects
							(font
								(size 1.27 1.27)
							)
						)
					)
					(number "53"
						(effects
							(font
								(size 1.27 1.27)
							)
						)
					)
				)
				(pin input line
					(at 0 -21.59 0)
					(length 3.81)
					(name "PET0_P"
						(effects
							(font
								(size 1.27 1.27)
							)
						)
					)
					(number "49"
						(effects
							(font
								(size 1.27 1.27)
							)
						)
					)
				)
				(pin input line
					(at 0 -24.13 0)
					(length 3.81)
					(name "PET0_N"
						(effects
							(font
								(size 1.27 1.27)
							)
						)
					)
					(number "47"
						(effects
							(font
								(size 1.27 1.27)
							)
						)
					)
				)
				(pin output line
					(at 0 -29.21 0)
					(length 3.81)
					(name "PER0_P"
						(effects
							(font
								(size 1.27 1.27)
							)
						)
					)
					(number "43"
						(effects
							(font
								(size 1.27 1.27)
							)
						)
					)
				)
				(pin output line
					(at 0 -31.75 0)
					(length 3.81)
					(name "PER0_N"
						(effects
							(font
								(size 1.27 1.27)
							)
						)
					)
					(number "41"
						(effects
							(font
								(size 1.27 1.27)
							)
						)
					)
				)
				(pin input line
					(at 0 -36.83 0)
					(length 3.81)
					(name "PET1_P"
						(effects
							(font
								(size 1.27 1.27)
							)
						)
					)
					(number "37"
						(effects
							(font
								(size 1.27 1.27)
							)
						)
					)
				)
				(pin input line
					(at 0 -39.37 0)
					(length 3.81)
					(name "PET1_N"
						(effects
							(font
								(size 1.27 1.27)
							)
						)
					)
					(number "35"
						(effects
							(font
								(size 1.27 1.27)
							)
						)
					)
				)
				(pin output line
					(at 0 -44.45 0)
					(length 3.81)
					(name "PER1_P"
						(effects
							(font
								(size 1.27 1.27)
							)
						)
					)
					(number "31"
						(effects
							(font
								(size 1.27 1.27)
							)
						)
					)
				)
				(pin output line
					(at 0 -46.99 0)
					(length 3.81)
					(name "PER1_N"
						(effects
							(font
								(size 1.27 1.27)
							)
						)
					)
					(number "29"
						(effects
							(font
								(size 1.27 1.27)
							)
						)
					)
				)
				(pin input line
					(at 0 -52.07 0)
					(length 3.81)
					(name "PET2_P"
						(effects
							(font
								(size 1.27 1.27)
							)
						)
					)
					(number "25"
						(effects
							(font
								(size 1.27 1.27)
							)
						)
					)
				)
				(pin input line
					(at 0 -54.61 0)
					(length 3.81)
					(name "PET2_N"
						(effects
							(font
								(size 1.27 1.27)
							)
						)
					)
					(number "23"
						(effects
							(font
								(size 1.27 1.27)
							)
						)
					)
				)
				(pin output line
					(at 0 -59.69 0)
					(length 3.81)
					(name "PER2_P"
						(effects
							(font
								(size 1.27 1.27)
							)
						)
					)
					(number "19"
						(effects
							(font
								(size 1.27 1.27)
							)
						)
					)
				)
				(pin output line
					(at 0 -62.23 0)
					(length 3.81)
					(name "PER2_N"
						(effects
							(font
								(size 1.27 1.27)
							)
						)
					)
					(number "17"
						(effects
							(font
								(size 1.27 1.27)
							)
						)
					)
				)
				(pin input line
					(at 0 -67.31 0)
					(length 3.81)
					(name "PET3_P"
						(effects
							(font
								(size 1.27 1.27)
							)
						)
					)
					(number "13"
						(effects
							(font
								(size 1.27 1.27)
							)
						)
					)
				)
				(pin input line
					(at 0 -69.85 0)
					(length 3.81)
					(name "PET3_N"
						(effects
							(font
								(size 1.27 1.27)
							)
						)
					)
					(number "11"
						(effects
							(font
								(size 1.27 1.27)
							)
						)
					)
				)
				(pin output line
					(at 0 -74.93 0)
					(length 3.81)
					(name "PER3_P"
						(effects
							(font
								(size 1.27 1.27)
							)
						)
					)
					(number "7"
						(effects
							(font
								(size 1.27 1.27)
							)
						)
					)
				)
				(pin output line
					(at 0 -77.47 0)
					(length 3.81)
					(name "PER3_N"
						(effects
							(font
								(size 1.27 1.27)
							)
						)
					)
					(number "5"
						(effects
							(font
								(size 1.27 1.27)
							)
						)
					)
				)
				(pin no_connect line
					(at 26.67 -38.1 180)
					(length 3.81)
					(hide yes)
					(name "NC"
						(effects
							(font
								(size 1.27 1.27)
							)
						)
					)
					(number "69"
						(effects
							(font
								(size 1.27 1.27)
							)
						)
					)
				)
				(pin no_connect line
					(at 26.67 -39.37 180)
					(length 3.81)
					(hide yes)
					(name "NC"
						(effects
							(font
								(size 1.27 1.27)
							)
						)
					)
					(number "6"
						(effects
							(font
								(size 1.27 1.27)
							)
						)
					)
				)
				(pin no_connect line
					(at 26.67 -40.64 180)
					(length 3.81)
					(hide yes)
					(name "NC"
						(effects
							(font
								(size 1.27 1.27)
							)
						)
					)
					(number "67"
						(effects
							(font
								(size 1.27 1.27)
							)
						)
					)
				)
				(pin no_connect line
					(at 26.67 -41.91 180)
					(length 3.81)
					(hide yes)
					(name "NC"
						(effects
							(font
								(size 1.27 1.27)
							)
						)
					)
					(number "48"
						(effects
							(font
								(size 1.27 1.27)
							)
						)
					)
				)
				(pin no_connect line
					(at 26.67 -43.18 180)
					(length 3.81)
					(hide yes)
					(name "NC"
						(effects
							(font
								(size 1.27 1.27)
							)
						)
					)
					(number "56"
						(effects
							(font
								(size 1.27 1.27)
							)
						)
					)
				)
				(pin no_connect line
					(at 26.67 -44.45 180)
					(length 3.81)
					(hide yes)
					(name "NC"
						(effects
							(font
								(size 1.27 1.27)
							)
						)
					)
					(number "20"
						(effects
							(font
								(size 1.27 1.27)
							)
						)
					)
				)
				(pin no_connect line
					(at 26.67 -45.72 180)
					(length 3.81)
					(hide yes)
					(name "NC"
						(effects
							(font
								(size 1.27 1.27)
							)
						)
					)
					(number "22"
						(effects
							(font
								(size 1.27 1.27)
							)
						)
					)
				)
				(pin no_connect line
					(at 26.67 -46.99 180)
					(length 3.81)
					(hide yes)
					(name "NC"
						(effects
							(font
								(size 1.27 1.27)
							)
						)
					)
					(number "24"
						(effects
							(font
								(size 1.27 1.27)
							)
						)
					)
				)
				(pin no_connect line
					(at 26.67 -59.69 180)
					(length 3.81)
					(hide yes)
					(name "NC"
						(effects
							(font
								(size 1.27 1.27)
							)
						)
					)
					(number "26"
						(effects
							(font
								(size 1.27 1.27)
							)
						)
					)
				)
				(pin no_connect line
					(at 26.67 -60.96 180)
					(length 3.81)
					(hide yes)
					(name "NC"
						(effects
							(font
								(size 1.27 1.27)
							)
						)
					)
					(number "28"
						(effects
							(font
								(size 1.27 1.27)
							)
						)
					)
				)
				(pin no_connect line
					(at 26.67 -62.23 180)
					(length 3.81)
					(hide yes)
					(name "NC"
						(effects
							(font
								(size 1.27 1.27)
							)
						)
					)
					(number "30"
						(effects
							(font
								(size 1.27 1.27)
							)
						)
					)
				)
				(pin no_connect line
					(at 26.67 -63.5 180)
					(length 3.81)
					(hide yes)
					(name "NC"
						(effects
							(font
								(size 1.27 1.27)
							)
						)
					)
					(number "32"
						(effects
							(font
								(size 1.27 1.27)
							)
						)
					)
				)
				(pin no_connect line
					(at 26.67 -64.77 180)
					(length 3.81)
					(hide yes)
					(name "NC"
						(effects
							(font
								(size 1.27 1.27)
							)
						)
					)
					(number "8"
						(effects
							(font
								(size 1.27 1.27)
							)
						)
					)
				)
				(pin no_connect line
					(at 26.67 -66.04 180)
					(length 3.81)
					(hide yes)
					(name "NC"
						(effects
							(font
								(size 1.27 1.27)
							)
						)
					)
					(number "34"
						(effects
							(font
								(size 1.27 1.27)
							)
						)
					)
				)
				(pin no_connect line
					(at 26.67 -67.31 180)
					(length 3.81)
					(hide yes)
					(name "NC"
						(effects
							(font
								(size 1.27 1.27)
							)
						)
					)
					(number "36"
						(effects
							(font
								(size 1.27 1.27)
							)
						)
					)
				)
				(pin no_connect line
					(at 26.67 -68.58 180)
					(length 3.81)
					(hide yes)
					(name "NC"
						(effects
							(font
								(size 1.27 1.27)
							)
						)
					)
					(number "46"
						(effects
							(font
								(size 1.27 1.27)
							)
						)
					)
				)
				(pin no_connect line
					(at 26.67 -69.85 180)
					(length 3.81)
					(hide yes)
					(name "NC"
						(effects
							(font
								(size 1.27 1.27)
							)
						)
					)
					(number "38"
						(effects
							(font
								(size 1.27 1.27)
							)
						)
					)
				)
				(pin no_connect line
					(at 26.67 -71.12 180)
					(length 3.81)
					(hide yes)
					(name "NC"
						(effects
							(font
								(size 1.27 1.27)
							)
						)
					)
					(number "58"
						(effects
							(font
								(size 1.27 1.27)
							)
						)
					)
				)
				(pin passive line
					(at 30.48 0 180)
					(length 3.81)
					(name "3V3"
						(effects
							(font
								(size 1.27 1.27)
							)
						)
					)
					(number "12"
						(effects
							(font
								(size 1.27 1.27)
							)
						)
					)
				)
				(pin passive line
					(at 30.48 0 180)
					(length 3.81)
					(hide yes)
					(name "3V3"
						(effects
							(font
								(size 1.27 1.27)
							)
						)
					)
					(number "14"
						(effects
							(font
								(size 1.27 1.27)
							)
						)
					)
				)
				(pin passive line
					(at 30.48 0 180)
					(length 3.81)
					(hide yes)
					(name "3V3"
						(effects
							(font
								(size 1.27 1.27)
							)
						)
					)
					(number "16"
						(effects
							(font
								(size 1.27 1.27)
							)
						)
					)
				)
				(pin passive line
					(at 30.48 0 180)
					(length 3.81)
					(hide yes)
					(name "3V3"
						(effects
							(font
								(size 1.27 1.27)
							)
						)
					)
					(number "18"
						(effects
							(font
								(size 1.27 1.27)
							)
						)
					)
				)
				(pin passive line
					(at 30.48 0 180)
					(length 3.81)
					(hide yes)
					(name "3V3"
						(effects
							(font
								(size 1.27 1.27)
							)
						)
					)
					(number "2"
						(effects
							(font
								(size 1.27 1.27)
							)
						)
					)
				)
				(pin passive line
					(at 30.48 0 180)
					(length 3.81)
					(hide yes)
					(name "3V3"
						(effects
							(font
								(size 1.27 1.27)
							)
						)
					)
					(number "4"
						(effects
							(font
								(size 1.27 1.27)
							)
						)
					)
				)
				(pin passive line
					(at 30.48 0 180)
					(length 3.81)
					(hide yes)
					(name "3V3"
						(effects
							(font
								(size 1.27 1.27)
							)
						)
					)
					(number "70"
						(effects
							(font
								(size 1.27 1.27)
							)
						)
					)
				)
				(pin passive line
					(at 30.48 0 180)
					(length 3.81)
					(hide yes)
					(name "3V3"
						(effects
							(font
								(size 1.27 1.27)
							)
						)
					)
					(number "72"
						(effects
							(font
								(size 1.27 1.27)
							)
						)
					)
				)
				(pin passive line
					(at 30.48 0 180)
					(length 3.81)
					(hide yes)
					(name "3V3"
						(effects
							(font
								(size 1.27 1.27)
							)
						)
					)
					(number "74"
						(effects
							(font
								(size 1.27 1.27)
							)
						)
					)
				)
				(pin input line
					(at 30.48 -12.7 180)
					(length 3.81)
					(name "SUSCLK"
						(effects
							(font
								(size 1.27 1.27)
							)
						)
					)
					(number "68"
						(effects
							(font
								(size 1.27 1.27)
							)
						)
					)
				)
				(pin output line
					(at 30.48 -26.67 180)
					(length 3.81)
					(name "ALERT"
						(effects
							(font
								(size 1.27 1.27)
							)
						)
					)
					(number "44"
						(effects
							(font
								(size 1.27 1.27)
							)
						)
					)
				)
				(pin bidirectional line
					(at 30.48 -29.21 180)
					(length 3.81)
					(name "SMB_DATA"
						(effects
							(font
								(size 1.27 1.27)
							)
						)
					)
					(number "42"
						(effects
							(font
								(size 1.27 1.27)
							)
						)
					)
				)
				(pin input line
					(at 30.48 -31.75 180)
					(length 3.81)
					(name "SMB_CLK"
						(effects
							(font
								(size 1.27 1.27)
							)
						)
					)
					(number "40"
						(effects
							(font
								(size 1.27 1.27)
							)
						)
					)
				)
				(pin passive line
					(at 30.48 -54.61 180)
					(length 3.81)
					(name "LED"
						(effects
							(font
								(size 1.27 1.27)
							)
						)
					)
					(number "10"
						(effects
							(font
								(size 1.27 1.27)
							)
						)
					)
				)
				(pin passive line
					(at 30.48 -74.93 180)
					(length 3.81)
					(name "MP"
						(effects
							(font
								(size 1.27 1.27)
							)
						)
					)
					(number "MP1"
						(effects
							(font
								(size 1.27 1.27)
							)
						)
					)
				)
				(pin passive line
					(at 30.48 -74.93 180)
					(length 3.81)
					(hide yes)
					(name "MP"
						(effects
							(font
								(size 1.27 1.27)
							)
						)
					)
					(number "MP2"
						(effects
							(font
								(size 1.27 1.27)
							)
						)
					)
				)
				(pin power_in line
					(at 30.48 -77.47 180)
					(length 3.81)
					(name "GND"
						(effects
							(font
								(size 1.27 1.27)
							)
						)
					)
					(number "1"
						(effects
							(font
								(size 1.27 1.27)
							)
						)
					)
				)
				(pin passive line
					(at 30.48 -77.47 180)
					(length 3.81)
					(hide yes)
					(name "GND"
						(effects
							(font
								(size 1.27 1.27)
							)
						)
					)
					(number "15"
						(effects
							(font
								(size 1.27 1.27)
							)
						)
					)
				)
				(pin passive line
					(at 30.48 -77.47 180)
					(length 3.81)
					(hide yes)
					(name "GND"
						(effects
							(font
								(size 1.27 1.27)
							)
						)
					)
					(number "21"
						(effects
							(font
								(size 1.27 1.27)
							)
						)
					)
				)
				(pin passive line
					(at 30.48 -77.47 180)
					(length 3.81)
					(hide yes)
					(name "GND"
						(effects
							(font
								(size 1.27 1.27)
							)
						)
					)
					(number "27"
						(effects
							(font
								(size 1.27 1.27)
							)
						)
					)
				)
				(pin passive line
					(at 30.48 -77.47 180)
					(length 3.81)
					(hide yes)
					(name "GND"
						(effects
							(font
								(size 1.27 1.27)
							)
						)
					)
					(number "3"
						(effects
							(font
								(size 1.27 1.27)
							)
						)
					)
				)
				(pin passive line
					(at 30.48 -77.47 180)
					(length 3.81)
					(hide yes)
					(name "GND"
						(effects
							(font
								(size 1.27 1.27)
							)
						)
					)
					(number "33"
						(effects
							(font
								(size 1.27 1.27)
							)
						)
					)
				)
				(pin passive line
					(at 30.48 -77.47 180)
					(length 3.81)
					(hide yes)
					(name "GND"
						(effects
							(font
								(size 1.27 1.27)
							)
						)
					)
					(number "39"
						(effects
							(font
								(size 1.27 1.27)
							)
						)
					)
				)
				(pin passive line
					(at 30.48 -77.47 180)
					(length 3.81)
					(hide yes)
					(name "GND"
						(effects
							(font
								(size 1.27 1.27)
							)
						)
					)
					(number "45"
						(effects
							(font
								(size 1.27 1.27)
							)
						)
					)
				)
				(pin passive line
					(at 30.48 -77.47 180)
					(length 3.81)
					(hide yes)
					(name "GND"
						(effects
							(font
								(size 1.27 1.27)
							)
						)
					)
					(number "51"
						(effects
							(font
								(size 1.27 1.27)
							)
						)
					)
				)
				(pin passive line
					(at 30.48 -77.47 180)
					(length 3.81)
					(hide yes)
					(name "GND"
						(effects
							(font
								(size 1.27 1.27)
							)
						)
					)
					(number "57"
						(effects
							(font
								(size 1.27 1.27)
							)
						)
					)
				)
				(pin passive line
					(at 30.48 -77.47 180)
					(length 3.81)
					(hide yes)
					(name "GND"
						(effects
							(font
								(size 1.27 1.27)
							)
						)
					)
					(number "71"
						(effects
							(font
								(size 1.27 1.27)
							)
						)
					)
				)
				(pin passive line
					(at 30.48 -77.47 180)
					(length 3.81)
					(hide yes)
					(name "GND"
						(effects
							(font
								(size 1.27 1.27)
							)
						)
					)
					(number "73"
						(effects
							(font
								(size 1.27 1.27)
							)
						)
					)
				)
				(pin passive line
					(at 30.48 -77.47 180)
					(length 3.81)
					(hide yes)
					(name "GND"
						(effects
							(font
								(size 1.27 1.27)
							)
						)
					)
					(number "75"
						(effects
							(font
								(size 1.27 1.27)
							)
						)
					)
				)
				(pin passive line
					(at 30.48 -77.47 180)
					(length 3.81)
					(hide yes)
					(name "GND"
						(effects
							(font
								(size 1.27 1.27)
							)
						)
					)
					(number "9"
						(effects
							(font
								(size 1.27 1.27)
							)
						)
					)
				)
			)
		)
	(symbol "antmicroPciConnectors:SFF-TA-1002-4C+"
			(pin_names
				(offset 1.016)
			)
			(exclude_from_sim no)
			(in_bom no)
			(on_board yes)
			(property "Reference" "J"
				(at 46.99 0 0)
				(effects
					(font
						(size 1.27 1.27)
						(thickness 0.15)
					)
					(justify left bottom)
				)
			)
			(property "Value" "SFF-TA-1002-4C+"
				(at 46.99 -2.54 0)
				(effects
					(font
						(size 1.27 1.27)
						(thickness 0.15)
					)
					(justify left bottom)
					(hide yes)
				)
			)
			(property "Footprint" "antmicro-footprints:SFF-TA-1002-4C+"
				(at 46.99 -5.08 0)
				(effects
					(font
						(size 1.27 1.27)
						(thickness 0.15)
					)
					(justify left bottom)
					(hide yes)
				)
			)
			(property "Datasheet" "https://cdn.amphenol-icc.com/media/wysiwyg/files/documentation/sme005.pdf?__cf_chl_jschl_tk__=4604d1306574a1ee474ea914090d3e0c57e266a6-1606907014-0-AbkYBTCTl__kMBcY3BDmgKpfUy32FqitwN2Lniuy8W-uyv2Ev04Q-Q5Mr7srIz_Wnur0_9chB4CRbxKSYcEh7IvAJYsUgJ0PWIS5YdRqqHg567uaZciEX2hQP4ss5l6M4XdNrxEjJppHvyRV3ku89t-VmUSzhgCb8oJlyHpTxST4dEmKZNXfM53TM0tmGirdVbCRt1Byrx5pkz_uMvNABIOj7B2-eDGK52J3DWRD76zEyjdxY7Iz11gPiOY5i_QGIR3uOwkR5LBPNXe8zGqAf8--AKa7RqDbIriQRt90_32C4zIuHqbGa05BXS135E65ov80PbVcb4eSiutCqcJUAacUwu3eVnXVeIumfihJxuP8Rv7_n6saeG_2IuQpEiskzovLGKZM3667Y-rm-AL1NRXTamtvBxqTk0vyMvZ60FgJ"
				(at 46.99 -7.62 0)
				(effects
					(font
						(size 1.27 1.27)
						(thickness 0.15)
					)
					(justify left bottom)
					(hide yes)
				)
			)
			(property "Description" "PCB EDGE PCI connector"
				(at 46.99 -20.32 0)
				(effects
					(font
						(size 1.27 1.27)
					)
					(justify left bottom)
					(hide yes)
				)
			)
			(property "MPN" ""
				(at 46.99 -10.16 0)
				(effects
					(font
						(size 1.27 1.27)
						(thickness 0.15)
					)
					(justify left bottom)
				)
			)
			(property "Manufacturer" ""
				(at 46.99 -12.7 0)
				(effects
					(font
						(size 1.27 1.27)
						(thickness 0.15)
					)
					(justify left bottom)
					(hide yes)
				)
			)
			(property "Author" "Antmicro"
				(at 46.99 -15.24 0)
				(effects
					(font
						(size 1.27 1.27)
						(thickness 0.15)
					)
					(justify left bottom)
					(hide yes)
				)
			)
			(property "License" "Apache-2.0"
				(at 46.99 -17.78 0)
				(effects
					(font
						(size 1.27 1.27)
						(thickness 0.15)
					)
					(justify left bottom)
					(hide yes)
				)
			)
			(property "ki_keywords" "PCIE, CONNECTOR, EDGE"
				(at 0 0 0)
				(effects
					(font
						(size 1.27 1.27)
					)
					(hide yes)
				)
			)
			(symbol "SFF-TA-1002-4C+_0_0"
				(rectangle
					(start 5.08 2.54)
					(end 20.32 -228.6)
					(stroke
						(width 0)
						(type default)
					)
					(fill
						(type background)
					)
				)
				(text "KEY"
					(at 11.43 -38.1 0)
					(effects
						(font
							(size 1.27 1.27)
							(thickness 0.15)
						)
						(justify left bottom)
					)
				)
				(text "KEY"
					(at 11.43 -114.3 0)
					(effects
						(font
							(size 1.27 1.27)
							(thickness 0.15)
						)
						(justify left bottom)
					)
				)
				(text "KEY"
					(at 11.43 -154.94 0)
					(effects
						(font
							(size 1.27 1.27)
							(thickness 0.15)
						)
						(justify left bottom)
					)
				)
			)
			(symbol "SFF-TA-1002-4C+_1_1"
				(rectangle
					(start 5.08 -35.56)
					(end 20.32 -38.1)
					(stroke
						(width 0)
						(type default)
					)
					(fill
						(type background)
					)
				)
				(rectangle
					(start 5.08 -111.76)
					(end 20.32 -114.3)
					(stroke
						(width 0)
						(type default)
					)
					(fill
						(type background)
					)
				)
				(rectangle
					(start 5.08 -152.4)
					(end 20.32 -154.94)
					(stroke
						(width 0)
						(type default)
					)
					(fill
						(type background)
					)
				)
				(pin passive line
					(at 0 0 0)
					(length 5.08)
					(name "OA1"
						(effects
							(font
								(size 1.27 1.27)
							)
						)
					)
					(number "OA1"
						(effects
							(font
								(size 1.27 1.27)
							)
						)
					)
				)
				(pin passive line
					(at 0 -2.54 0)
					(length 5.08)
					(name "OA2"
						(effects
							(font
								(size 1.27 1.27)
							)
						)
					)
					(number "OA2"
						(effects
							(font
								(size 1.27 1.27)
							)
						)
					)
				)
				(pin passive line
					(at 0 -5.08 0)
					(length 5.08)
					(name "OA3"
						(effects
							(font
								(size 1.27 1.27)
							)
						)
					)
					(number "OA3"
						(effects
							(font
								(size 1.27 1.27)
							)
						)
					)
				)
				(pin passive line
					(at 0 -7.62 0)
					(length 5.08)
					(name "OA4"
						(effects
							(font
								(size 1.27 1.27)
							)
						)
					)
					(number "OA4"
						(effects
							(font
								(size 1.27 1.27)
							)
						)
					)
				)
				(pin passive line
					(at 0 -10.16 0)
					(length 5.08)
					(name "OA5"
						(effects
							(font
								(size 1.27 1.27)
							)
						)
					)
					(number "OA5"
						(effects
							(font
								(size 1.27 1.27)
							)
						)
					)
				)
				(pin passive line
					(at 0 -12.7 0)
					(length 5.08)
					(name "OA6"
						(effects
							(font
								(size 1.27 1.27)
							)
						)
					)
					(number "OA6"
						(effects
							(font
								(size 1.27 1.27)
							)
						)
					)
				)
				(pin passive line
					(at 0 -15.24 0)
					(length 5.08)
					(name "OA7"
						(effects
							(font
								(size 1.27 1.27)
							)
						)
					)
					(number "OA7"
						(effects
							(font
								(size 1.27 1.27)
							)
						)
					)
				)
				(pin passive line
					(at 0 -17.78 0)
					(length 5.08)
					(name "OA8"
						(effects
							(font
								(size 1.27 1.27)
							)
						)
					)
					(number "OA8"
						(effects
							(font
								(size 1.27 1.27)
							)
						)
					)
				)
				(pin passive line
					(at 0 -20.32 0)
					(length 5.08)
					(name "OA9"
						(effects
							(font
								(size 1.27 1.27)
							)
						)
					)
					(number "OA9"
						(effects
							(font
								(size 1.27 1.27)
							)
						)
					)
				)
				(pin passive line
					(at 0 -22.86 0)
					(length 5.08)
					(name "OA10"
						(effects
							(font
								(size 1.27 1.27)
							)
						)
					)
					(number "OA10"
						(effects
							(font
								(size 1.27 1.27)
							)
						)
					)
				)
				(pin passive line
					(at 0 -25.4 0)
					(length 5.08)
					(name "OA11"
						(effects
							(font
								(size 1.27 1.27)
							)
						)
					)
					(number "OA11"
						(effects
							(font
								(size 1.27 1.27)
							)
						)
					)
				)
				(pin passive line
					(at 0 -27.94 0)
					(length 5.08)
					(name "OA12"
						(effects
							(font
								(size 1.27 1.27)
							)
						)
					)
					(number "OA12"
						(effects
							(font
								(size 1.27 1.27)
							)
						)
					)
				)
				(pin passive line
					(at 0 -30.48 0)
					(length 5.08)
					(name "OA13"
						(effects
							(font
								(size 1.27 1.27)
							)
						)
					)
					(number "OA13"
						(effects
							(font
								(size 1.27 1.27)
							)
						)
					)
				)
				(pin passive line
					(at 0 -33.02 0)
					(length 5.08)
					(name "OA14"
						(effects
							(font
								(size 1.27 1.27)
							)
						)
					)
					(number "OA14"
						(effects
							(font
								(size 1.27 1.27)
							)
						)
					)
				)
				(pin passive line
					(at 0 -40.64 0)
					(length 5.08)
					(name "A1"
						(effects
							(font
								(size 1.27 1.27)
							)
						)
					)
					(number "A1"
						(effects
							(font
								(size 1.27 1.27)
							)
						)
					)
				)
				(pin passive line
					(at 0 -43.18 0)
					(length 5.08)
					(name "A2"
						(effects
							(font
								(size 1.27 1.27)
							)
						)
					)
					(number "A2"
						(effects
							(font
								(size 1.27 1.27)
							)
						)
					)
				)
				(pin passive line
					(at 0 -45.72 0)
					(length 5.08)
					(name "A3"
						(effects
							(font
								(size 1.27 1.27)
							)
						)
					)
					(number "A3"
						(effects
							(font
								(size 1.27 1.27)
							)
						)
					)
				)
				(pin passive line
					(at 0 -48.26 0)
					(length 5.08)
					(name "A4"
						(effects
							(font
								(size 1.27 1.27)
							)
						)
					)
					(number "A4"
						(effects
							(font
								(size 1.27 1.27)
							)
						)
					)
				)
				(pin passive line
					(at 0 -50.8 0)
					(length 5.08)
					(name "A5"
						(effects
							(font
								(size 1.27 1.27)
							)
						)
					)
					(number "A5"
						(effects
							(font
								(size 1.27 1.27)
							)
						)
					)
				)
				(pin passive line
					(at 0 -53.34 0)
					(length 5.08)
					(name "A6"
						(effects
							(font
								(size 1.27 1.27)
							)
						)
					)
					(number "A6"
						(effects
							(font
								(size 1.27 1.27)
							)
						)
					)
				)
				(pin passive line
					(at 0 -55.88 0)
					(length 5.08)
					(name "A7"
						(effects
							(font
								(size 1.27 1.27)
							)
						)
					)
					(number "A7"
						(effects
							(font
								(size 1.27 1.27)
							)
						)
					)
				)
				(pin passive line
					(at 0 -58.42 0)
					(length 5.08)
					(name "A8"
						(effects
							(font
								(size 1.27 1.27)
							)
						)
					)
					(number "A8"
						(effects
							(font
								(size 1.27 1.27)
							)
						)
					)
				)
				(pin passive line
					(at 0 -60.96 0)
					(length 5.08)
					(name "A9"
						(effects
							(font
								(size 1.27 1.27)
							)
						)
					)
					(number "A9"
						(effects
							(font
								(size 1.27 1.27)
							)
						)
					)
				)
				(pin passive line
					(at 0 -63.5 0)
					(length 5.08)
					(name "A10"
						(effects
							(font
								(size 1.27 1.27)
							)
						)
					)
					(number "A10"
						(effects
							(font
								(size 1.27 1.27)
							)
						)
					)
				)
				(pin passive line
					(at 0 -66.04 0)
					(length 5.08)
					(name "A11"
						(effects
							(font
								(size 1.27 1.27)
							)
						)
					)
					(number "A11"
						(effects
							(font
								(size 1.27 1.27)
							)
						)
					)
				)
				(pin passive line
					(at 0 -68.58 0)
					(length 5.08)
					(name "A12"
						(effects
							(font
								(size 1.27 1.27)
							)
						)
					)
					(number "A12"
						(effects
							(font
								(size 1.27 1.27)
							)
						)
					)
				)
				(pin passive line
					(at 0 -71.12 0)
					(length 5.08)
					(name "A13"
						(effects
							(font
								(size 1.27 1.27)
							)
						)
					)
					(number "A13"
						(effects
							(font
								(size 1.27 1.27)
							)
						)
					)
				)
				(pin passive line
					(at 0 -73.66 0)
					(length 5.08)
					(name "A14"
						(effects
							(font
								(size 1.27 1.27)
							)
						)
					)
					(number "A14"
						(effects
							(font
								(size 1.27 1.27)
							)
						)
					)
				)
				(pin passive line
					(at 0 -76.2 0)
					(length 5.08)
					(name "A15"
						(effects
							(font
								(size 1.27 1.27)
							)
						)
					)
					(number "A15"
						(effects
							(font
								(size 1.27 1.27)
							)
						)
					)
				)
				(pin passive line
					(at 0 -78.74 0)
					(length 5.08)
					(name "A16"
						(effects
							(font
								(size 1.27 1.27)
							)
						)
					)
					(number "A16"
						(effects
							(font
								(size 1.27 1.27)
							)
						)
					)
				)
				(pin passive line
					(at 0 -81.28 0)
					(length 5.08)
					(name "A17"
						(effects
							(font
								(size 1.27 1.27)
							)
						)
					)
					(number "A17"
						(effects
							(font
								(size 1.27 1.27)
							)
						)
					)
				)
				(pin passive line
					(at 0 -83.82 0)
					(length 5.08)
					(name "A18"
						(effects
							(font
								(size 1.27 1.27)
							)
						)
					)
					(number "A18"
						(effects
							(font
								(size 1.27 1.27)
							)
						)
					)
				)
				(pin passive line
					(at 0 -86.36 0)
					(length 5.08)
					(name "A19"
						(effects
							(font
								(size 1.27 1.27)
							)
						)
					)
					(number "A19"
						(effects
							(font
								(size 1.27 1.27)
							)
						)
					)
				)
				(pin passive line
					(at 0 -88.9 0)
					(length 5.08)
					(name "A20"
						(effects
							(font
								(size 1.27 1.27)
							)
						)
					)
					(number "A20"
						(effects
							(font
								(size 1.27 1.27)
							)
						)
					)
				)
				(pin passive line
					(at 0 -91.44 0)
					(length 5.08)
					(name "A21"
						(effects
							(font
								(size 1.27 1.27)
							)
						)
					)
					(number "A21"
						(effects
							(font
								(size 1.27 1.27)
							)
						)
					)
				)
				(pin passive line
					(at 0 -93.98 0)
					(length 5.08)
					(name "A22"
						(effects
							(font
								(size 1.27 1.27)
							)
						)
					)
					(number "A22"
						(effects
							(font
								(size 1.27 1.27)
							)
						)
					)
				)
				(pin passive line
					(at 0 -96.52 0)
					(length 5.08)
					(name "A23"
						(effects
							(font
								(size 1.27 1.27)
							)
						)
					)
					(number "A23"
						(effects
							(font
								(size 1.27 1.27)
							)
						)
					)
				)
				(pin passive line
					(at 0 -99.06 0)
					(length 5.08)
					(name "A24"
						(effects
							(font
								(size 1.27 1.27)
							)
						)
					)
					(number "A24"
						(effects
							(font
								(size 1.27 1.27)
							)
						)
					)
				)
				(pin passive line
					(at 0 -101.6 0)
					(length 5.08)
					(name "A25"
						(effects
							(font
								(size 1.27 1.27)
							)
						)
					)
					(number "A25"
						(effects
							(font
								(size 1.27 1.27)
							)
						)
					)
				)
				(pin passive line
					(at 0 -104.14 0)
					(length 5.08)
					(name "A26"
						(effects
							(font
								(size 1.27 1.27)
							)
						)
					)
					(number "A26"
						(effects
							(font
								(size 1.27 1.27)
							)
						)
					)
				)
				(pin passive line
					(at 0 -106.68 0)
					(length 5.08)
					(name "A27"
						(effects
							(font
								(size 1.27 1.27)
							)
						)
					)
					(number "A27"
						(effects
							(font
								(size 1.27 1.27)
							)
						)
					)
				)
				(pin passive line
					(at 0 -109.22 0)
					(length 5.08)
					(name "A28"
						(effects
							(font
								(size 1.27 1.27)
							)
						)
					)
					(number "A28"
						(effects
							(font
								(size 1.27 1.27)
							)
						)
					)
				)
				(pin passive line
					(at 0 -116.84 0)
					(length 5.08)
					(name "A29"
						(effects
							(font
								(size 1.27 1.27)
							)
						)
					)
					(number "A29"
						(effects
							(font
								(size 1.27 1.27)
							)
						)
					)
				)
				(pin passive line
					(at 0 -119.38 0)
					(length 5.08)
					(name "A30"
						(effects
							(font
								(size 1.27 1.27)
							)
						)
					)
					(number "A30"
						(effects
							(font
								(size 1.27 1.27)
							)
						)
					)
				)
				(pin passive line
					(at 0 -121.92 0)
					(length 5.08)
					(name "A31"
						(effects
							(font
								(size 1.27 1.27)
							)
						)
					)
					(number "A31"
						(effects
							(font
								(size 1.27 1.27)
							)
						)
					)
				)
				(pin passive line
					(at 0 -124.46 0)
					(length 5.08)
					(name "A32"
						(effects
							(font
								(size 1.27 1.27)
							)
						)
					)
					(number "A32"
						(effects
							(font
								(size 1.27 1.27)
							)
						)
					)
				)
				(pin passive line
					(at 0 -127 0)
					(length 5.08)
					(name "A33"
						(effects
							(font
								(size 1.27 1.27)
							)
						)
					)
					(number "A33"
						(effects
							(font
								(size 1.27 1.27)
							)
						)
					)
				)
				(pin passive line
					(at 0 -129.54 0)
					(length 5.08)
					(name "A34"
						(effects
							(font
								(size 1.27 1.27)
							)
						)
					)
					(number "A34"
						(effects
							(font
								(size 1.27 1.27)
							)
						)
					)
				)
				(pin passive line
					(at 0 -132.08 0)
					(length 5.08)
					(name "A35"
						(effects
							(font
								(size 1.27 1.27)
							)
						)
					)
					(number "A35"
						(effects
							(font
								(size 1.27 1.27)
							)
						)
					)
				)
				(pin passive line
					(at 0 -134.62 0)
					(length 5.08)
					(name "A36"
						(effects
							(font
								(size 1.27 1.27)
							)
						)
					)
					(number "A36"
						(effects
							(font
								(size 1.27 1.27)
							)
						)
					)
				)
				(pin passive line
					(at 0 -137.16 0)
					(length 5.08)
					(name "A37"
						(effects
							(font
								(size 1.27 1.27)
							)
						)
					)
					(number "A37"
						(effects
							(font
								(size 1.27 1.27)
							)
						)
					)
				)
				(pin passive line
					(at 0 -139.7 0)
					(length 5.08)
					(name "A38"
						(effects
							(font
								(size 1.27 1.27)
							)
						)
					)
					(number "A38"
						(effects
							(font
								(size 1.27 1.27)
							)
						)
					)
				)
				(pin passive line
					(at 0 -142.24 0)
					(length 5.08)
					(name "A39"
						(effects
							(font
								(size 1.27 1.27)
							)
						)
					)
					(number "A39"
						(effects
							(font
								(size 1.27 1.27)
							)
						)
					)
				)
				(pin passive line
					(at 0 -144.78 0)
					(length 5.08)
					(name "A40"
						(effects
							(font
								(size 1.27 1.27)
							)
						)
					)
					(number "A40"
						(effects
							(font
								(size 1.27 1.27)
							)
						)
					)
				)
				(pin passive line
					(at 0 -147.32 0)
					(length 5.08)
					(name "A41"
						(effects
							(font
								(size 1.27 1.27)
							)
						)
					)
					(number "A41"
						(effects
							(font
								(size 1.27 1.27)
							)
						)
					)
				)
				(pin passive line
					(at 0 -149.86 0)
					(length 5.08)
					(name "A42"
						(effects
							(font
								(size 1.27 1.27)
							)
						)
					)
					(number "A42"
						(effects
							(font
								(size 1.27 1.27)
							)
						)
					)
				)
				(pin passive line
					(at 0 -157.48 0)
					(length 5.08)
					(name "A43"
						(effects
							(font
								(size 1.27 1.27)
							)
						)
					)
					(number "A43"
						(effects
							(font
								(size 1.27 1.27)
							)
						)
					)
				)
				(pin passive line
					(at 0 -160.02 0)
					(length 5.08)
					(name "A44"
						(effects
							(font
								(size 1.27 1.27)
							)
						)
					)
					(number "A44"
						(effects
							(font
								(size 1.27 1.27)
							)
						)
					)
				)
				(pin passive line
					(at 0 -162.56 0)
					(length 5.08)
					(name "A45"
						(effects
							(font
								(size 1.27 1.27)
							)
						)
					)
					(number "A45"
						(effects
							(font
								(size 1.27 1.27)
							)
						)
					)
				)
				(pin passive line
					(at 0 -165.1 0)
					(length 5.08)
					(name "A46"
						(effects
							(font
								(size 1.27 1.27)
							)
						)
					)
					(number "A46"
						(effects
							(font
								(size 1.27 1.27)
							)
						)
					)
				)
				(pin passive line
					(at 0 -167.64 0)
					(length 5.08)
					(name "A47"
						(effects
							(font
								(size 1.27 1.27)
							)
						)
					)
					(number "A47"
						(effects
							(font
								(size 1.27 1.27)
							)
						)
					)
				)
				(pin passive line
					(at 0 -170.18 0)
					(length 5.08)
					(name "A48"
						(effects
							(font
								(size 1.27 1.27)
							)
						)
					)
					(number "A48"
						(effects
							(font
								(size 1.27 1.27)
							)
						)
					)
				)
				(pin passive line
					(at 0 -172.72 0)
					(length 5.08)
					(name "A49"
						(effects
							(font
								(size 1.27 1.27)
							)
						)
					)
					(number "A49"
						(effects
							(font
								(size 1.27 1.27)
							)
						)
					)
				)
				(pin passive line
					(at 0 -175.26 0)
					(length 5.08)
					(name "A50"
						(effects
							(font
								(size 1.27 1.27)
							)
						)
					)
					(number "A50"
						(effects
							(font
								(size 1.27 1.27)
							)
						)
					)
				)
				(pin passive line
					(at 0 -177.8 0)
					(length 5.08)
					(name "A51"
						(effects
							(font
								(size 1.27 1.27)
							)
						)
					)
					(number "A51"
						(effects
							(font
								(size 1.27 1.27)
							)
						)
					)
				)
				(pin passive line
					(at 0 -180.34 0)
					(length 5.08)
					(name "A52"
						(effects
							(font
								(size 1.27 1.27)
							)
						)
					)
					(number "A52"
						(effects
							(font
								(size 1.27 1.27)
							)
						)
					)
				)
				(pin passive line
					(at 0 -182.88 0)
					(length 5.08)
					(name "A53"
						(effects
							(font
								(size 1.27 1.27)
							)
						)
					)
					(number "A53"
						(effects
							(font
								(size 1.27 1.27)
							)
						)
					)
				)
				(pin passive line
					(at 0 -185.42 0)
					(length 5.08)
					(name "A54"
						(effects
							(font
								(size 1.27 1.27)
							)
						)
					)
					(number "A54"
						(effects
							(font
								(size 1.27 1.27)
							)
						)
					)
				)
				(pin passive line
					(at 0 -187.96 0)
					(length 5.08)
					(name "A55"
						(effects
							(font
								(size 1.27 1.27)
							)
						)
					)
					(number "A55"
						(effects
							(font
								(size 1.27 1.27)
							)
						)
					)
				)
				(pin passive line
					(at 0 -190.5 0)
					(length 5.08)
					(name "A56"
						(effects
							(font
								(size 1.27 1.27)
							)
						)
					)
					(number "A56"
						(effects
							(font
								(size 1.27 1.27)
							)
						)
					)
				)
				(pin passive line
					(at 0 -193.04 0)
					(length 5.08)
					(name "A57"
						(effects
							(font
								(size 1.27 1.27)
							)
						)
					)
					(number "A57"
						(effects
							(font
								(size 1.27 1.27)
							)
						)
					)
				)
				(pin passive line
					(at 0 -195.58 0)
					(length 5.08)
					(name "A58"
						(effects
							(font
								(size 1.27 1.27)
							)
						)
					)
					(number "A58"
						(effects
							(font
								(size 1.27 1.27)
							)
						)
					)
				)
				(pin passive line
					(at 0 -198.12 0)
					(length 5.08)
					(name "A59"
						(effects
							(font
								(size 1.27 1.27)
							)
						)
					)
					(number "A59"
						(effects
							(font
								(size 1.27 1.27)
							)
						)
					)
				)
				(pin passive line
					(at 0 -200.66 0)
					(length 5.08)
					(name "A60"
						(effects
							(font
								(size 1.27 1.27)
							)
						)
					)
					(number "A60"
						(effects
							(font
								(size 1.27 1.27)
							)
						)
					)
				)
				(pin passive line
					(at 0 -203.2 0)
					(length 5.08)
					(name "A61"
						(effects
							(font
								(size 1.27 1.27)
							)
						)
					)
					(number "A61"
						(effects
							(font
								(size 1.27 1.27)
							)
						)
					)
				)
				(pin passive line
					(at 0 -205.74 0)
					(length 5.08)
					(name "A62"
						(effects
							(font
								(size 1.27 1.27)
							)
						)
					)
					(number "A62"
						(effects
							(font
								(size 1.27 1.27)
							)
						)
					)
				)
				(pin passive line
					(at 0 -208.28 0)
					(length 5.08)
					(name "A63"
						(effects
							(font
								(size 1.27 1.27)
							)
						)
					)
					(number "A63"
						(effects
							(font
								(size 1.27 1.27)
							)
						)
					)
				)
				(pin passive line
					(at 0 -210.82 0)
					(length 5.08)
					(name "A64"
						(effects
							(font
								(size 1.27 1.27)
							)
						)
					)
					(number "A64"
						(effects
							(font
								(size 1.27 1.27)
							)
						)
					)
				)
				(pin passive line
					(at 0 -213.36 0)
					(length 5.08)
					(name "A65"
						(effects
							(font
								(size 1.27 1.27)
							)
						)
					)
					(number "A65"
						(effects
							(font
								(size 1.27 1.27)
							)
						)
					)
				)
				(pin passive line
					(at 0 -215.9 0)
					(length 5.08)
					(name "A66"
						(effects
							(font
								(size 1.27 1.27)
							)
						)
					)
					(number "A66"
						(effects
							(font
								(size 1.27 1.27)
							)
						)
					)
				)
				(pin passive line
					(at 0 -218.44 0)
					(length 5.08)
					(name "A67"
						(effects
							(font
								(size 1.27 1.27)
							)
						)
					)
					(number "A67"
						(effects
							(font
								(size 1.27 1.27)
							)
						)
					)
				)
				(pin passive line
					(at 0 -220.98 0)
					(length 5.08)
					(name "A68"
						(effects
							(font
								(size 1.27 1.27)
							)
						)
					)
					(number "A68"
						(effects
							(font
								(size 1.27 1.27)
							)
						)
					)
				)
				(pin passive line
					(at 0 -223.52 0)
					(length 5.08)
					(name "A69"
						(effects
							(font
								(size 1.27 1.27)
							)
						)
					)
					(number "A69"
						(effects
							(font
								(size 1.27 1.27)
							)
						)
					)
				)
				(pin passive line
					(at 0 -226.06 0)
					(length 5.08)
					(name "A70"
						(effects
							(font
								(size 1.27 1.27)
							)
						)
					)
					(number "A70"
						(effects
							(font
								(size 1.27 1.27)
							)
						)
					)
				)
				(pin passive line
					(at 25.4 0 180)
					(length 5.08)
					(name "OB1"
						(effects
							(font
								(size 1.27 1.27)
							)
						)
					)
					(number "OB1"
						(effects
							(font
								(size 1.27 1.27)
							)
						)
					)
				)
				(pin passive line
					(at 25.4 -2.54 180)
					(length 5.08)
					(name "OB2"
						(effects
							(font
								(size 1.27 1.27)
							)
						)
					)
					(number "OB2"
						(effects
							(font
								(size 1.27 1.27)
							)
						)
					)
				)
				(pin passive line
					(at 25.4 -5.08 180)
					(length 5.08)
					(name "OB3"
						(effects
							(font
								(size 1.27 1.27)
							)
						)
					)
					(number "OB3"
						(effects
							(font
								(size 1.27 1.27)
							)
						)
					)
				)
				(pin passive line
					(at 25.4 -7.62 180)
					(length 5.08)
					(name "OB4"
						(effects
							(font
								(size 1.27 1.27)
							)
						)
					)
					(number "OB4"
						(effects
							(font
								(size 1.27 1.27)
							)
						)
					)
				)
				(pin passive line
					(at 25.4 -10.16 180)
					(length 5.08)
					(name "OB5"
						(effects
							(font
								(size 1.27 1.27)
							)
						)
					)
					(number "OB5"
						(effects
							(font
								(size 1.27 1.27)
							)
						)
					)
				)
				(pin passive line
					(at 25.4 -12.7 180)
					(length 5.08)
					(name "OB6"
						(effects
							(font
								(size 1.27 1.27)
							)
						)
					)
					(number "OB6"
						(effects
							(font
								(size 1.27 1.27)
							)
						)
					)
				)
				(pin passive line
					(at 25.4 -15.24 180)
					(length 5.08)
					(name "OB7"
						(effects
							(font
								(size 1.27 1.27)
							)
						)
					)
					(number "OB7"
						(effects
							(font
								(size 1.27 1.27)
							)
						)
					)
				)
				(pin passive line
					(at 25.4 -17.78 180)
					(length 5.08)
					(name "OB8"
						(effects
							(font
								(size 1.27 1.27)
							)
						)
					)
					(number "OB8"
						(effects
							(font
								(size 1.27 1.27)
							)
						)
					)
				)
				(pin passive line
					(at 25.4 -20.32 180)
					(length 5.08)
					(name "OB9"
						(effects
							(font
								(size 1.27 1.27)
							)
						)
					)
					(number "OB9"
						(effects
							(font
								(size 1.27 1.27)
							)
						)
					)
				)
				(pin passive line
					(at 25.4 -22.86 180)
					(length 5.08)
					(name "OB10"
						(effects
							(font
								(size 1.27 1.27)
							)
						)
					)
					(number "OB10"
						(effects
							(font
								(size 1.27 1.27)
							)
						)
					)
				)
				(pin passive line
					(at 25.4 -25.4 180)
					(length 5.08)
					(name "OB11"
						(effects
							(font
								(size 1.27 1.27)
							)
						)
					)
					(number "OB11"
						(effects
							(font
								(size 1.27 1.27)
							)
						)
					)
				)
				(pin passive line
					(at 25.4 -27.94 180)
					(length 5.08)
					(name "OB12"
						(effects
							(font
								(size 1.27 1.27)
							)
						)
					)
					(number "OB12"
						(effects
							(font
								(size 1.27 1.27)
							)
						)
					)
				)
				(pin passive line
					(at 25.4 -30.48 180)
					(length 5.08)
					(name "OB13"
						(effects
							(font
								(size 1.27 1.27)
							)
						)
					)
					(number "OB13"
						(effects
							(font
								(size 1.27 1.27)
							)
						)
					)
				)
				(pin passive line
					(at 25.4 -33.02 180)
					(length 5.08)
					(name "OB14"
						(effects
							(font
								(size 1.27 1.27)
							)
						)
					)
					(number "OB14"
						(effects
							(font
								(size 1.27 1.27)
							)
						)
					)
				)
				(pin passive line
					(at 25.4 -40.64 180)
					(length 5.08)
					(name "B1"
						(effects
							(font
								(size 1.27 1.27)
							)
						)
					)
					(number "B1"
						(effects
							(font
								(size 1.27 1.27)
							)
						)
					)
				)
				(pin passive line
					(at 25.4 -43.18 180)
					(length 5.08)
					(name "B2"
						(effects
							(font
								(size 1.27 1.27)
							)
						)
					)
					(number "B2"
						(effects
							(font
								(size 1.27 1.27)
							)
						)
					)
				)
				(pin passive line
					(at 25.4 -45.72 180)
					(length 5.08)
					(name "B3"
						(effects
							(font
								(size 1.27 1.27)
							)
						)
					)
					(number "B3"
						(effects
							(font
								(size 1.27 1.27)
							)
						)
					)
				)
				(pin passive line
					(at 25.4 -48.26 180)
					(length 5.08)
					(name "B4"
						(effects
							(font
								(size 1.27 1.27)
							)
						)
					)
					(number "B4"
						(effects
							(font
								(size 1.27 1.27)
							)
						)
					)
				)
				(pin passive line
					(at 25.4 -50.8 180)
					(length 5.08)
					(name "B5"
						(effects
							(font
								(size 1.27 1.27)
							)
						)
					)
					(number "B5"
						(effects
							(font
								(size 1.27 1.27)
							)
						)
					)
				)
				(pin passive line
					(at 25.4 -53.34 180)
					(length 5.08)
					(name "B6"
						(effects
							(font
								(size 1.27 1.27)
							)
						)
					)
					(number "B6"
						(effects
							(font
								(size 1.27 1.27)
							)
						)
					)
				)
				(pin passive line
					(at 25.4 -55.88 180)
					(length 5.08)
					(name "B7"
						(effects
							(font
								(size 1.27 1.27)
							)
						)
					)
					(number "B7"
						(effects
							(font
								(size 1.27 1.27)
							)
						)
					)
				)
				(pin passive line
					(at 25.4 -58.42 180)
					(length 5.08)
					(name "B8"
						(effects
							(font
								(size 1.27 1.27)
							)
						)
					)
					(number "B8"
						(effects
							(font
								(size 1.27 1.27)
							)
						)
					)
				)
				(pin passive line
					(at 25.4 -60.96 180)
					(length 5.08)
					(name "B9"
						(effects
							(font
								(size 1.27 1.27)
							)
						)
					)
					(number "B9"
						(effects
							(font
								(size 1.27 1.27)
							)
						)
					)
				)
				(pin passive line
					(at 25.4 -63.5 180)
					(length 5.08)
					(name "B10"
						(effects
							(font
								(size 1.27 1.27)
							)
						)
					)
					(number "B10"
						(effects
							(font
								(size 1.27 1.27)
							)
						)
					)
				)
				(pin passive line
					(at 25.4 -66.04 180)
					(length 5.08)
					(name "B11"
						(effects
							(font
								(size 1.27 1.27)
							)
						)
					)
					(number "B11"
						(effects
							(font
								(size 1.27 1.27)
							)
						)
					)
				)
				(pin passive line
					(at 25.4 -68.58 180)
					(length 5.08)
					(name "B12"
						(effects
							(font
								(size 1.27 1.27)
							)
						)
					)
					(number "B12"
						(effects
							(font
								(size 1.27 1.27)
							)
						)
					)
				)
				(pin passive line
					(at 25.4 -71.12 180)
					(length 5.08)
					(name "B13"
						(effects
							(font
								(size 1.27 1.27)
							)
						)
					)
					(number "B13"
						(effects
							(font
								(size 1.27 1.27)
							)
						)
					)
				)
				(pin passive line
					(at 25.4 -73.66 180)
					(length 5.08)
					(name "B14"
						(effects
							(font
								(size 1.27 1.27)
							)
						)
					)
					(number "B14"
						(effects
							(font
								(size 1.27 1.27)
							)
						)
					)
				)
				(pin passive line
					(at 25.4 -76.2 180)
					(length 5.08)
					(name "B15"
						(effects
							(font
								(size 1.27 1.27)
							)
						)
					)
					(number "B15"
						(effects
							(font
								(size 1.27 1.27)
							)
						)
					)
				)
				(pin passive line
					(at 25.4 -78.74 180)
					(length 5.08)
					(name "B16"
						(effects
							(font
								(size 1.27 1.27)
							)
						)
					)
					(number "B16"
						(effects
							(font
								(size 1.27 1.27)
							)
						)
					)
				)
				(pin passive line
					(at 25.4 -81.28 180)
					(length 5.08)
					(name "B17"
						(effects
							(font
								(size 1.27 1.27)
							)
						)
					)
					(number "B17"
						(effects
							(font
								(size 1.27 1.27)
							)
						)
					)
				)
				(pin passive line
					(at 25.4 -83.82 180)
					(length 5.08)
					(name "B18"
						(effects
							(font
								(size 1.27 1.27)
							)
						)
					)
					(number "B18"
						(effects
							(font
								(size 1.27 1.27)
							)
						)
					)
				)
				(pin passive line
					(at 25.4 -86.36 180)
					(length 5.08)
					(name "B19"
						(effects
							(font
								(size 1.27 1.27)
							)
						)
					)
					(number "B19"
						(effects
							(font
								(size 1.27 1.27)
							)
						)
					)
				)
				(pin passive line
					(at 25.4 -88.9 180)
					(length 5.08)
					(name "B20"
						(effects
							(font
								(size 1.27 1.27)
							)
						)
					)
					(number "B20"
						(effects
							(font
								(size 1.27 1.27)
							)
						)
					)
				)
				(pin passive line
					(at 25.4 -91.44 180)
					(length 5.08)
					(name "B21"
						(effects
							(font
								(size 1.27 1.27)
							)
						)
					)
					(number "B21"
						(effects
							(font
								(size 1.27 1.27)
							)
						)
					)
				)
				(pin passive line
					(at 25.4 -93.98 180)
					(length 5.08)
					(name "B22"
						(effects
							(font
								(size 1.27 1.27)
							)
						)
					)
					(number "B22"
						(effects
							(font
								(size 1.27 1.27)
							)
						)
					)
				)
				(pin passive line
					(at 25.4 -96.52 180)
					(length 5.08)
					(name "B23"
						(effects
							(font
								(size 1.27 1.27)
							)
						)
					)
					(number "B23"
						(effects
							(font
								(size 1.27 1.27)
							)
						)
					)
				)
				(pin passive line
					(at 25.4 -99.06 180)
					(length 5.08)
					(name "B24"
						(effects
							(font
								(size 1.27 1.27)
							)
						)
					)
					(number "B24"
						(effects
							(font
								(size 1.27 1.27)
							)
						)
					)
				)
				(pin passive line
					(at 25.4 -101.6 180)
					(length 5.08)
					(name "B25"
						(effects
							(font
								(size 1.27 1.27)
							)
						)
					)
					(number "B25"
						(effects
							(font
								(size 1.27 1.27)
							)
						)
					)
				)
				(pin passive line
					(at 25.4 -104.14 180)
					(length 5.08)
					(name "B26"
						(effects
							(font
								(size 1.27 1.27)
							)
						)
					)
					(number "B26"
						(effects
							(font
								(size 1.27 1.27)
							)
						)
					)
				)
				(pin passive line
					(at 25.4 -106.68 180)
					(length 5.08)
					(name "B27"
						(effects
							(font
								(size 1.27 1.27)
							)
						)
					)
					(number "B27"
						(effects
							(font
								(size 1.27 1.27)
							)
						)
					)
				)
				(pin passive line
					(at 25.4 -109.22 180)
					(length 5.08)
					(name "B28"
						(effects
							(font
								(size 1.27 1.27)
							)
						)
					)
					(number "B28"
						(effects
							(font
								(size 1.27 1.27)
							)
						)
					)
				)
				(pin passive line
					(at 25.4 -116.84 180)
					(length 5.08)
					(name "B29"
						(effects
							(font
								(size 1.27 1.27)
							)
						)
					)
					(number "B29"
						(effects
							(font
								(size 1.27 1.27)
							)
						)
					)
				)
				(pin passive line
					(at 25.4 -119.38 180)
					(length 5.08)
					(name "B30"
						(effects
							(font
								(size 1.27 1.27)
							)
						)
					)
					(number "B30"
						(effects
							(font
								(size 1.27 1.27)
							)
						)
					)
				)
				(pin passive line
					(at 25.4 -121.92 180)
					(length 5.08)
					(name "B31"
						(effects
							(font
								(size 1.27 1.27)
							)
						)
					)
					(number "B31"
						(effects
							(font
								(size 1.27 1.27)
							)
						)
					)
				)
				(pin passive line
					(at 25.4 -124.46 180)
					(length 5.08)
					(name "B32"
						(effects
							(font
								(size 1.27 1.27)
							)
						)
					)
					(number "B32"
						(effects
							(font
								(size 1.27 1.27)
							)
						)
					)
				)
				(pin passive line
					(at 25.4 -127 180)
					(length 5.08)
					(name "B33"
						(effects
							(font
								(size 1.27 1.27)
							)
						)
					)
					(number "B33"
						(effects
							(font
								(size 1.27 1.27)
							)
						)
					)
				)
				(pin passive line
					(at 25.4 -129.54 180)
					(length 5.08)
					(name "B34"
						(effects
							(font
								(size 1.27 1.27)
							)
						)
					)
					(number "B34"
						(effects
							(font
								(size 1.27 1.27)
							)
						)
					)
				)
				(pin passive line
					(at 25.4 -132.08 180)
					(length 5.08)
					(name "B35"
						(effects
							(font
								(size 1.27 1.27)
							)
						)
					)
					(number "B35"
						(effects
							(font
								(size 1.27 1.27)
							)
						)
					)
				)
				(pin passive line
					(at 25.4 -134.62 180)
					(length 5.08)
					(name "B36"
						(effects
							(font
								(size 1.27 1.27)
							)
						)
					)
					(number "B36"
						(effects
							(font
								(size 1.27 1.27)
							)
						)
					)
				)
				(pin passive line
					(at 25.4 -137.16 180)
					(length 5.08)
					(name "B37"
						(effects
							(font
								(size 1.27 1.27)
							)
						)
					)
					(number "B37"
						(effects
							(font
								(size 1.27 1.27)
							)
						)
					)
				)
				(pin passive line
					(at 25.4 -139.7 180)
					(length 5.08)
					(name "B38"
						(effects
							(font
								(size 1.27 1.27)
							)
						)
					)
					(number "B38"
						(effects
							(font
								(size 1.27 1.27)
							)
						)
					)
				)
				(pin passive line
					(at 25.4 -142.24 180)
					(length 5.08)
					(name "B39"
						(effects
							(font
								(size 1.27 1.27)
							)
						)
					)
					(number "B39"
						(effects
							(font
								(size 1.27 1.27)
							)
						)
					)
				)
				(pin passive line
					(at 25.4 -144.78 180)
					(length 5.08)
					(name "B40"
						(effects
							(font
								(size 1.27 1.27)
							)
						)
					)
					(number "B40"
						(effects
							(font
								(size 1.27 1.27)
							)
						)
					)
				)
				(pin passive line
					(at 25.4 -147.32 180)
					(length 5.08)
					(name "B41"
						(effects
							(font
								(size 1.27 1.27)
							)
						)
					)
					(number "B41"
						(effects
							(font
								(size 1.27 1.27)
							)
						)
					)
				)
				(pin passive line
					(at 25.4 -149.86 180)
					(length 5.08)
					(name "B42"
						(effects
							(font
								(size 1.27 1.27)
							)
						)
					)
					(number "B42"
						(effects
							(font
								(size 1.27 1.27)
							)
						)
					)
				)
				(pin passive line
					(at 25.4 -157.48 180)
					(length 5.08)
					(name "B43"
						(effects
							(font
								(size 1.27 1.27)
							)
						)
					)
					(number "B43"
						(effects
							(font
								(size 1.27 1.27)
							)
						)
					)
				)
				(pin passive line
					(at 25.4 -160.02 180)
					(length 5.08)
					(name "B44"
						(effects
							(font
								(size 1.27 1.27)
							)
						)
					)
					(number "B44"
						(effects
							(font
								(size 1.27 1.27)
							)
						)
					)
				)
				(pin passive line
					(at 25.4 -162.56 180)
					(length 5.08)
					(name "B45"
						(effects
							(font
								(size 1.27 1.27)
							)
						)
					)
					(number "B45"
						(effects
							(font
								(size 1.27 1.27)
							)
						)
					)
				)
				(pin passive line
					(at 25.4 -165.1 180)
					(length 5.08)
					(name "B46"
						(effects
							(font
								(size 1.27 1.27)
							)
						)
					)
					(number "B46"
						(effects
							(font
								(size 1.27 1.27)
							)
						)
					)
				)
				(pin passive line
					(at 25.4 -167.64 180)
					(length 5.08)
					(name "B47"
						(effects
							(font
								(size 1.27 1.27)
							)
						)
					)
					(number "B47"
						(effects
							(font
								(size 1.27 1.27)
							)
						)
					)
				)
				(pin passive line
					(at 25.4 -170.18 180)
					(length 5.08)
					(name "B48"
						(effects
							(font
								(size 1.27 1.27)
							)
						)
					)
					(number "B48"
						(effects
							(font
								(size 1.27 1.27)
							)
						)
					)
				)
				(pin passive line
					(at 25.4 -172.72 180)
					(length 5.08)
					(name "B49"
						(effects
							(font
								(size 1.27 1.27)
							)
						)
					)
					(number "B49"
						(effects
							(font
								(size 1.27 1.27)
							)
						)
					)
				)
				(pin passive line
					(at 25.4 -175.26 180)
					(length 5.08)
					(name "B50"
						(effects
							(font
								(size 1.27 1.27)
							)
						)
					)
					(number "B50"
						(effects
							(font
								(size 1.27 1.27)
							)
						)
					)
				)
				(pin passive line
					(at 25.4 -177.8 180)
					(length 5.08)
					(name "B51"
						(effects
							(font
								(size 1.27 1.27)
							)
						)
					)
					(number "B51"
						(effects
							(font
								(size 1.27 1.27)
							)
						)
					)
				)
				(pin passive line
					(at 25.4 -180.34 180)
					(length 5.08)
					(name "B52"
						(effects
							(font
								(size 1.27 1.27)
							)
						)
					)
					(number "B52"
						(effects
							(font
								(size 1.27 1.27)
							)
						)
					)
				)
				(pin passive line
					(at 25.4 -182.88 180)
					(length 5.08)
					(name "B53"
						(effects
							(font
								(size 1.27 1.27)
							)
						)
					)
					(number "B53"
						(effects
							(font
								(size 1.27 1.27)
							)
						)
					)
				)
				(pin passive line
					(at 25.4 -185.42 180)
					(length 5.08)
					(name "B54"
						(effects
							(font
								(size 1.27 1.27)
							)
						)
					)
					(number "B54"
						(effects
							(font
								(size 1.27 1.27)
							)
						)
					)
				)
				(pin passive line
					(at 25.4 -187.96 180)
					(length 5.08)
					(name "B55"
						(effects
							(font
								(size 1.27 1.27)
							)
						)
					)
					(number "B55"
						(effects
							(font
								(size 1.27 1.27)
							)
						)
					)
				)
				(pin passive line
					(at 25.4 -190.5 180)
					(length 5.08)
					(name "B56"
						(effects
							(font
								(size 1.27 1.27)
							)
						)
					)
					(number "B56"
						(effects
							(font
								(size 1.27 1.27)
							)
						)
					)
				)
				(pin passive line
					(at 25.4 -193.04 180)
					(length 5.08)
					(name "B57"
						(effects
							(font
								(size 1.27 1.27)
							)
						)
					)
					(number "B57"
						(effects
							(font
								(size 1.27 1.27)
							)
						)
					)
				)
				(pin passive line
					(at 25.4 -195.58 180)
					(length 5.08)
					(name "B58"
						(effects
							(font
								(size 1.27 1.27)
							)
						)
					)
					(number "B58"
						(effects
							(font
								(size 1.27 1.27)
							)
						)
					)
				)
				(pin passive line
					(at 25.4 -198.12 180)
					(length 5.08)
					(name "B59"
						(effects
							(font
								(size 1.27 1.27)
							)
						)
					)
					(number "B59"
						(effects
							(font
								(size 1.27 1.27)
							)
						)
					)
				)
				(pin passive line
					(at 25.4 -200.66 180)
					(length 5.08)
					(name "B60"
						(effects
							(font
								(size 1.27 1.27)
							)
						)
					)
					(number "B60"
						(effects
							(font
								(size 1.27 1.27)
							)
						)
					)
				)
				(pin passive line
					(at 25.4 -203.2 180)
					(length 5.08)
					(name "B61"
						(effects
							(font
								(size 1.27 1.27)
							)
						)
					)
					(number "B61"
						(effects
							(font
								(size 1.27 1.27)
							)
						)
					)
				)
				(pin passive line
					(at 25.4 -205.74 180)
					(length 5.08)
					(name "B62"
						(effects
							(font
								(size 1.27 1.27)
							)
						)
					)
					(number "B62"
						(effects
							(font
								(size 1.27 1.27)
							)
						)
					)
				)
				(pin passive line
					(at 25.4 -208.28 180)
					(length 5.08)
					(name "B63"
						(effects
							(font
								(size 1.27 1.27)
							)
						)
					)
					(number "B63"
						(effects
							(font
								(size 1.27 1.27)
							)
						)
					)
				)
				(pin passive line
					(at 25.4 -210.82 180)
					(length 5.08)
					(name "B64"
						(effects
							(font
								(size 1.27 1.27)
							)
						)
					)
					(number "B64"
						(effects
							(font
								(size 1.27 1.27)
							)
						)
					)
				)
				(pin passive line
					(at 25.4 -213.36 180)
					(length 5.08)
					(name "B65"
						(effects
							(font
								(size 1.27 1.27)
							)
						)
					)
					(number "B65"
						(effects
							(font
								(size 1.27 1.27)
							)
						)
					)
				)
				(pin passive line
					(at 25.4 -215.9 180)
					(length 5.08)
					(name "B66"
						(effects
							(font
								(size 1.27 1.27)
							)
						)
					)
					(number "B66"
						(effects
							(font
								(size 1.27 1.27)
							)
						)
					)
				)
				(pin passive line
					(at 25.4 -218.44 180)
					(length 5.08)
					(name "B67"
						(effects
							(font
								(size 1.27 1.27)
							)
						)
					)
					(number "B67"
						(effects
							(font
								(size 1.27 1.27)
							)
						)
					)
				)
				(pin passive line
					(at 25.4 -220.98 180)
					(length 5.08)
					(name "B68"
						(effects
							(font
								(size 1.27 1.27)
							)
						)
					)
					(number "B68"
						(effects
							(font
								(size 1.27 1.27)
							)
						)
					)
				)
				(pin passive line
					(at 25.4 -223.52 180)
					(length 5.08)
					(name "B69"
						(effects
							(font
								(size 1.27 1.27)
							)
						)
					)
					(number "B69"
						(effects
							(font
								(size 1.27 1.27)
							)
						)
					)
				)
				(pin passive line
					(at 25.4 -226.06 180)
					(length 5.08)
					(name "B70"
						(effects
							(font
								(size 1.27 1.27)
							)
						)
					)
					(number "B70"
						(effects
							(font
								(size 1.27 1.27)
							)
						)
					)
				)
			)
		)
	(symbol "antmicroPushbuttonSwitches:SW_KMR211NGLFS_SMD"
			(pin_names
				(hide yes)
			)
			(exclude_from_sim no)
			(in_bom yes)
			(on_board yes)
			(property "Reference" "SW"
				(at 25.4 -2.54 0)
				(effects
					(font
						(size 1.27 1.27)
						(thickness 0.15)
					)
					(justify left bottom)
				)
			)
			(property "Value" "SW_KMR211NGLFS_SMD"
				(at 25.4 -7.62 0)
				(effects
					(font
						(size 1.27 1.27)
						(thickness 0.15)
					)
					(justify left bottom)
					(hide yes)
				)
			)
			(property "Footprint" "antmicro-footprints:SW_KMR211NGLFS_SMD"
				(at 25.4 -10.16 0)
				(effects
					(font
						(size 1.27 1.27)
						(thickness 0.15)
					)
					(justify left bottom)
					(hide yes)
				)
			)
			(property "Datasheet" "http://www.farnell.com/datasheets/2631211.pdf"
				(at 25.4 -12.7 0)
				(effects
					(font
						(size 1.27 1.27)
						(thickness 0.15)
					)
					(justify left bottom)
					(hide yes)
				)
			)
			(property "Description" "Tactile Switch, KMR 2 Series, Top Actuated, Surface Mount, Oval Button, 120 gf, 50mA at 32VDC"
				(at 25.4 -22.86 0)
				(effects
					(font
						(size 1.27 1.27)
					)
					(justify left bottom)
					(hide yes)
				)
			)
			(property "MPN" "KMR211NGLFS"
				(at 25.4 -5.08 0)
				(effects
					(font
						(size 1.27 1.27)
						(thickness 0.15)
					)
					(justify left bottom)
				)
			)
			(property "Manufacturer" "C&K"
				(at 25.4 -15.24 0)
				(effects
					(font
						(size 1.27 1.27)
						(thickness 0.15)
					)
					(justify left bottom)
					(hide yes)
				)
			)
			(property "Author" "Antmicro"
				(at 25.4 -17.78 0)
				(effects
					(font
						(size 1.27 1.27)
						(thickness 0.15)
					)
					(justify left bottom)
					(hide yes)
				)
			)
			(property "License" "Apache-2.0"
				(at 25.4 -20.32 0)
				(effects
					(font
						(size 1.27 1.27)
						(thickness 0.15)
					)
					(justify left bottom)
					(hide yes)
				)
			)
			(property "ki_keywords" "VERTICAL, SMT, SWITCH, MECHANICAL, TACTILE"
				(at 0 0 0)
				(effects
					(font
						(size 1.27 1.27)
					)
					(hide yes)
				)
			)
			(symbol "SW_KMR211NGLFS_SMD_1_1"
				(polyline
					(pts
						(xy 2.54 0) (xy 3.302 0)
					)
					(stroke
						(width 0.254)
						(type default)
					)
					(fill
						(type none)
					)
				)
				(polyline
					(pts
						(xy 2.54 -2.54) (xy 3.302 -2.54)
					)
					(stroke
						(width 0.254)
						(type default)
					)
					(fill
						(type none)
					)
				)
				(polyline
					(pts
						(xy 3.302 1.27) (xy 6.858 1.27)
					)
					(stroke
						(width 0.254)
						(type default)
					)
					(fill
						(type none)
					)
				)
				(circle
					(center 3.556 0)
					(radius 0.254)
					(stroke
						(width 0.254)
						(type default)
					)
					(fill
						(type none)
					)
				)
				(polyline
					(pts
						(xy 3.556 -0.3048) (xy 3.556 -2.1844)
					)
					(stroke
						(width 0.254)
						(type default)
					)
					(fill
						(type none)
					)
				)
				(circle
					(center 3.556 -2.54)
					(radius 0.254)
					(stroke
						(width 0.254)
						(type default)
					)
					(fill
						(type none)
					)
				)
				(polyline
					(pts
						(xy 4.064 2.794) (xy 6.096 2.794)
					)
					(stroke
						(width 0.254)
						(type default)
					)
					(fill
						(type none)
					)
				)
				(polyline
					(pts
						(xy 5.08 1.27) (xy 5.08 2.794)
					)
					(stroke
						(width 0.254)
						(type default)
					)
					(fill
						(type none)
					)
				)
				(circle
					(center 6.604 0)
					(radius 0.254)
					(stroke
						(width 0.254)
						(type default)
					)
					(fill
						(type none)
					)
				)
				(polyline
					(pts
						(xy 6.604 -0.254) (xy 6.604 -2.1844)
					)
					(stroke
						(width 0.254)
						(type default)
					)
					(fill
						(type none)
					)
				)
				(circle
					(center 6.604 -2.54)
					(radius 0.254)
					(stroke
						(width 0.254)
						(type default)
					)
					(fill
						(type none)
					)
				)
				(polyline
					(pts
						(xy 7.62 0) (xy 6.858 0)
					)
					(stroke
						(width 0.254)
						(type default)
					)
					(fill
						(type none)
					)
				)
				(polyline
					(pts
						(xy 7.62 -2.54) (xy 6.858 -2.54)
					)
					(stroke
						(width 0.254)
						(type default)
					)
					(fill
						(type none)
					)
				)
				(pin passive line
					(at 0 0 0)
					(length 2.54)
					(name "1"
						(effects
							(font
								(size 1.27 1.27)
							)
						)
					)
					(number "1"
						(effects
							(font
								(size 1.27 1.27)
							)
						)
					)
				)
				(pin passive line
					(at 0 -2.54 0)
					(length 2.54)
					(name "2"
						(effects
							(font
								(size 1.27 1.27)
							)
						)
					)
					(number "2"
						(effects
							(font
								(size 1.27 1.27)
							)
						)
					)
				)
				(pin passive line
					(at 10.16 0 180)
					(length 2.54)
					(name "3"
						(effects
							(font
								(size 1.27 1.27)
							)
						)
					)
					(number "3"
						(effects
							(font
								(size 1.27 1.27)
							)
						)
					)
				)
				(pin passive line
					(at 10.16 -2.54 180)
					(length 2.54)
					(name "4"
						(effects
							(font
								(size 1.27 1.27)
							)
						)
					)
					(number "4"
						(effects
							(font
								(size 1.27 1.27)
							)
						)
					)
				)
			)
		)
	(symbol "antmicroResistors0402:R_0R_0402"
			(pin_numbers
				(hide yes)
			)
			(pin_names
				(hide yes)
			)
			(exclude_from_sim no)
			(in_bom yes)
			(on_board yes)
			(property "Reference" "R"
				(at 20.32 -5.08 0)
				(effects
					(font
						(size 1.27 1.27)
						(thickness 0.15)
					)
					(justify left bottom)
				)
			)
			(property "Value" "R_0R_0402"
				(at 20.32 -12.7 0)
				(effects
					(font
						(size 1.27 1.27)
						(thickness 0.15)
					)
					(justify left bottom)
					(hide yes)
				)
			)
			(property "Footprint" "antmicro-footprints:R_0402_1005Metric"
				(at 20.32 -15.24 0)
				(effects
					(font
						(size 1.27 1.27)
						(thickness 0.15)
					)
					(justify left bottom)
					(hide yes)
				)
			)
			(property "Datasheet" "https://industrial.panasonic.com/cdbs/www-data/pdf/RDA0000/AOA0000C301.pdf"
				(at 20.32 -17.78 0)
				(effects
					(font
						(size 1.27 1.27)
						(thickness 0.15)
					)
					(justify left bottom)
					(hide yes)
				)
			)
			(property "Description" "SMD Chip Resistor, Jumper, 0 ohm, 100 mW, 0402 [1005 Metric], Thick Film, General Purpose"
				(at 20.32 -33.02 0)
				(effects
					(font
						(size 1.27 1.27)
					)
					(justify left bottom)
					(hide yes)
				)
			)
			(property "MPN" "ERJ2GE0R00X"
				(at 20.32 -20.32 0)
				(effects
					(font
						(size 1.27 1.27)
						(thickness 0.15)
					)
					(justify left bottom)
					(hide yes)
				)
			)
			(property "Manufacturer" "Panasonic"
				(at 20.32 -22.86 0)
				(effects
					(font
						(size 1.27 1.27)
						(thickness 0.15)
					)
					(justify left bottom)
					(hide yes)
				)
			)
			(property "License" "Apache-2.0"
				(at 20.32 -25.4 0)
				(effects
					(font
						(size 1.27 1.27)
						(thickness 0.15)
					)
					(justify left bottom)
					(hide yes)
				)
			)
			(property "Author" "Antmicro"
				(at 20.32 -27.94 0)
				(effects
					(font
						(size 1.27 1.27)
						(thickness 0.15)
					)
					(justify left bottom)
					(hide yes)
				)
			)
			(property "Val" "0R"
				(at 20.32 -7.62 0)
				(effects
					(font
						(size 1.27 1.27)
						(thickness 0.15)
					)
					(justify left bottom)
				)
			)
			(property "Tolerance" "~"
				(at 20.32 -10.16 0)
				(effects
					(font
						(size 1.27 1.27)
					)
					(justify left bottom)
					(hide yes)
				)
			)
			(property "Current" "1A"
				(at 20.32 -30.48 0)
				(effects
					(font
						(size 1.27 1.27)
						(thickness 0.15)
					)
					(justify left bottom)
					(hide yes)
				)
			)
			(property "ki_keywords" "0402, SMT, RESISTOR, PASSIVE"
				(at 0 0 0)
				(effects
					(font
						(size 1.27 1.27)
					)
					(hide yes)
				)
			)
			(symbol "R_0R_0402_0_1"
				(rectangle
					(start 0.635 0.889)
					(end 4.445 -0.889)
					(stroke
						(width 0.254)
						(type default)
					)
					(fill
						(type none)
					)
				)
			)
			(symbol "R_0R_0402_1_1"
				(pin passive line
					(at 0 0 0)
					(length 0.635)
					(name "~"
						(effects
							(font
								(size 1.27 1.27)
							)
						)
					)
					(number "1"
						(effects
							(font
								(size 1.27 1.27)
							)
						)
					)
				)
				(pin passive line
					(at 5.08 0 180)
					(length 0.635)
					(name "~"
						(effects
							(font
								(size 1.27 1.27)
							)
						)
					)
					(number "2"
						(effects
							(font
								(size 1.27 1.27)
							)
						)
					)
				)
			)
		)
	(symbol "antmicroResistors0402:R_100R_0402"
			(pin_numbers
				(hide yes)
			)
			(pin_names
				(hide yes)
			)
			(exclude_from_sim no)
			(in_bom yes)
			(on_board yes)
			(property "Reference" "R"
				(at 20.32 -5.08 0)
				(effects
					(font
						(size 1.27 1.27)
						(thickness 0.15)
					)
					(justify left bottom)
				)
			)
			(property "Value" "R_100R_0402"
				(at 20.32 -12.7 0)
				(effects
					(font
						(size 1.27 1.27)
						(thickness 0.15)
					)
					(justify left bottom)
					(hide yes)
				)
			)
			(property "Footprint" "antmicro-footprints:R_0402_1005Metric"
				(at 20.32 -15.24 0)
				(effects
					(font
						(size 1.27 1.27)
						(thickness 0.15)
					)
					(justify left bottom)
					(hide yes)
				)
			)
			(property "Datasheet" "https://www.bourns.com/docs/product-datasheets/cr.pdf"
				(at 20.32 -17.78 0)
				(effects
					(font
						(size 1.27 1.27)
						(thickness 0.15)
					)
					(justify left bottom)
					(hide yes)
				)
			)
			(property "Description" "SMD Chip Resistor, 100 ohm, ± 1%, 62.5 mW, 0402 [1005 Metric], Thick Film, General Purpose"
				(at 20.32 -30.48 0)
				(effects
					(font
						(size 1.27 1.27)
					)
					(justify left bottom)
					(hide yes)
				)
			)
			(property "MPN" "CR0402-FX-1000GLF"
				(at 20.32 -20.32 0)
				(effects
					(font
						(size 1.27 1.27)
						(thickness 0.15)
					)
					(justify left bottom)
					(hide yes)
				)
			)
			(property "Manufacturer" "Bourns"
				(at 20.32 -22.86 0)
				(effects
					(font
						(size 1.27 1.27)
						(thickness 0.15)
					)
					(justify left bottom)
					(hide yes)
				)
			)
			(property "License" "Apache-2.0"
				(at 20.32 -25.4 0)
				(effects
					(font
						(size 1.27 1.27)
						(thickness 0.15)
					)
					(justify left bottom)
					(hide yes)
				)
			)
			(property "Author" "Antmicro"
				(at 20.32 -27.94 0)
				(effects
					(font
						(size 1.27 1.27)
						(thickness 0.15)
					)
					(justify left bottom)
					(hide yes)
				)
			)
			(property "Val" "100R"
				(at 20.32 -7.62 0)
				(effects
					(font
						(size 1.27 1.27)
						(thickness 0.15)
					)
					(justify left bottom)
				)
			)
			(property "Tolerance" "1%"
				(at 20.32 -10.16 0)
				(effects
					(font
						(size 1.27 1.27)
					)
					(justify left bottom)
					(hide yes)
				)
			)
			(property "ki_keywords" "0402, SMT, RESISTOR, PASSIVE"
				(at 0 0 0)
				(effects
					(font
						(size 1.27 1.27)
					)
					(hide yes)
				)
			)
			(symbol "R_100R_0402_0_1"
				(rectangle
					(start 0.635 0.889)
					(end 4.445 -0.889)
					(stroke
						(width 0.254)
						(type default)
					)
					(fill
						(type none)
					)
				)
			)
			(symbol "R_100R_0402_1_1"
				(pin passive line
					(at 0 0 0)
					(length 0.635)
					(name "~"
						(effects
							(font
								(size 1.27 1.27)
							)
						)
					)
					(number "1"
						(effects
							(font
								(size 1.27 1.27)
							)
						)
					)
				)
				(pin passive line
					(at 5.08 0 180)
					(length 0.635)
					(name "~"
						(effects
							(font
								(size 1.27 1.27)
							)
						)
					)
					(number "2"
						(effects
							(font
								(size 1.27 1.27)
							)
						)
					)
				)
			)
		)
	(symbol "antmicroResistors0402:R_100k_0402"
			(pin_numbers
				(hide yes)
			)
			(pin_names
				(hide yes)
			)
			(exclude_from_sim no)
			(in_bom yes)
			(on_board yes)
			(property "Reference" "R"
				(at 20.32 -5.08 0)
				(effects
					(font
						(size 1.27 1.27)
						(thickness 0.15)
					)
					(justify left bottom)
				)
			)
			(property "Value" "R_100k_0402"
				(at 20.32 -12.7 0)
				(effects
					(font
						(size 1.27 1.27)
						(thickness 0.15)
					)
					(justify left bottom)
					(hide yes)
				)
			)
			(property "Footprint" "antmicro-footprints:R_0402_1005Metric"
				(at 20.32 -15.24 0)
				(effects
					(font
						(size 1.27 1.27)
						(thickness 0.15)
					)
					(justify left bottom)
					(hide yes)
				)
			)
			(property "Datasheet" "https://www.bourns.com/docs/product-datasheets/cr.pdf"
				(at 20.32 -17.78 0)
				(effects
					(font
						(size 1.27 1.27)
						(thickness 0.15)
					)
					(justify left bottom)
					(hide yes)
				)
			)
			(property "Description" "SMD Chip Resistor, 100 kohm, ± 1%, 62.5 mW, 0402 [1005 Metric], Thick Film, General Purpose"
				(at 20.32 -30.48 0)
				(effects
					(font
						(size 1.27 1.27)
					)
					(justify left bottom)
					(hide yes)
				)
			)
			(property "MPN" "CR0402-FX-1003GLF"
				(at 20.32 -20.32 0)
				(effects
					(font
						(size 1.27 1.27)
						(thickness 0.15)
					)
					(justify left bottom)
					(hide yes)
				)
			)
			(property "Manufacturer" "Bourns"
				(at 20.32 -22.86 0)
				(effects
					(font
						(size 1.27 1.27)
						(thickness 0.15)
					)
					(justify left bottom)
					(hide yes)
				)
			)
			(property "License" "Apache-2.0"
				(at 20.32 -25.4 0)
				(effects
					(font
						(size 1.27 1.27)
						(thickness 0.15)
					)
					(justify left bottom)
					(hide yes)
				)
			)
			(property "Author" "Antmicro"
				(at 20.32 -27.94 0)
				(effects
					(font
						(size 1.27 1.27)
						(thickness 0.15)
					)
					(justify left bottom)
					(hide yes)
				)
			)
			(property "Val" "100k"
				(at 20.32 -7.62 0)
				(effects
					(font
						(size 1.27 1.27)
						(thickness 0.15)
					)
					(justify left bottom)
				)
			)
			(property "Tolerance" "1%"
				(at 20.32 -10.16 0)
				(effects
					(font
						(size 1.27 1.27)
					)
					(justify left bottom)
					(hide yes)
				)
			)
			(property "ki_keywords" "0402, SMT, RESISTOR, PASSIVE"
				(at 0 0 0)
				(effects
					(font
						(size 1.27 1.27)
					)
					(hide yes)
				)
			)
			(symbol "R_100k_0402_0_1"
				(rectangle
					(start 0.635 0.889)
					(end 4.445 -0.889)
					(stroke
						(width 0.254)
						(type default)
					)
					(fill
						(type none)
					)
				)
			)
			(symbol "R_100k_0402_1_1"
				(pin passive line
					(at 0 0 0)
					(length 0.635)
					(name "~"
						(effects
							(font
								(size 1.27 1.27)
							)
						)
					)
					(number "1"
						(effects
							(font
								(size 1.27 1.27)
							)
						)
					)
				)
				(pin passive line
					(at 5.08 0 180)
					(length 0.635)
					(name "~"
						(effects
							(font
								(size 1.27 1.27)
							)
						)
					)
					(number "2"
						(effects
							(font
								(size 1.27 1.27)
							)
						)
					)
				)
			)
		)
	(symbol "antmicroResistors0402:R_10k2_0402"
			(pin_numbers
				(hide yes)
			)
			(pin_names
				(hide yes)
			)
			(exclude_from_sim no)
			(in_bom yes)
			(on_board yes)
			(property "Reference" "R"
				(at 20.32 -5.08 0)
				(effects
					(font
						(size 1.27 1.27)
						(thickness 0.15)
					)
					(justify left bottom)
				)
			)
			(property "Value" "R_10k2_0402"
				(at 20.32 -12.7 0)
				(effects
					(font
						(size 1.27 1.27)
						(thickness 0.15)
					)
					(justify left bottom)
					(hide yes)
				)
			)
			(property "Footprint" "antmicro-footprints:R_0402_1005Metric"
				(at 20.32 -15.24 0)
				(effects
					(font
						(size 1.27 1.27)
						(thickness 0.15)
					)
					(justify left bottom)
					(hide yes)
				)
			)
			(property "Datasheet" "https://www.bourns.com/docs/product-datasheets/cr.pdf"
				(at 20.32 -17.78 0)
				(effects
					(font
						(size 1.27 1.27)
						(thickness 0.15)
					)
					(justify left bottom)
					(hide yes)
				)
			)
			(property "Description" "SMD Chip Resistor"
				(at 20.32 -30.48 0)
				(effects
					(font
						(size 1.27 1.27)
					)
					(justify left bottom)
					(hide yes)
				)
			)
			(property "MPN" "CR0402-FX-1022GLF"
				(at 20.32 -20.32 0)
				(effects
					(font
						(size 1.27 1.27)
						(thickness 0.15)
					)
					(justify left bottom)
					(hide yes)
				)
			)
			(property "Manufacturer" "Bourns"
				(at 20.32 -22.86 0)
				(effects
					(font
						(size 1.27 1.27)
						(thickness 0.15)
					)
					(justify left bottom)
					(hide yes)
				)
			)
			(property "License" "Apache-2.0"
				(at 20.32 -25.4 0)
				(effects
					(font
						(size 1.27 1.27)
						(thickness 0.15)
					)
					(justify left bottom)
					(hide yes)
				)
			)
			(property "Author" "Antmicro"
				(at 20.32 -27.94 0)
				(effects
					(font
						(size 1.27 1.27)
						(thickness 0.15)
					)
					(justify left bottom)
					(hide yes)
				)
			)
			(property "Val" "10k2"
				(at 20.32 -7.62 0)
				(effects
					(font
						(size 1.27 1.27)
						(thickness 0.15)
					)
					(justify left bottom)
				)
			)
			(property "Tolerance" "1%"
				(at 20.32 -10.16 0)
				(effects
					(font
						(size 1.27 1.27)
					)
					(justify left bottom)
					(hide yes)
				)
			)
			(property "ki_keywords" "0402, SMT, RESISTOR, PASSIVE"
				(at 0 0 0)
				(effects
					(font
						(size 1.27 1.27)
					)
					(hide yes)
				)
			)
			(symbol "R_10k2_0402_0_1"
				(rectangle
					(start 0.635 0.889)
					(end 4.445 -0.889)
					(stroke
						(width 0.254)
						(type default)
					)
					(fill
						(type none)
					)
				)
			)
			(symbol "R_10k2_0402_1_1"
				(pin passive line
					(at 0 0 0)
					(length 0.635)
					(name "~"
						(effects
							(font
								(size 1.27 1.27)
							)
						)
					)
					(number "1"
						(effects
							(font
								(size 1.27 1.27)
							)
						)
					)
				)
				(pin passive line
					(at 5.08 0 180)
					(length 0.635)
					(name "~"
						(effects
							(font
								(size 1.27 1.27)
							)
						)
					)
					(number "2"
						(effects
							(font
								(size 1.27 1.27)
							)
						)
					)
				)
			)
		)
	(symbol "antmicroResistors0402:R_10k_0402"
			(pin_numbers
				(hide yes)
			)
			(pin_names
				(hide yes)
			)
			(exclude_from_sim no)
			(in_bom yes)
			(on_board yes)
			(property "Reference" "R"
				(at 20.32 -5.08 0)
				(effects
					(font
						(size 1.27 1.27)
						(thickness 0.15)
					)
					(justify left bottom)
				)
			)
			(property "Value" "R_10k_0402"
				(at 20.32 -12.7 0)
				(effects
					(font
						(size 1.27 1.27)
						(thickness 0.15)
					)
					(justify left bottom)
					(hide yes)
				)
			)
			(property "Footprint" "antmicro-footprints:R_0402_1005Metric"
				(at 20.32 -15.24 0)
				(effects
					(font
						(size 1.27 1.27)
						(thickness 0.15)
					)
					(justify left bottom)
					(hide yes)
				)
			)
			(property "Datasheet" "https://www.bourns.com/docs/product-datasheets/cr.pdf"
				(at 20.32 -17.78 0)
				(effects
					(font
						(size 1.27 1.27)
						(thickness 0.15)
					)
					(justify left bottom)
					(hide yes)
				)
			)
			(property "Description" "SMD Chip Resistor, 10 kohm, ± 1%, 62.5 mW, 0402 [1005 Metric], Thick Film, General Purpose"
				(at 20.32 -30.48 0)
				(effects
					(font
						(size 1.27 1.27)
					)
					(justify left bottom)
					(hide yes)
				)
			)
			(property "MPN" "CR0402-FX-1002GLF"
				(at 20.32 -20.32 0)
				(effects
					(font
						(size 1.27 1.27)
						(thickness 0.15)
					)
					(justify left bottom)
					(hide yes)
				)
			)
			(property "Manufacturer" "Bourns"
				(at 20.32 -22.86 0)
				(effects
					(font
						(size 1.27 1.27)
						(thickness 0.15)
					)
					(justify left bottom)
					(hide yes)
				)
			)
			(property "License" "Apache-2.0"
				(at 20.32 -25.4 0)
				(effects
					(font
						(size 1.27 1.27)
						(thickness 0.15)
					)
					(justify left bottom)
					(hide yes)
				)
			)
			(property "Author" "Antmicro"
				(at 20.32 -27.94 0)
				(effects
					(font
						(size 1.27 1.27)
						(thickness 0.15)
					)
					(justify left bottom)
					(hide yes)
				)
			)
			(property "Val" "10k"
				(at 20.32 -7.62 0)
				(effects
					(font
						(size 1.27 1.27)
						(thickness 0.15)
					)
					(justify left bottom)
				)
			)
			(property "Tolerance" "1%"
				(at 20.32 -10.16 0)
				(effects
					(font
						(size 1.27 1.27)
					)
					(justify left bottom)
					(hide yes)
				)
			)
			(property "ki_keywords" "0402, SMT, RESISTOR, PASSIVE"
				(at 0 0 0)
				(effects
					(font
						(size 1.27 1.27)
					)
					(hide yes)
				)
			)
			(symbol "R_10k_0402_0_1"
				(rectangle
					(start 0.635 0.889)
					(end 4.445 -0.889)
					(stroke
						(width 0.254)
						(type default)
					)
					(fill
						(type none)
					)
				)
			)
			(symbol "R_10k_0402_1_1"
				(pin passive line
					(at 0 0 0)
					(length 0.635)
					(name "~"
						(effects
							(font
								(size 1.27 1.27)
							)
						)
					)
					(number "1"
						(effects
							(font
								(size 1.27 1.27)
							)
						)
					)
				)
				(pin passive line
					(at 5.08 0 180)
					(length 0.635)
					(name "~"
						(effects
							(font
								(size 1.27 1.27)
							)
						)
					)
					(number "2"
						(effects
							(font
								(size 1.27 1.27)
							)
						)
					)
				)
			)
		)
	(symbol "antmicroResistors0402:R_124k_0402"
			(pin_numbers
				(hide yes)
			)
			(pin_names
				(hide yes)
			)
			(exclude_from_sim no)
			(in_bom yes)
			(on_board yes)
			(property "Reference" "R"
				(at 20.32 -5.08 0)
				(effects
					(font
						(size 1.27 1.27)
						(thickness 0.15)
					)
					(justify left bottom)
				)
			)
			(property "Value" "R_124k_0402"
				(at 20.32 -12.7 0)
				(effects
					(font
						(size 1.27 1.27)
						(thickness 0.15)
					)
					(justify left bottom)
					(hide yes)
				)
			)
			(property "Footprint" "antmicro-footprints:R_0402_1005Metric"
				(at 20.32 -15.24 0)
				(effects
					(font
						(size 1.27 1.27)
						(thickness 0.15)
					)
					(justify left bottom)
					(hide yes)
				)
			)
			(property "Datasheet" "https://www.bourns.com/docs/product-datasheets/cr.pdf"
				(at 20.32 -17.78 0)
				(effects
					(font
						(size 1.27 1.27)
						(thickness 0.15)
					)
					(justify left bottom)
					(hide yes)
				)
			)
			(property "Description" "SMD Chip Resistor, 124 kohm, ± 1%, 100 mW, 0402 [1005 Metric], Thick Film, Precision"
				(at 20.32 -30.48 0)
				(effects
					(font
						(size 1.27 1.27)
					)
					(justify left bottom)
					(hide yes)
				)
			)
			(property "MPN" "CR0402-FX-1243GLF"
				(at 20.32 -20.32 0)
				(effects
					(font
						(size 1.27 1.27)
						(thickness 0.15)
					)
					(justify left bottom)
					(hide yes)
				)
			)
			(property "Manufacturer" "Bourns"
				(at 20.32 -22.86 0)
				(effects
					(font
						(size 1.27 1.27)
						(thickness 0.15)
					)
					(justify left bottom)
					(hide yes)
				)
			)
			(property "License" "Apache-2.0"
				(at 20.32 -25.4 0)
				(effects
					(font
						(size 1.27 1.27)
						(thickness 0.15)
					)
					(justify left bottom)
					(hide yes)
				)
			)
			(property "Author" "Antmicro"
				(at 20.32 -27.94 0)
				(effects
					(font
						(size 1.27 1.27)
						(thickness 0.15)
					)
					(justify left bottom)
					(hide yes)
				)
			)
			(property "Val" "124k"
				(at 20.32 -7.62 0)
				(effects
					(font
						(size 1.27 1.27)
						(thickness 0.15)
					)
					(justify left bottom)
				)
			)
			(property "Tolerance" "1%"
				(at 20.32 -10.16 0)
				(effects
					(font
						(size 1.27 1.27)
					)
					(justify left bottom)
					(hide yes)
				)
			)
			(property "ki_keywords" "0402, SMT, RESISTOR, PASSIVE"
				(at 0 0 0)
				(effects
					(font
						(size 1.27 1.27)
					)
					(hide yes)
				)
			)
			(symbol "R_124k_0402_0_1"
				(rectangle
					(start 0.635 0.889)
					(end 4.445 -0.889)
					(stroke
						(width 0.254)
						(type default)
					)
					(fill
						(type none)
					)
				)
			)
			(symbol "R_124k_0402_1_1"
				(pin passive line
					(at 0 0 0)
					(length 0.635)
					(name "~"
						(effects
							(font
								(size 1.27 1.27)
							)
						)
					)
					(number "1"
						(effects
							(font
								(size 1.27 1.27)
							)
						)
					)
				)
				(pin passive line
					(at 5.08 0 180)
					(length 0.635)
					(name "~"
						(effects
							(font
								(size 1.27 1.27)
							)
						)
					)
					(number "2"
						(effects
							(font
								(size 1.27 1.27)
							)
						)
					)
				)
			)
		)
	(symbol "antmicroResistors0402:R_12k1_0402"
			(pin_numbers
				(hide yes)
			)
			(pin_names
				(hide yes)
			)
			(exclude_from_sim no)
			(in_bom yes)
			(on_board yes)
			(property "Reference" "R"
				(at 20.32 -5.08 0)
				(effects
					(font
						(size 1.27 1.27)
						(thickness 0.15)
					)
					(justify left bottom)
				)
			)
			(property "Value" "R_12k1_0402"
				(at 20.32 -12.7 0)
				(effects
					(font
						(size 1.27 1.27)
						(thickness 0.15)
					)
					(justify left bottom)
					(hide yes)
				)
			)
			(property "Footprint" "antmicro-footprints:R_0402_1005Metric"
				(at 20.32 -15.24 0)
				(effects
					(font
						(size 1.27 1.27)
						(thickness 0.15)
					)
					(justify left bottom)
					(hide yes)
				)
			)
			(property "Datasheet" "https://www.bourns.com/docs/product-datasheets/cr.pdf"
				(at 20.32 -17.78 0)
				(effects
					(font
						(size 1.27 1.27)
						(thickness 0.15)
					)
					(justify left bottom)
					(hide yes)
				)
			)
			(property "Description" "SMD Chip Resistor, 12.1 kohm, ± 1%, 62.5 mW, 0402 [1005 Metric], Thick Film, General Purpose"
				(at 20.32 -30.48 0)
				(effects
					(font
						(size 1.27 1.27)
					)
					(justify left bottom)
					(hide yes)
				)
			)
			(property "MPN" "CR0402-FX-1212GLF"
				(at 20.32 -20.32 0)
				(effects
					(font
						(size 1.27 1.27)
						(thickness 0.15)
					)
					(justify left bottom)
					(hide yes)
				)
			)
			(property "Manufacturer" "Bourns"
				(at 20.32 -22.86 0)
				(effects
					(font
						(size 1.27 1.27)
						(thickness 0.15)
					)
					(justify left bottom)
					(hide yes)
				)
			)
			(property "License" "Apache-2.0"
				(at 20.32 -25.4 0)
				(effects
					(font
						(size 1.27 1.27)
						(thickness 0.15)
					)
					(justify left bottom)
					(hide yes)
				)
			)
			(property "Author" "Antmicro"
				(at 20.32 -27.94 0)
				(effects
					(font
						(size 1.27 1.27)
						(thickness 0.15)
					)
					(justify left bottom)
					(hide yes)
				)
			)
			(property "Val" "12k1"
				(at 20.32 -7.62 0)
				(effects
					(font
						(size 1.27 1.27)
						(thickness 0.15)
					)
					(justify left bottom)
				)
			)
			(property "Tolerance" "1%"
				(at 20.32 -10.16 0)
				(effects
					(font
						(size 1.27 1.27)
					)
					(justify left bottom)
					(hide yes)
				)
			)
			(property "ki_keywords" "0402, SMT, RESISTOR, PASSIVE"
				(at 0 0 0)
				(effects
					(font
						(size 1.27 1.27)
					)
					(hide yes)
				)
			)
			(symbol "R_12k1_0402_0_1"
				(rectangle
					(start 0.635 0.889)
					(end 4.445 -0.889)
					(stroke
						(width 0.254)
						(type default)
					)
					(fill
						(type none)
					)
				)
			)
			(symbol "R_12k1_0402_1_1"
				(pin passive line
					(at 0 0 0)
					(length 0.635)
					(name "~"
						(effects
							(font
								(size 1.27 1.27)
							)
						)
					)
					(number "1"
						(effects
							(font
								(size 1.27 1.27)
							)
						)
					)
				)
				(pin passive line
					(at 5.08 0 180)
					(length 0.635)
					(name "~"
						(effects
							(font
								(size 1.27 1.27)
							)
						)
					)
					(number "2"
						(effects
							(font
								(size 1.27 1.27)
							)
						)
					)
				)
			)
		)
	(symbol "antmicroResistors0402:R_12k_0402"
			(pin_numbers
				(hide yes)
			)
			(pin_names
				(hide yes)
			)
			(exclude_from_sim no)
			(in_bom yes)
			(on_board yes)
			(property "Reference" "R"
				(at 20.32 -5.08 0)
				(effects
					(font
						(size 1.27 1.27)
						(thickness 0.15)
					)
					(justify left bottom)
				)
			)
			(property "Value" "R_12k_0402"
				(at 20.32 -12.7 0)
				(effects
					(font
						(size 1.27 1.27)
						(thickness 0.15)
					)
					(justify left bottom)
					(hide yes)
				)
			)
			(property "Footprint" "antmicro-footprints:R_0402_1005Metric"
				(at 20.32 -15.24 0)
				(effects
					(font
						(size 1.27 1.27)
						(thickness 0.15)
					)
					(justify left bottom)
					(hide yes)
				)
			)
			(property "Datasheet" "https://www.bourns.com/docs/product-datasheets/cr.pdf"
				(at 20.32 -17.78 0)
				(effects
					(font
						(size 1.27 1.27)
						(thickness 0.15)
					)
					(justify left bottom)
					(hide yes)
				)
			)
			(property "Description" "SMD Chip Resistor, 12 kohm, ± 1%, 62.5 mW, 0402 [1005 Metric], Thick Film, General Purpose"
				(at 20.32 -30.48 0)
				(effects
					(font
						(size 1.27 1.27)
					)
					(justify left bottom)
					(hide yes)
				)
			)
			(property "MPN" "CR0402-FX-1202GLF"
				(at 20.32 -20.32 0)
				(effects
					(font
						(size 1.27 1.27)
						(thickness 0.15)
					)
					(justify left bottom)
					(hide yes)
				)
			)
			(property "Manufacturer" "Bourns"
				(at 20.32 -22.86 0)
				(effects
					(font
						(size 1.27 1.27)
						(thickness 0.15)
					)
					(justify left bottom)
					(hide yes)
				)
			)
			(property "License" "Apache-2.0"
				(at 20.32 -25.4 0)
				(effects
					(font
						(size 1.27 1.27)
						(thickness 0.15)
					)
					(justify left bottom)
					(hide yes)
				)
			)
			(property "Author" "Antmicro"
				(at 20.32 -27.94 0)
				(effects
					(font
						(size 1.27 1.27)
						(thickness 0.15)
					)
					(justify left bottom)
					(hide yes)
				)
			)
			(property "Val" "12k"
				(at 20.32 -7.62 0)
				(effects
					(font
						(size 1.27 1.27)
						(thickness 0.15)
					)
					(justify left bottom)
				)
			)
			(property "Tolerance" "1%"
				(at 20.32 -10.16 0)
				(effects
					(font
						(size 1.27 1.27)
					)
					(justify left bottom)
					(hide yes)
				)
			)
			(property "ki_keywords" "0402, SMT, RESISTOR, PASSIVE"
				(at 0 0 0)
				(effects
					(font
						(size 1.27 1.27)
					)
					(hide yes)
				)
			)
			(symbol "R_12k_0402_0_1"
				(rectangle
					(start 0.635 0.889)
					(end 4.445 -0.889)
					(stroke
						(width 0.254)
						(type default)
					)
					(fill
						(type none)
					)
				)
			)
			(symbol "R_12k_0402_1_1"
				(pin passive line
					(at 0 0 0)
					(length 0.635)
					(name "~"
						(effects
							(font
								(size 1.27 1.27)
							)
						)
					)
					(number "1"
						(effects
							(font
								(size 1.27 1.27)
							)
						)
					)
				)
				(pin passive line
					(at 5.08 0 180)
					(length 0.635)
					(name "~"
						(effects
							(font
								(size 1.27 1.27)
							)
						)
					)
					(number "2"
						(effects
							(font
								(size 1.27 1.27)
							)
						)
					)
				)
			)
		)
	(symbol "antmicroResistors0402:R_16k9_0402"
			(pin_numbers
				(hide yes)
			)
			(pin_names
				(hide yes)
			)
			(exclude_from_sim no)
			(in_bom yes)
			(on_board yes)
			(property "Reference" "R"
				(at 20.32 -5.08 0)
				(effects
					(font
						(size 1.27 1.27)
						(thickness 0.15)
					)
					(justify left bottom)
				)
			)
			(property "Value" "R_16k9_0402"
				(at 20.32 -12.7 0)
				(effects
					(font
						(size 1.27 1.27)
						(thickness 0.15)
					)
					(justify left bottom)
					(hide yes)
				)
			)
			(property "Footprint" "antmicro-footprints:R_0402_1005Metric"
				(at 20.32 -15.24 0)
				(effects
					(font
						(size 1.27 1.27)
						(thickness 0.15)
					)
					(justify left bottom)
					(hide yes)
				)
			)
			(property "Datasheet" "https://www.bourns.com/docs/product-datasheets/cr.pdf"
				(at 20.32 -17.78 0)
				(effects
					(font
						(size 1.27 1.27)
						(thickness 0.15)
					)
					(justify left bottom)
					(hide yes)
				)
			)
			(property "Description" "SMD Chip Resistor, Ceramic, 16.9 kohm, ± 1%, 62.5 mW, 0402 [1005 Metric], Thick Film"
				(at 20.32 -30.48 0)
				(effects
					(font
						(size 1.27 1.27)
					)
					(justify left bottom)
					(hide yes)
				)
			)
			(property "MPN" "CR0402-FX-1692GLF"
				(at 20.32 -20.32 0)
				(effects
					(font
						(size 1.27 1.27)
						(thickness 0.15)
					)
					(justify left bottom)
					(hide yes)
				)
			)
			(property "Manufacturer" "Bourns"
				(at 20.32 -22.86 0)
				(effects
					(font
						(size 1.27 1.27)
						(thickness 0.15)
					)
					(justify left bottom)
					(hide yes)
				)
			)
			(property "License" "Apache-2.0"
				(at 20.32 -25.4 0)
				(effects
					(font
						(size 1.27 1.27)
						(thickness 0.15)
					)
					(justify left bottom)
					(hide yes)
				)
			)
			(property "Author" "Antmicro"
				(at 20.32 -27.94 0)
				(effects
					(font
						(size 1.27 1.27)
						(thickness 0.15)
					)
					(justify left bottom)
					(hide yes)
				)
			)
			(property "Val" "16k9"
				(at 20.32 -7.62 0)
				(effects
					(font
						(size 1.27 1.27)
						(thickness 0.15)
					)
					(justify left bottom)
				)
			)
			(property "Tolerance" "1%"
				(at 20.32 -10.16 0)
				(effects
					(font
						(size 1.27 1.27)
					)
					(justify left bottom)
					(hide yes)
				)
			)
			(property "ki_keywords" "0402, SMT, RESISTOR, PASSIVE"
				(at 0 0 0)
				(effects
					(font
						(size 1.27 1.27)
					)
					(hide yes)
				)
			)
			(symbol "R_16k9_0402_0_1"
				(rectangle
					(start 0.635 0.889)
					(end 4.445 -0.889)
					(stroke
						(width 0.254)
						(type default)
					)
					(fill
						(type none)
					)
				)
			)
			(symbol "R_16k9_0402_1_1"
				(pin passive line
					(at 0 0 0)
					(length 0.635)
					(name "~"
						(effects
							(font
								(size 1.27 1.27)
							)
						)
					)
					(number "1"
						(effects
							(font
								(size 1.27 1.27)
							)
						)
					)
				)
				(pin passive line
					(at 5.08 0 180)
					(length 0.635)
					(name "~"
						(effects
							(font
								(size 1.27 1.27)
							)
						)
					)
					(number "2"
						(effects
							(font
								(size 1.27 1.27)
							)
						)
					)
				)
			)
		)
	(symbol "antmicroResistors0402:R_1M8_0402"
			(pin_numbers
				(hide yes)
			)
			(pin_names
				(hide yes)
			)
			(exclude_from_sim no)
			(in_bom yes)
			(on_board yes)
			(property "Reference" "R"
				(at 20.32 -5.08 0)
				(effects
					(font
						(size 1.27 1.27)
						(thickness 0.15)
					)
					(justify left bottom)
				)
			)
			(property "Value" "R_1M8_0402"
				(at 20.32 -12.7 0)
				(effects
					(font
						(size 1.27 1.27)
						(thickness 0.15)
					)
					(justify left bottom)
					(hide yes)
				)
			)
			(property "Footprint" "antmicro-footprints:R_0402_1005Metric"
				(at 20.32 -15.24 0)
				(effects
					(font
						(size 1.27 1.27)
						(thickness 0.15)
					)
					(justify left bottom)
					(hide yes)
				)
			)
			(property "Datasheet" "https://www.bourns.com/docs/product-datasheets/cr.pdf"
				(at 20.32 -17.78 0)
				(effects
					(font
						(size 1.27 1.27)
						(thickness 0.15)
					)
					(justify left bottom)
					(hide yes)
				)
			)
			(property "Description" "SMD Chip Resistor"
				(at 20.32 -30.48 0)
				(effects
					(font
						(size 1.27 1.27)
					)
					(justify left bottom)
					(hide yes)
				)
			)
			(property "MPN" "CR0402-FX-1804GLF"
				(at 20.32 -20.32 0)
				(effects
					(font
						(size 1.27 1.27)
						(thickness 0.15)
					)
					(justify left bottom)
					(hide yes)
				)
			)
			(property "Manufacturer" "Bourns"
				(at 20.32 -22.86 0)
				(effects
					(font
						(size 1.27 1.27)
						(thickness 0.15)
					)
					(justify left bottom)
					(hide yes)
				)
			)
			(property "License" "Apache-2.0"
				(at 20.32 -25.4 0)
				(effects
					(font
						(size 1.27 1.27)
						(thickness 0.15)
					)
					(justify left bottom)
					(hide yes)
				)
			)
			(property "Author" "Antmicro"
				(at 20.32 -27.94 0)
				(effects
					(font
						(size 1.27 1.27)
						(thickness 0.15)
					)
					(justify left bottom)
					(hide yes)
				)
			)
			(property "Val" "1M8"
				(at 20.32 -7.62 0)
				(effects
					(font
						(size 1.27 1.27)
						(thickness 0.15)
					)
					(justify left bottom)
				)
			)
			(property "Tolerance" "1%"
				(at 20.32 -10.16 0)
				(effects
					(font
						(size 1.27 1.27)
					)
					(justify left bottom)
					(hide yes)
				)
			)
			(property "ki_keywords" "0402, SMT, RESISTOR, PASSIVE"
				(at 0 0 0)
				(effects
					(font
						(size 1.27 1.27)
					)
					(hide yes)
				)
			)
			(symbol "R_1M8_0402_0_1"
				(rectangle
					(start 0.635 0.889)
					(end 4.445 -0.889)
					(stroke
						(width 0.254)
						(type default)
					)
					(fill
						(type none)
					)
				)
			)
			(symbol "R_1M8_0402_1_1"
				(pin passive line
					(at 0 0 0)
					(length 0.635)
					(name "~"
						(effects
							(font
								(size 1.27 1.27)
							)
						)
					)
					(number "1"
						(effects
							(font
								(size 1.27 1.27)
							)
						)
					)
				)
				(pin passive line
					(at 5.08 0 180)
					(length 0.635)
					(name "~"
						(effects
							(font
								(size 1.27 1.27)
							)
						)
					)
					(number "2"
						(effects
							(font
								(size 1.27 1.27)
							)
						)
					)
				)
			)
		)
	(symbol "antmicroResistors0402:R_1k_0402"
			(pin_numbers
				(hide yes)
			)
			(pin_names
				(hide yes)
			)
			(exclude_from_sim no)
			(in_bom yes)
			(on_board yes)
			(property "Reference" "R"
				(at 20.32 -5.08 0)
				(effects
					(font
						(size 1.27 1.27)
						(thickness 0.15)
					)
					(justify left bottom)
				)
			)
			(property "Value" "R_1k_0402"
				(at 20.32 -12.7 0)
				(effects
					(font
						(size 1.27 1.27)
						(thickness 0.15)
					)
					(justify left bottom)
					(hide yes)
				)
			)
			(property "Footprint" "antmicro-footprints:R_0402_1005Metric"
				(at 20.32 -15.24 0)
				(effects
					(font
						(size 1.27 1.27)
						(thickness 0.15)
					)
					(justify left bottom)
					(hide yes)
				)
			)
			(property "Datasheet" "https://www.bourns.com/docs/product-datasheets/cr.pdf"
				(at 20.32 -17.78 0)
				(effects
					(font
						(size 1.27 1.27)
						(thickness 0.15)
					)
					(justify left bottom)
					(hide yes)
				)
			)
			(property "Description" "SMD Chip Resistor, 1 kohm, ± 1%, 63 mW, 0402 [1005 Metric], Thick Film, General Purpose"
				(at 20.32 -30.48 0)
				(effects
					(font
						(size 1.27 1.27)
					)
					(justify left bottom)
					(hide yes)
				)
			)
			(property "MPN" "CR0402-FX-1001GLF"
				(at 20.32 -20.32 0)
				(effects
					(font
						(size 1.27 1.27)
						(thickness 0.15)
					)
					(justify left bottom)
					(hide yes)
				)
			)
			(property "Manufacturer" "Bourns"
				(at 20.32 -22.86 0)
				(effects
					(font
						(size 1.27 1.27)
						(thickness 0.15)
					)
					(justify left bottom)
					(hide yes)
				)
			)
			(property "License" "Apache-2.0"
				(at 20.32 -25.4 0)
				(effects
					(font
						(size 1.27 1.27)
						(thickness 0.15)
					)
					(justify left bottom)
					(hide yes)
				)
			)
			(property "Author" "Antmicro"
				(at 20.32 -27.94 0)
				(effects
					(font
						(size 1.27 1.27)
						(thickness 0.15)
					)
					(justify left bottom)
					(hide yes)
				)
			)
			(property "Val" "1k"
				(at 20.32 -7.62 0)
				(effects
					(font
						(size 1.27 1.27)
						(thickness 0.15)
					)
					(justify left bottom)
				)
			)
			(property "Tolerance" "1%"
				(at 20.32 -10.16 0)
				(effects
					(font
						(size 1.27 1.27)
					)
					(justify left bottom)
					(hide yes)
				)
			)
			(property "ki_keywords" "0402, SMT, RESISTOR, PASSIVE"
				(at 0 0 0)
				(effects
					(font
						(size 1.27 1.27)
					)
					(hide yes)
				)
			)
			(symbol "R_1k_0402_0_1"
				(rectangle
					(start 0.635 0.889)
					(end 4.445 -0.889)
					(stroke
						(width 0.254)
						(type default)
					)
					(fill
						(type none)
					)
				)
			)
			(symbol "R_1k_0402_1_1"
				(pin passive line
					(at 0 0 0)
					(length 0.635)
					(name "~"
						(effects
							(font
								(size 1.27 1.27)
							)
						)
					)
					(number "1"
						(effects
							(font
								(size 1.27 1.27)
							)
						)
					)
				)
				(pin passive line
					(at 5.08 0 180)
					(length 0.635)
					(name "~"
						(effects
							(font
								(size 1.27 1.27)
							)
						)
					)
					(number "2"
						(effects
							(font
								(size 1.27 1.27)
							)
						)
					)
				)
			)
		)
	(symbol "antmicroResistors0402:R_200R_0402"
			(pin_numbers
				(hide yes)
			)
			(pin_names
				(hide yes)
			)
			(exclude_from_sim no)
			(in_bom yes)
			(on_board yes)
			(property "Reference" "R"
				(at 20.32 -5.08 0)
				(effects
					(font
						(size 1.27 1.27)
						(thickness 0.15)
					)
					(justify left bottom)
				)
			)
			(property "Value" "R_200R_0402"
				(at 20.32 -12.7 0)
				(effects
					(font
						(size 1.27 1.27)
						(thickness 0.15)
					)
					(justify left bottom)
					(hide yes)
				)
			)
			(property "Footprint" "antmicro-footprints:R_0402_1005Metric"
				(at 20.32 -15.24 0)
				(effects
					(font
						(size 1.27 1.27)
						(thickness 0.15)
					)
					(justify left bottom)
					(hide yes)
				)
			)
			(property "Datasheet" "https://www.bourns.com/docs/product-datasheets/cr.pdf"
				(at 20.32 -17.78 0)
				(effects
					(font
						(size 1.27 1.27)
						(thickness 0.15)
					)
					(justify left bottom)
					(hide yes)
				)
			)
			(property "Description" "SMD Chip Resistor, 200 ohm, ± 1%, 62.5 mW, 0402 [1005 Metric], Thick Film, General Purpose"
				(at 20.32 -30.48 0)
				(effects
					(font
						(size 1.27 1.27)
					)
					(justify left bottom)
					(hide yes)
				)
			)
			(property "MPN" "CR0402-FX-2000GLF"
				(at 20.32 -20.32 0)
				(effects
					(font
						(size 1.27 1.27)
						(thickness 0.15)
					)
					(justify left bottom)
					(hide yes)
				)
			)
			(property "Manufacturer" "Bourns"
				(at 20.32 -22.86 0)
				(effects
					(font
						(size 1.27 1.27)
						(thickness 0.15)
					)
					(justify left bottom)
					(hide yes)
				)
			)
			(property "License" "Apache-2.0"
				(at 20.32 -25.4 0)
				(effects
					(font
						(size 1.27 1.27)
						(thickness 0.15)
					)
					(justify left bottom)
					(hide yes)
				)
			)
			(property "Author" "Antmicro"
				(at 20.32 -27.94 0)
				(effects
					(font
						(size 1.27 1.27)
						(thickness 0.15)
					)
					(justify left bottom)
					(hide yes)
				)
			)
			(property "Val" "200R"
				(at 20.32 -7.62 0)
				(effects
					(font
						(size 1.27 1.27)
						(thickness 0.15)
					)
					(justify left bottom)
				)
			)
			(property "Tolerance" "1%"
				(at 20.32 -10.16 0)
				(effects
					(font
						(size 1.27 1.27)
					)
					(justify left bottom)
					(hide yes)
				)
			)
			(property "ki_keywords" "0402, SMT, RESISTOR, PASSIVE"
				(at 0 0 0)
				(effects
					(font
						(size 1.27 1.27)
					)
					(hide yes)
				)
			)
			(symbol "R_200R_0402_0_1"
				(rectangle
					(start 0.635 0.889)
					(end 4.445 -0.889)
					(stroke
						(width 0.254)
						(type default)
					)
					(fill
						(type none)
					)
				)
			)
			(symbol "R_200R_0402_1_1"
				(pin passive line
					(at 0 0 0)
					(length 0.635)
					(name "~"
						(effects
							(font
								(size 1.27 1.27)
							)
						)
					)
					(number "1"
						(effects
							(font
								(size 1.27 1.27)
							)
						)
					)
				)
				(pin passive line
					(at 5.08 0 180)
					(length 0.635)
					(name "~"
						(effects
							(font
								(size 1.27 1.27)
							)
						)
					)
					(number "2"
						(effects
							(font
								(size 1.27 1.27)
							)
						)
					)
				)
			)
		)
	(symbol "antmicroResistors0402:R_200k_0402"
			(pin_numbers
				(hide yes)
			)
			(pin_names
				(hide yes)
			)
			(exclude_from_sim no)
			(in_bom yes)
			(on_board yes)
			(property "Reference" "R"
				(at 20.32 -5.08 0)
				(effects
					(font
						(size 1.27 1.27)
						(thickness 0.15)
					)
					(justify left bottom)
				)
			)
			(property "Value" "R_200k_0402"
				(at 20.32 -12.7 0)
				(effects
					(font
						(size 1.27 1.27)
						(thickness 0.15)
					)
					(justify left bottom)
					(hide yes)
				)
			)
			(property "Footprint" "antmicro-footprints:R_0402_1005Metric"
				(at 20.32 -15.24 0)
				(effects
					(font
						(size 1.27 1.27)
						(thickness 0.15)
					)
					(justify left bottom)
					(hide yes)
				)
			)
			(property "Datasheet" "https://www.bourns.com/docs/product-datasheets/cr.pdf"
				(at 20.32 -17.78 0)
				(effects
					(font
						(size 1.27 1.27)
						(thickness 0.15)
					)
					(justify left bottom)
					(hide yes)
				)
			)
			(property "Description" "SMD Chip Resistor, 200 kohm, ± 1%, 62.5 mW, 0402 [1005 Metric], Thick Film, General Purpose"
				(at 20.32 -30.48 0)
				(effects
					(font
						(size 1.27 1.27)
					)
					(justify left bottom)
					(hide yes)
				)
			)
			(property "MPN" "CR0402-FX-2003GLF"
				(at 20.32 -20.32 0)
				(effects
					(font
						(size 1.27 1.27)
						(thickness 0.15)
					)
					(justify left bottom)
					(hide yes)
				)
			)
			(property "Manufacturer" "Bourns"
				(at 20.32 -22.86 0)
				(effects
					(font
						(size 1.27 1.27)
						(thickness 0.15)
					)
					(justify left bottom)
					(hide yes)
				)
			)
			(property "License" "Apache-2.0"
				(at 20.32 -25.4 0)
				(effects
					(font
						(size 1.27 1.27)
						(thickness 0.15)
					)
					(justify left bottom)
					(hide yes)
				)
			)
			(property "Author" "Antmicro"
				(at 20.32 -27.94 0)
				(effects
					(font
						(size 1.27 1.27)
						(thickness 0.15)
					)
					(justify left bottom)
					(hide yes)
				)
			)
			(property "Val" "200k"
				(at 20.32 -7.62 0)
				(effects
					(font
						(size 1.27 1.27)
						(thickness 0.15)
					)
					(justify left bottom)
				)
			)
			(property "Tolerance" "1%"
				(at 20.32 -10.16 0)
				(effects
					(font
						(size 1.27 1.27)
					)
					(justify left bottom)
					(hide yes)
				)
			)
			(property "ki_keywords" "0402, SMT, RESISTOR, PASSIVE"
				(at 0 0 0)
				(effects
					(font
						(size 1.27 1.27)
					)
					(hide yes)
				)
			)
			(symbol "R_200k_0402_0_1"
				(rectangle
					(start 0.635 0.889)
					(end 4.445 -0.889)
					(stroke
						(width 0.254)
						(type default)
					)
					(fill
						(type none)
					)
				)
			)
			(symbol "R_200k_0402_1_1"
				(pin passive line
					(at 0 0 0)
					(length 0.635)
					(name "~"
						(effects
							(font
								(size 1.27 1.27)
							)
						)
					)
					(number "1"
						(effects
							(font
								(size 1.27 1.27)
							)
						)
					)
				)
				(pin passive line
					(at 5.08 0 180)
					(length 0.635)
					(name "~"
						(effects
							(font
								(size 1.27 1.27)
							)
						)
					)
					(number "2"
						(effects
							(font
								(size 1.27 1.27)
							)
						)
					)
				)
			)
		)
	(symbol "antmicroResistors0402:R_220R_0402"
			(pin_numbers
				(hide yes)
			)
			(pin_names
				(hide yes)
			)
			(exclude_from_sim no)
			(in_bom yes)
			(on_board yes)
			(property "Reference" "R"
				(at 20.32 -5.08 0)
				(effects
					(font
						(size 1.27 1.27)
						(thickness 0.15)
					)
					(justify left bottom)
				)
			)
			(property "Value" "R_220R_0402"
				(at 20.32 -12.7 0)
				(effects
					(font
						(size 1.27 1.27)
						(thickness 0.15)
					)
					(justify left bottom)
					(hide yes)
				)
			)
			(property "Footprint" "antmicro-footprints:R_0402_1005Metric"
				(at 20.32 -15.24 0)
				(effects
					(font
						(size 1.27 1.27)
						(thickness 0.15)
					)
					(justify left bottom)
					(hide yes)
				)
			)
			(property "Datasheet" "https://www.bourns.com/docs/product-datasheets/cr.pdf"
				(at 20.32 -17.78 0)
				(effects
					(font
						(size 1.27 1.27)
						(thickness 0.15)
					)
					(justify left bottom)
					(hide yes)
				)
			)
			(property "Description" "SMD Chip Resistor, 220 ohm, ± 1%, 62.5 mW, 0402 [1005 Metric], Thick Film, General Purpose"
				(at 20.32 -30.48 0)
				(effects
					(font
						(size 1.27 1.27)
					)
					(justify left bottom)
					(hide yes)
				)
			)
			(property "MPN" "CR0402-FX-2200GLF"
				(at 20.32 -20.32 0)
				(effects
					(font
						(size 1.27 1.27)
						(thickness 0.15)
					)
					(justify left bottom)
					(hide yes)
				)
			)
			(property "Manufacturer" "Bourns"
				(at 20.32 -22.86 0)
				(effects
					(font
						(size 1.27 1.27)
						(thickness 0.15)
					)
					(justify left bottom)
					(hide yes)
				)
			)
			(property "License" "Apache-2.0"
				(at 20.32 -25.4 0)
				(effects
					(font
						(size 1.27 1.27)
						(thickness 0.15)
					)
					(justify left bottom)
					(hide yes)
				)
			)
			(property "Author" "Antmicro"
				(at 20.32 -27.94 0)
				(effects
					(font
						(size 1.27 1.27)
						(thickness 0.15)
					)
					(justify left bottom)
					(hide yes)
				)
			)
			(property "Val" "220R"
				(at 20.32 -7.62 0)
				(effects
					(font
						(size 1.27 1.27)
						(thickness 0.15)
					)
					(justify left bottom)
				)
			)
			(property "Tolerance" "1%"
				(at 20.32 -10.16 0)
				(effects
					(font
						(size 1.27 1.27)
					)
					(justify left bottom)
					(hide yes)
				)
			)
			(property "ki_keywords" "0402, SMT, RESISTOR, PASSIVE"
				(at 0 0 0)
				(effects
					(font
						(size 1.27 1.27)
					)
					(hide yes)
				)
			)
			(symbol "R_220R_0402_0_1"
				(rectangle
					(start 0.635 0.889)
					(end 4.445 -0.889)
					(stroke
						(width 0.254)
						(type default)
					)
					(fill
						(type none)
					)
				)
			)
			(symbol "R_220R_0402_1_1"
				(pin passive line
					(at 0 0 0)
					(length 0.635)
					(name "~"
						(effects
							(font
								(size 1.27 1.27)
							)
						)
					)
					(number "1"
						(effects
							(font
								(size 1.27 1.27)
							)
						)
					)
				)
				(pin passive line
					(at 5.08 0 180)
					(length 0.635)
					(name "~"
						(effects
							(font
								(size 1.27 1.27)
							)
						)
					)
					(number "2"
						(effects
							(font
								(size 1.27 1.27)
							)
						)
					)
				)
			)
		)
	(symbol "antmicroResistors0402:R_22R_0402"
			(pin_numbers
				(hide yes)
			)
			(pin_names
				(hide yes)
			)
			(exclude_from_sim no)
			(in_bom yes)
			(on_board yes)
			(property "Reference" "R"
				(at 20.32 -5.08 0)
				(effects
					(font
						(size 1.27 1.27)
						(thickness 0.15)
					)
					(justify left bottom)
				)
			)
			(property "Value" "R_22R_0402"
				(at 20.32 -12.7 0)
				(effects
					(font
						(size 1.27 1.27)
						(thickness 0.15)
					)
					(justify left bottom)
					(hide yes)
				)
			)
			(property "Footprint" "antmicro-footprints:R_0402_1005Metric"
				(at 20.32 -15.24 0)
				(effects
					(font
						(size 1.27 1.27)
						(thickness 0.15)
					)
					(justify left bottom)
					(hide yes)
				)
			)
			(property "Datasheet" "https://www.bourns.com/docs/product-datasheets/cr.pdf"
				(at 20.32 -17.78 0)
				(effects
					(font
						(size 1.27 1.27)
						(thickness 0.15)
					)
					(justify left bottom)
					(hide yes)
				)
			)
			(property "Description" "SMD Chip Resistor, 22 ohm, ± 1%, 62.5 mW, 0402 [1005 Metric], Thick Film, General Purpose"
				(at 20.32 -30.48 0)
				(effects
					(font
						(size 1.27 1.27)
					)
					(justify left bottom)
					(hide yes)
				)
			)
			(property "MPN" "CR0402-FX-22R0GLF"
				(at 20.32 -20.32 0)
				(effects
					(font
						(size 1.27 1.27)
						(thickness 0.15)
					)
					(justify left bottom)
					(hide yes)
				)
			)
			(property "Manufacturer" "Bourns"
				(at 20.32 -22.86 0)
				(effects
					(font
						(size 1.27 1.27)
						(thickness 0.15)
					)
					(justify left bottom)
					(hide yes)
				)
			)
			(property "License" "Apache-2.0"
				(at 20.32 -25.4 0)
				(effects
					(font
						(size 1.27 1.27)
						(thickness 0.15)
					)
					(justify left bottom)
					(hide yes)
				)
			)
			(property "Author" "Antmicro"
				(at 20.32 -27.94 0)
				(effects
					(font
						(size 1.27 1.27)
						(thickness 0.15)
					)
					(justify left bottom)
					(hide yes)
				)
			)
			(property "Val" "22R"
				(at 20.32 -7.62 0)
				(effects
					(font
						(size 1.27 1.27)
						(thickness 0.15)
					)
					(justify left bottom)
				)
			)
			(property "Tolerance" "1%"
				(at 20.32 -10.16 0)
				(effects
					(font
						(size 1.27 1.27)
					)
					(justify left bottom)
					(hide yes)
				)
			)
			(property "ki_keywords" "0402, SMT, RESISTOR, PASSIVE"
				(at 0 0 0)
				(effects
					(font
						(size 1.27 1.27)
					)
					(hide yes)
				)
			)
			(symbol "R_22R_0402_0_1"
				(rectangle
					(start 0.635 0.889)
					(end 4.445 -0.889)
					(stroke
						(width 0.254)
						(type default)
					)
					(fill
						(type none)
					)
				)
			)
			(symbol "R_22R_0402_1_1"
				(pin passive line
					(at 0 0 0)
					(length 0.635)
					(name "~"
						(effects
							(font
								(size 1.27 1.27)
							)
						)
					)
					(number "1"
						(effects
							(font
								(size 1.27 1.27)
							)
						)
					)
				)
				(pin passive line
					(at 5.08 0 180)
					(length 0.635)
					(name "~"
						(effects
							(font
								(size 1.27 1.27)
							)
						)
					)
					(number "2"
						(effects
							(font
								(size 1.27 1.27)
							)
						)
					)
				)
			)
		)
	(symbol "antmicroResistors0402:R_240R_0402"
			(pin_numbers
				(hide yes)
			)
			(pin_names
				(hide yes)
			)
			(exclude_from_sim no)
			(in_bom yes)
			(on_board yes)
			(property "Reference" "R"
				(at 20.32 -5.08 0)
				(effects
					(font
						(size 1.27 1.27)
						(thickness 0.15)
					)
					(justify left bottom)
				)
			)
			(property "Value" "R_240R_0402"
				(at 20.32 -12.7 0)
				(effects
					(font
						(size 1.27 1.27)
						(thickness 0.15)
					)
					(justify left bottom)
					(hide yes)
				)
			)
			(property "Footprint" "antmicro-footprints:R_0402_1005Metric"
				(at 20.32 -15.24 0)
				(effects
					(font
						(size 1.27 1.27)
						(thickness 0.15)
					)
					(justify left bottom)
					(hide yes)
				)
			)
			(property "Datasheet" "https://www.bourns.com/docs/product-datasheets/cr.pdf"
				(at 20.32 -17.78 0)
				(effects
					(font
						(size 1.27 1.27)
						(thickness 0.15)
					)
					(justify left bottom)
					(hide yes)
				)
			)
			(property "Description" "SMD Chip Resistor, 240 ohm, ± 1%, 63 mW, 0402 [1005 Metric], Thick Film, General Purpose"
				(at 20.32 -30.48 0)
				(effects
					(font
						(size 1.27 1.27)
					)
					(justify left bottom)
					(hide yes)
				)
			)
			(property "MPN" "CR0402-FX-2400GLF"
				(at 20.32 -20.32 0)
				(effects
					(font
						(size 1.27 1.27)
						(thickness 0.15)
					)
					(justify left bottom)
					(hide yes)
				)
			)
			(property "Manufacturer" "Bourns"
				(at 20.32 -22.86 0)
				(effects
					(font
						(size 1.27 1.27)
						(thickness 0.15)
					)
					(justify left bottom)
					(hide yes)
				)
			)
			(property "License" "Apache-2.0"
				(at 20.32 -25.4 0)
				(effects
					(font
						(size 1.27 1.27)
						(thickness 0.15)
					)
					(justify left bottom)
					(hide yes)
				)
			)
			(property "Author" "Antmicro"
				(at 20.32 -27.94 0)
				(effects
					(font
						(size 1.27 1.27)
						(thickness 0.15)
					)
					(justify left bottom)
					(hide yes)
				)
			)
			(property "Val" "240R"
				(at 20.32 -7.62 0)
				(effects
					(font
						(size 1.27 1.27)
						(thickness 0.15)
					)
					(justify left bottom)
				)
			)
			(property "Tolerance" "1%"
				(at 20.32 -10.16 0)
				(effects
					(font
						(size 1.27 1.27)
					)
					(justify left bottom)
					(hide yes)
				)
			)
			(property "ki_keywords" "0402, SMT, RESISTOR, PASSIVE"
				(at 0 0 0)
				(effects
					(font
						(size 1.27 1.27)
					)
					(hide yes)
				)
			)
			(symbol "R_240R_0402_0_1"
				(rectangle
					(start 0.635 0.889)
					(end 4.445 -0.889)
					(stroke
						(width 0.254)
						(type default)
					)
					(fill
						(type none)
					)
				)
			)
			(symbol "R_240R_0402_1_1"
				(pin passive line
					(at 0 0 0)
					(length 0.635)
					(name "~"
						(effects
							(font
								(size 1.27 1.27)
							)
						)
					)
					(number "1"
						(effects
							(font
								(size 1.27 1.27)
							)
						)
					)
				)
				(pin passive line
					(at 5.08 0 180)
					(length 0.635)
					(name "~"
						(effects
							(font
								(size 1.27 1.27)
							)
						)
					)
					(number "2"
						(effects
							(font
								(size 1.27 1.27)
							)
						)
					)
				)
			)
		)
	(symbol "antmicroResistors0402:R_243k_0402"
			(pin_numbers
				(hide yes)
			)
			(pin_names
				(hide yes)
			)
			(exclude_from_sim no)
			(in_bom yes)
			(on_board yes)
			(property "Reference" "R"
				(at 20.32 -5.08 0)
				(effects
					(font
						(size 1.27 1.27)
						(thickness 0.15)
					)
					(justify left bottom)
				)
			)
			(property "Value" "R_243k_0402"
				(at 20.32 -12.7 0)
				(effects
					(font
						(size 1.27 1.27)
						(thickness 0.15)
					)
					(justify left bottom)
					(hide yes)
				)
			)
			(property "Footprint" "antmicro-footprints:R_0402_1005Metric"
				(at 20.32 -15.24 0)
				(effects
					(font
						(size 1.27 1.27)
						(thickness 0.15)
					)
					(justify left bottom)
					(hide yes)
				)
			)
			(property "Datasheet" "https://www.bourns.com/docs/product-datasheets/cr.pdf"
				(at 20.32 -17.78 0)
				(effects
					(font
						(size 1.27 1.27)
						(thickness 0.15)
					)
					(justify left bottom)
					(hide yes)
				)
			)
			(property "Description" "SMD Chip Resistor"
				(at 20.32 -30.48 0)
				(effects
					(font
						(size 1.27 1.27)
					)
					(justify left bottom)
					(hide yes)
				)
			)
			(property "MPN" "CR0402-FX-2433GLF"
				(at 20.32 -20.32 0)
				(effects
					(font
						(size 1.27 1.27)
						(thickness 0.15)
					)
					(justify left bottom)
					(hide yes)
				)
			)
			(property "Manufacturer" "Bourns"
				(at 20.32 -22.86 0)
				(effects
					(font
						(size 1.27 1.27)
						(thickness 0.15)
					)
					(justify left bottom)
					(hide yes)
				)
			)
			(property "License" "Apache-2.0"
				(at 20.32 -25.4 0)
				(effects
					(font
						(size 1.27 1.27)
						(thickness 0.15)
					)
					(justify left bottom)
					(hide yes)
				)
			)
			(property "Author" "Antmicro"
				(at 20.32 -27.94 0)
				(effects
					(font
						(size 1.27 1.27)
						(thickness 0.15)
					)
					(justify left bottom)
					(hide yes)
				)
			)
			(property "Val" "243k"
				(at 20.32 -7.62 0)
				(effects
					(font
						(size 1.27 1.27)
						(thickness 0.15)
					)
					(justify left bottom)
				)
			)
			(property "Tolerance" "1%"
				(at 20.32 -10.16 0)
				(effects
					(font
						(size 1.27 1.27)
					)
					(justify left bottom)
					(hide yes)
				)
			)
			(property "ki_keywords" "0402, SMT, RESISTOR, PASSIVE"
				(at 0 0 0)
				(effects
					(font
						(size 1.27 1.27)
					)
					(hide yes)
				)
			)
			(symbol "R_243k_0402_0_1"
				(rectangle
					(start 0.635 0.889)
					(end 4.445 -0.889)
					(stroke
						(width 0.254)
						(type default)
					)
					(fill
						(type none)
					)
				)
			)
			(symbol "R_243k_0402_1_1"
				(pin passive line
					(at 0 0 0)
					(length 0.635)
					(name "~"
						(effects
							(font
								(size 1.27 1.27)
							)
						)
					)
					(number "1"
						(effects
							(font
								(size 1.27 1.27)
							)
						)
					)
				)
				(pin passive line
					(at 5.08 0 180)
					(length 0.635)
					(name "~"
						(effects
							(font
								(size 1.27 1.27)
							)
						)
					)
					(number "2"
						(effects
							(font
								(size 1.27 1.27)
							)
						)
					)
				)
			)
		)
	(symbol "antmicroResistors0402:R_2k2_0402"
			(pin_numbers
				(hide yes)
			)
			(pin_names
				(hide yes)
			)
			(exclude_from_sim no)
			(in_bom yes)
			(on_board yes)
			(property "Reference" "R"
				(at 20.32 -5.08 0)
				(effects
					(font
						(size 1.27 1.27)
						(thickness 0.15)
					)
					(justify left bottom)
				)
			)
			(property "Value" "R_2k2_0402"
				(at 20.32 -12.7 0)
				(effects
					(font
						(size 1.27 1.27)
						(thickness 0.15)
					)
					(justify left bottom)
					(hide yes)
				)
			)
			(property "Footprint" "antmicro-footprints:R_0402_1005Metric"
				(at 20.32 -15.24 0)
				(effects
					(font
						(size 1.27 1.27)
						(thickness 0.15)
					)
					(justify left bottom)
					(hide yes)
				)
			)
			(property "Datasheet" "https://www.bourns.com/docs/product-datasheets/cr.pdf"
				(at 20.32 -17.78 0)
				(effects
					(font
						(size 1.27 1.27)
						(thickness 0.15)
					)
					(justify left bottom)
					(hide yes)
				)
			)
			(property "Description" "SMD Chip Resistor, 2.2 kohm, ± 1%, 62.5 mW, 0402 [1005 Metric], Thick Film, General Purpose"
				(at 20.32 -30.48 0)
				(effects
					(font
						(size 1.27 1.27)
					)
					(justify left bottom)
					(hide yes)
				)
			)
			(property "MPN" "CR0402-FX-2201GLF"
				(at 20.32 -20.32 0)
				(effects
					(font
						(size 1.27 1.27)
						(thickness 0.15)
					)
					(justify left bottom)
					(hide yes)
				)
			)
			(property "Manufacturer" "Bourns"
				(at 20.32 -22.86 0)
				(effects
					(font
						(size 1.27 1.27)
						(thickness 0.15)
					)
					(justify left bottom)
					(hide yes)
				)
			)
			(property "License" "Apache-2.0"
				(at 20.32 -25.4 0)
				(effects
					(font
						(size 1.27 1.27)
						(thickness 0.15)
					)
					(justify left bottom)
					(hide yes)
				)
			)
			(property "Author" "Antmicro"
				(at 20.32 -27.94 0)
				(effects
					(font
						(size 1.27 1.27)
						(thickness 0.15)
					)
					(justify left bottom)
					(hide yes)
				)
			)
			(property "Val" "2k2"
				(at 20.32 -7.62 0)
				(effects
					(font
						(size 1.27 1.27)
						(thickness 0.15)
					)
					(justify left bottom)
				)
			)
			(property "Tolerance" "1%"
				(at 20.32 -10.16 0)
				(effects
					(font
						(size 1.27 1.27)
					)
					(justify left bottom)
					(hide yes)
				)
			)
			(property "ki_keywords" "0402, SMT, RESISTOR, PASSIVE"
				(at 0 0 0)
				(effects
					(font
						(size 1.27 1.27)
					)
					(hide yes)
				)
			)
			(symbol "R_2k2_0402_0_1"
				(rectangle
					(start 0.635 0.889)
					(end 4.445 -0.889)
					(stroke
						(width 0.254)
						(type default)
					)
					(fill
						(type none)
					)
				)
			)
			(symbol "R_2k2_0402_1_1"
				(pin passive line
					(at 0 0 0)
					(length 0.635)
					(name "~"
						(effects
							(font
								(size 1.27 1.27)
							)
						)
					)
					(number "1"
						(effects
							(font
								(size 1.27 1.27)
							)
						)
					)
				)
				(pin passive line
					(at 5.08 0 180)
					(length 0.635)
					(name "~"
						(effects
							(font
								(size 1.27 1.27)
							)
						)
					)
					(number "2"
						(effects
							(font
								(size 1.27 1.27)
							)
						)
					)
				)
			)
		)
	(symbol "antmicroResistors0402:R_330R_0402"
			(pin_numbers
				(hide yes)
			)
			(pin_names
				(hide yes)
			)
			(exclude_from_sim no)
			(in_bom yes)
			(on_board yes)
			(property "Reference" "R"
				(at 20.32 -5.08 0)
				(effects
					(font
						(size 1.27 1.27)
						(thickness 0.15)
					)
					(justify left bottom)
				)
			)
			(property "Value" "R_330R_0402"
				(at 20.32 -12.7 0)
				(effects
					(font
						(size 1.27 1.27)
						(thickness 0.15)
					)
					(justify left bottom)
					(hide yes)
				)
			)
			(property "Footprint" "antmicro-footprints:R_0402_1005Metric"
				(at 20.32 -15.24 0)
				(effects
					(font
						(size 1.27 1.27)
						(thickness 0.15)
					)
					(justify left bottom)
					(hide yes)
				)
			)
			(property "Datasheet" "https://www.bourns.com/docs/product-datasheets/cr.pdf"
				(at 20.32 -17.78 0)
				(effects
					(font
						(size 1.27 1.27)
						(thickness 0.15)
					)
					(justify left bottom)
					(hide yes)
				)
			)
			(property "Description" "SMD Chip Resistor, 330 ohm, ± 1%, 62.5 mW, 0402 [1005 Metric], Thick Film, General Purpose"
				(at 20.32 -30.48 0)
				(effects
					(font
						(size 1.27 1.27)
					)
					(justify left bottom)
					(hide yes)
				)
			)
			(property "MPN" "CR0402-FX-3300GLF"
				(at 20.32 -20.32 0)
				(effects
					(font
						(size 1.27 1.27)
						(thickness 0.15)
					)
					(justify left bottom)
					(hide yes)
				)
			)
			(property "Manufacturer" "Bourns"
				(at 20.32 -22.86 0)
				(effects
					(font
						(size 1.27 1.27)
						(thickness 0.15)
					)
					(justify left bottom)
					(hide yes)
				)
			)
			(property "License" "Apache-2.0"
				(at 20.32 -25.4 0)
				(effects
					(font
						(size 1.27 1.27)
						(thickness 0.15)
					)
					(justify left bottom)
					(hide yes)
				)
			)
			(property "Author" "Antmicro"
				(at 20.32 -27.94 0)
				(effects
					(font
						(size 1.27 1.27)
						(thickness 0.15)
					)
					(justify left bottom)
					(hide yes)
				)
			)
			(property "Val" "330R"
				(at 20.32 -7.62 0)
				(effects
					(font
						(size 1.27 1.27)
						(thickness 0.15)
					)
					(justify left bottom)
				)
			)
			(property "Tolerance" "1%"
				(at 20.32 -10.16 0)
				(effects
					(font
						(size 1.27 1.27)
					)
					(justify left bottom)
					(hide yes)
				)
			)
			(property "ki_keywords" "0402, SMT, RESISTOR, PASSIVE"
				(at 0 0 0)
				(effects
					(font
						(size 1.27 1.27)
					)
					(hide yes)
				)
			)
			(symbol "R_330R_0402_0_1"
				(rectangle
					(start 0.635 0.889)
					(end 4.445 -0.889)
					(stroke
						(width 0.254)
						(type default)
					)
					(fill
						(type none)
					)
				)
			)
			(symbol "R_330R_0402_1_1"
				(pin passive line
					(at 0 0 0)
					(length 0.635)
					(name "~"
						(effects
							(font
								(size 1.27 1.27)
							)
						)
					)
					(number "1"
						(effects
							(font
								(size 1.27 1.27)
							)
						)
					)
				)
				(pin passive line
					(at 5.08 0 180)
					(length 0.635)
					(name "~"
						(effects
							(font
								(size 1.27 1.27)
							)
						)
					)
					(number "2"
						(effects
							(font
								(size 1.27 1.27)
							)
						)
					)
				)
			)
		)
	(symbol "antmicroResistors0402:R_357k_0402"
			(pin_numbers
				(hide yes)
			)
			(pin_names
				(hide yes)
			)
			(exclude_from_sim no)
			(in_bom yes)
			(on_board yes)
			(property "Reference" "R"
				(at 20.32 -5.08 0)
				(effects
					(font
						(size 1.27 1.27)
						(thickness 0.15)
					)
					(justify left bottom)
				)
			)
			(property "Value" "R_357k_0402"
				(at 20.32 -12.7 0)
				(effects
					(font
						(size 1.27 1.27)
						(thickness 0.15)
					)
					(justify left bottom)
					(hide yes)
				)
			)
			(property "Footprint" "antmicro-footprints:R_0402_1005Metric"
				(at 20.32 -15.24 0)
				(effects
					(font
						(size 1.27 1.27)
						(thickness 0.15)
					)
					(justify left bottom)
					(hide yes)
				)
			)
			(property "Datasheet" "https://www.bourns.com/docs/product-datasheets/cr.pdf"
				(at 20.32 -17.78 0)
				(effects
					(font
						(size 1.27 1.27)
						(thickness 0.15)
					)
					(justify left bottom)
					(hide yes)
				)
			)
			(property "Description" "SMD Chip Resistor"
				(at 20.32 -30.48 0)
				(effects
					(font
						(size 1.27 1.27)
					)
					(justify left bottom)
					(hide yes)
				)
			)
			(property "MPN" "CR0402-FX-3573GLF"
				(at 20.32 -20.32 0)
				(effects
					(font
						(size 1.27 1.27)
						(thickness 0.15)
					)
					(justify left bottom)
					(hide yes)
				)
			)
			(property "Manufacturer" "Bourns"
				(at 20.32 -22.86 0)
				(effects
					(font
						(size 1.27 1.27)
						(thickness 0.15)
					)
					(justify left bottom)
					(hide yes)
				)
			)
			(property "License" "Apache-2.0"
				(at 20.32 -25.4 0)
				(effects
					(font
						(size 1.27 1.27)
						(thickness 0.15)
					)
					(justify left bottom)
					(hide yes)
				)
			)
			(property "Author" "Antmicro"
				(at 20.32 -27.94 0)
				(effects
					(font
						(size 1.27 1.27)
						(thickness 0.15)
					)
					(justify left bottom)
					(hide yes)
				)
			)
			(property "Val" "357k"
				(at 20.32 -7.62 0)
				(effects
					(font
						(size 1.27 1.27)
						(thickness 0.15)
					)
					(justify left bottom)
				)
			)
			(property "Tolerance" "1%"
				(at 20.32 -10.16 0)
				(effects
					(font
						(size 1.27 1.27)
					)
					(justify left bottom)
					(hide yes)
				)
			)
			(property "ki_keywords" "0402, SMT, RESISTOR, PASSIVE"
				(at 0 0 0)
				(effects
					(font
						(size 1.27 1.27)
					)
					(hide yes)
				)
			)
			(symbol "R_357k_0402_0_1"
				(rectangle
					(start 0.635 0.889)
					(end 4.445 -0.889)
					(stroke
						(width 0.254)
						(type default)
					)
					(fill
						(type none)
					)
				)
			)
			(symbol "R_357k_0402_1_1"
				(pin passive line
					(at 0 0 0)
					(length 0.635)
					(name "~"
						(effects
							(font
								(size 1.27 1.27)
							)
						)
					)
					(number "1"
						(effects
							(font
								(size 1.27 1.27)
							)
						)
					)
				)
				(pin passive line
					(at 5.08 0 180)
					(length 0.635)
					(name "~"
						(effects
							(font
								(size 1.27 1.27)
							)
						)
					)
					(number "2"
						(effects
							(font
								(size 1.27 1.27)
							)
						)
					)
				)
			)
		)
	(symbol "antmicroResistors0402:R_453k_0402"
			(pin_numbers
				(hide yes)
			)
			(pin_names
				(hide yes)
			)
			(exclude_from_sim no)
			(in_bom yes)
			(on_board yes)
			(property "Reference" "R"
				(at 20.32 -5.08 0)
				(effects
					(font
						(size 1.27 1.27)
						(thickness 0.15)
					)
					(justify left bottom)
				)
			)
			(property "Value" "R_453k_0402"
				(at 20.32 -12.7 0)
				(effects
					(font
						(size 1.27 1.27)
						(thickness 0.15)
					)
					(justify left bottom)
					(hide yes)
				)
			)
			(property "Footprint" "antmicro-footprints:R_0402_1005Metric"
				(at 20.32 -15.24 0)
				(effects
					(font
						(size 1.27 1.27)
						(thickness 0.15)
					)
					(justify left bottom)
					(hide yes)
				)
			)
			(property "Datasheet" "https://www.bourns.com/docs/product-datasheets/cr.pdf"
				(at 20.32 -17.78 0)
				(effects
					(font
						(size 1.27 1.27)
						(thickness 0.15)
					)
					(justify left bottom)
					(hide yes)
				)
			)
			(property "Description" "SMD Chip Resistor"
				(at 20.32 -30.48 0)
				(effects
					(font
						(size 1.27 1.27)
					)
					(justify left bottom)
					(hide yes)
				)
			)
			(property "MPN" "CR0402-FX-4533GLF"
				(at 20.32 -20.32 0)
				(effects
					(font
						(size 1.27 1.27)
						(thickness 0.15)
					)
					(justify left bottom)
					(hide yes)
				)
			)
			(property "Manufacturer" "Bourns"
				(at 20.32 -22.86 0)
				(effects
					(font
						(size 1.27 1.27)
						(thickness 0.15)
					)
					(justify left bottom)
					(hide yes)
				)
			)
			(property "License" "Apache-2.0"
				(at 20.32 -25.4 0)
				(effects
					(font
						(size 1.27 1.27)
						(thickness 0.15)
					)
					(justify left bottom)
					(hide yes)
				)
			)
			(property "Author" "Antmicro"
				(at 20.32 -27.94 0)
				(effects
					(font
						(size 1.27 1.27)
						(thickness 0.15)
					)
					(justify left bottom)
					(hide yes)
				)
			)
			(property "Val" "453k"
				(at 20.32 -7.62 0)
				(effects
					(font
						(size 1.27 1.27)
						(thickness 0.15)
					)
					(justify left bottom)
				)
			)
			(property "Tolerance" "1%"
				(at 20.32 -10.16 0)
				(effects
					(font
						(size 1.27 1.27)
					)
					(justify left bottom)
					(hide yes)
				)
			)
			(property "ki_keywords" "0402, SMT, RESISTOR, PASSIVE"
				(at 0 0 0)
				(effects
					(font
						(size 1.27 1.27)
					)
					(hide yes)
				)
			)
			(symbol "R_453k_0402_0_1"
				(rectangle
					(start 0.635 0.889)
					(end 4.445 -0.889)
					(stroke
						(width 0.254)
						(type default)
					)
					(fill
						(type none)
					)
				)
			)
			(symbol "R_453k_0402_1_1"
				(pin passive line
					(at 0 0 0)
					(length 0.635)
					(name "~"
						(effects
							(font
								(size 1.27 1.27)
							)
						)
					)
					(number "1"
						(effects
							(font
								(size 1.27 1.27)
							)
						)
					)
				)
				(pin passive line
					(at 5.08 0 180)
					(length 0.635)
					(name "~"
						(effects
							(font
								(size 1.27 1.27)
							)
						)
					)
					(number "2"
						(effects
							(font
								(size 1.27 1.27)
							)
						)
					)
				)
			)
		)
	(symbol "antmicroResistors0402:R_47k_0402"
			(pin_numbers
				(hide yes)
			)
			(pin_names
				(hide yes)
			)
			(exclude_from_sim no)
			(in_bom yes)
			(on_board yes)
			(property "Reference" "R"
				(at 20.32 -5.08 0)
				(effects
					(font
						(size 1.27 1.27)
						(thickness 0.15)
					)
					(justify left bottom)
				)
			)
			(property "Value" "R_47k_0402"
				(at 20.32 -12.7 0)
				(effects
					(font
						(size 1.27 1.27)
						(thickness 0.15)
					)
					(justify left bottom)
					(hide yes)
				)
			)
			(property "Footprint" "antmicro-footprints:R_0402_1005Metric"
				(at 20.32 -15.24 0)
				(effects
					(font
						(size 1.27 1.27)
						(thickness 0.15)
					)
					(justify left bottom)
					(hide yes)
				)
			)
			(property "Datasheet" "https://www.bourns.com/docs/product-datasheets/cr.pdf"
				(at 20.32 -17.78 0)
				(effects
					(font
						(size 1.27 1.27)
						(thickness 0.15)
					)
					(justify left bottom)
					(hide yes)
				)
			)
			(property "Description" "SMD Chip Resistor, 47 kohm, ± 1%, 62.5 mW, 0402 [1005 Metric], Thick Film, General Purpose"
				(at 20.32 -30.48 0)
				(effects
					(font
						(size 1.27 1.27)
					)
					(justify left bottom)
					(hide yes)
				)
			)
			(property "MPN" "CR0402-FX-4702GLF"
				(at 20.32 -20.32 0)
				(effects
					(font
						(size 1.27 1.27)
						(thickness 0.15)
					)
					(justify left bottom)
					(hide yes)
				)
			)
			(property "Manufacturer" "Bourns"
				(at 20.32 -22.86 0)
				(effects
					(font
						(size 1.27 1.27)
						(thickness 0.15)
					)
					(justify left bottom)
					(hide yes)
				)
			)
			(property "License" "Apache-2.0"
				(at 20.32 -25.4 0)
				(effects
					(font
						(size 1.27 1.27)
						(thickness 0.15)
					)
					(justify left bottom)
					(hide yes)
				)
			)
			(property "Author" "Antmicro"
				(at 20.32 -27.94 0)
				(effects
					(font
						(size 1.27 1.27)
						(thickness 0.15)
					)
					(justify left bottom)
					(hide yes)
				)
			)
			(property "Val" "47k"
				(at 20.32 -7.62 0)
				(effects
					(font
						(size 1.27 1.27)
						(thickness 0.15)
					)
					(justify left bottom)
				)
			)
			(property "Tolerance" "1%"
				(at 20.32 -10.16 0)
				(effects
					(font
						(size 1.27 1.27)
					)
					(justify left bottom)
					(hide yes)
				)
			)
			(property "ki_keywords" "0402, SMT, RESISTOR, PASSIVE"
				(at 0 0 0)
				(effects
					(font
						(size 1.27 1.27)
					)
					(hide yes)
				)
			)
			(symbol "R_47k_0402_0_1"
				(rectangle
					(start 0.635 0.889)
					(end 4.445 -0.889)
					(stroke
						(width 0.254)
						(type default)
					)
					(fill
						(type none)
					)
				)
			)
			(symbol "R_47k_0402_1_1"
				(pin passive line
					(at 0 0 0)
					(length 0.635)
					(name "~"
						(effects
							(font
								(size 1.27 1.27)
							)
						)
					)
					(number "1"
						(effects
							(font
								(size 1.27 1.27)
							)
						)
					)
				)
				(pin passive line
					(at 5.08 0 180)
					(length 0.635)
					(name "~"
						(effects
							(font
								(size 1.27 1.27)
							)
						)
					)
					(number "2"
						(effects
							(font
								(size 1.27 1.27)
							)
						)
					)
				)
			)
		)
	(symbol "antmicroResistors0402:R_49R9_0402"
			(pin_numbers
				(hide yes)
			)
			(pin_names
				(hide yes)
			)
			(exclude_from_sim no)
			(in_bom yes)
			(on_board yes)
			(property "Reference" "R"
				(at 20.32 -5.08 0)
				(effects
					(font
						(size 1.27 1.27)
						(thickness 0.15)
					)
					(justify left bottom)
				)
			)
			(property "Value" "R_49R9_0402"
				(at 20.32 -12.7 0)
				(effects
					(font
						(size 1.27 1.27)
						(thickness 0.15)
					)
					(justify left bottom)
					(hide yes)
				)
			)
			(property "Footprint" "antmicro-footprints:R_0402_1005Metric"
				(at 20.32 -15.24 0)
				(effects
					(font
						(size 1.27 1.27)
						(thickness 0.15)
					)
					(justify left bottom)
					(hide yes)
				)
			)
			(property "Datasheet" "https://www.bourns.com/docs/product-datasheets/cr.pdf"
				(at 20.32 -17.78 0)
				(effects
					(font
						(size 1.27 1.27)
						(thickness 0.15)
					)
					(justify left bottom)
					(hide yes)
				)
			)
			(property "Description" "SMD Chip Resistor, 49.9 ohm, ± 1%, 62.5 mW, 0402 [1005 Metric], Thick Film, General Purpose"
				(at 20.32 -30.48 0)
				(effects
					(font
						(size 1.27 1.27)
					)
					(justify left bottom)
					(hide yes)
				)
			)
			(property "MPN" "CR0402-FX-49R9GLF"
				(at 20.32 -20.32 0)
				(effects
					(font
						(size 1.27 1.27)
						(thickness 0.15)
					)
					(justify left bottom)
					(hide yes)
				)
			)
			(property "Manufacturer" "Bourns"
				(at 20.32 -22.86 0)
				(effects
					(font
						(size 1.27 1.27)
						(thickness 0.15)
					)
					(justify left bottom)
					(hide yes)
				)
			)
			(property "License" "Apache-2.0"
				(at 20.32 -25.4 0)
				(effects
					(font
						(size 1.27 1.27)
						(thickness 0.15)
					)
					(justify left bottom)
					(hide yes)
				)
			)
			(property "Author" "Antmicro"
				(at 20.32 -27.94 0)
				(effects
					(font
						(size 1.27 1.27)
						(thickness 0.15)
					)
					(justify left bottom)
					(hide yes)
				)
			)
			(property "Val" "49R9"
				(at 20.32 -7.62 0)
				(effects
					(font
						(size 1.27 1.27)
						(thickness 0.15)
					)
					(justify left bottom)
				)
			)
			(property "Tolerance" "1%"
				(at 20.32 -10.16 0)
				(effects
					(font
						(size 1.27 1.27)
					)
					(justify left bottom)
					(hide yes)
				)
			)
			(property "ki_keywords" "0402, SMT, RESISTOR, PASSIVE"
				(at 0 0 0)
				(effects
					(font
						(size 1.27 1.27)
					)
					(hide yes)
				)
			)
			(symbol "R_49R9_0402_0_1"
				(rectangle
					(start 0.635 0.889)
					(end 4.445 -0.889)
					(stroke
						(width 0.254)
						(type default)
					)
					(fill
						(type none)
					)
				)
			)
			(symbol "R_49R9_0402_1_1"
				(pin passive line
					(at 0 0 0)
					(length 0.635)
					(name "~"
						(effects
							(font
								(size 1.27 1.27)
							)
						)
					)
					(number "1"
						(effects
							(font
								(size 1.27 1.27)
							)
						)
					)
				)
				(pin passive line
					(at 5.08 0 180)
					(length 0.635)
					(name "~"
						(effects
							(font
								(size 1.27 1.27)
							)
						)
					)
					(number "2"
						(effects
							(font
								(size 1.27 1.27)
							)
						)
					)
				)
			)
		)
	(symbol "antmicroResistors0402:R_4k7_0402"
			(pin_numbers
				(hide yes)
			)
			(pin_names
				(hide yes)
			)
			(exclude_from_sim no)
			(in_bom yes)
			(on_board yes)
			(property "Reference" "R"
				(at 20.32 -5.08 0)
				(effects
					(font
						(size 1.27 1.27)
						(thickness 0.15)
					)
					(justify left bottom)
				)
			)
			(property "Value" "R_4k7_0402"
				(at 20.32 -12.7 0)
				(effects
					(font
						(size 1.27 1.27)
						(thickness 0.15)
					)
					(justify left bottom)
					(hide yes)
				)
			)
			(property "Footprint" "antmicro-footprints:R_0402_1005Metric"
				(at 20.32 -15.24 0)
				(effects
					(font
						(size 1.27 1.27)
						(thickness 0.15)
					)
					(justify left bottom)
					(hide yes)
				)
			)
			(property "Datasheet" "https://www.bourns.com/docs/product-datasheets/cr.pdf"
				(at 20.32 -17.78 0)
				(effects
					(font
						(size 1.27 1.27)
						(thickness 0.15)
					)
					(justify left bottom)
					(hide yes)
				)
			)
			(property "Description" "SMD Chip Resistor, 4.7 kohm, ± 1%, 62.5 mW, 0402 [1005 Metric], Thick Film, General Purpose"
				(at 20.32 -30.48 0)
				(effects
					(font
						(size 1.27 1.27)
					)
					(justify left bottom)
					(hide yes)
				)
			)
			(property "MPN" "CR0402-FX-4701GLF"
				(at 20.32 -20.32 0)
				(effects
					(font
						(size 1.27 1.27)
						(thickness 0.15)
					)
					(justify left bottom)
					(hide yes)
				)
			)
			(property "Manufacturer" "Bourns"
				(at 20.32 -22.86 0)
				(effects
					(font
						(size 1.27 1.27)
						(thickness 0.15)
					)
					(justify left bottom)
					(hide yes)
				)
			)
			(property "License" "Apache-2.0"
				(at 20.32 -25.4 0)
				(effects
					(font
						(size 1.27 1.27)
						(thickness 0.15)
					)
					(justify left bottom)
					(hide yes)
				)
			)
			(property "Author" "Antmicro"
				(at 20.32 -27.94 0)
				(effects
					(font
						(size 1.27 1.27)
						(thickness 0.15)
					)
					(justify left bottom)
					(hide yes)
				)
			)
			(property "Val" "4k7"
				(at 20.32 -7.62 0)
				(effects
					(font
						(size 1.27 1.27)
						(thickness 0.15)
					)
					(justify left bottom)
				)
			)
			(property "Tolerance" "1%"
				(at 20.32 -10.16 0)
				(effects
					(font
						(size 1.27 1.27)
					)
					(justify left bottom)
					(hide yes)
				)
			)
			(property "ki_keywords" "0402, SMT, RESISTOR, PASSIVE"
				(at 0 0 0)
				(effects
					(font
						(size 1.27 1.27)
					)
					(hide yes)
				)
			)
			(symbol "R_4k7_0402_0_1"
				(rectangle
					(start 0.635 0.889)
					(end 4.445 -0.889)
					(stroke
						(width 0.254)
						(type default)
					)
					(fill
						(type none)
					)
				)
			)
			(symbol "R_4k7_0402_1_1"
				(pin passive line
					(at 0 0 0)
					(length 0.635)
					(name "~"
						(effects
							(font
								(size 1.27 1.27)
							)
						)
					)
					(number "1"
						(effects
							(font
								(size 1.27 1.27)
							)
						)
					)
				)
				(pin passive line
					(at 5.08 0 180)
					(length 0.635)
					(name "~"
						(effects
							(font
								(size 1.27 1.27)
							)
						)
					)
					(number "2"
						(effects
							(font
								(size 1.27 1.27)
							)
						)
					)
				)
			)
		)
	(symbol "antmicroResistors0402:R_51R_0402"
			(pin_numbers
				(hide yes)
			)
			(pin_names
				(hide yes)
			)
			(exclude_from_sim no)
			(in_bom yes)
			(on_board yes)
			(property "Reference" "R"
				(at 20.32 -5.08 0)
				(effects
					(font
						(size 1.27 1.27)
						(thickness 0.15)
					)
					(justify left bottom)
				)
			)
			(property "Value" "R_51R_0402"
				(at 20.32 -12.7 0)
				(effects
					(font
						(size 1.27 1.27)
						(thickness 0.15)
					)
					(justify left bottom)
					(hide yes)
				)
			)
			(property "Footprint" "antmicro-footprints:R_0402_1005Metric"
				(at 20.32 -15.24 0)
				(effects
					(font
						(size 1.27 1.27)
						(thickness 0.15)
					)
					(justify left bottom)
					(hide yes)
				)
			)
			(property "Datasheet" "https://www.bourns.com/docs/product-datasheets/cr.pdf"
				(at 20.32 -17.78 0)
				(effects
					(font
						(size 1.27 1.27)
						(thickness 0.15)
					)
					(justify left bottom)
					(hide yes)
				)
			)
			(property "Description" "SMD Chip Resistor, 51 ohm, ± 1%, 63 mW, 0402 [1005 Metric], Thick Film, General Purpose"
				(at 20.32 -30.48 0)
				(effects
					(font
						(size 1.27 1.27)
					)
					(justify left bottom)
					(hide yes)
				)
			)
			(property "MPN" "CR0402-FX-51R0GLF"
				(at 20.32 -20.32 0)
				(effects
					(font
						(size 1.27 1.27)
						(thickness 0.15)
					)
					(justify left bottom)
					(hide yes)
				)
			)
			(property "Manufacturer" "Bourns"
				(at 20.32 -22.86 0)
				(effects
					(font
						(size 1.27 1.27)
						(thickness 0.15)
					)
					(justify left bottom)
					(hide yes)
				)
			)
			(property "License" "Apache-2.0"
				(at 20.32 -25.4 0)
				(effects
					(font
						(size 1.27 1.27)
						(thickness 0.15)
					)
					(justify left bottom)
					(hide yes)
				)
			)
			(property "Author" "Antmicro"
				(at 20.32 -27.94 0)
				(effects
					(font
						(size 1.27 1.27)
						(thickness 0.15)
					)
					(justify left bottom)
					(hide yes)
				)
			)
			(property "Val" "51R"
				(at 20.32 -7.62 0)
				(effects
					(font
						(size 1.27 1.27)
						(thickness 0.15)
					)
					(justify left bottom)
				)
			)
			(property "Tolerance" "1%"
				(at 20.32 -10.16 0)
				(effects
					(font
						(size 1.27 1.27)
					)
					(justify left bottom)
					(hide yes)
				)
			)
			(property "ki_keywords" "0402, SMT, RESISTOR, PASSIVE"
				(at 0 0 0)
				(effects
					(font
						(size 1.27 1.27)
					)
					(hide yes)
				)
			)
			(symbol "R_51R_0402_0_1"
				(rectangle
					(start 0.635 0.889)
					(end 4.445 -0.889)
					(stroke
						(width 0.254)
						(type default)
					)
					(fill
						(type none)
					)
				)
			)
			(symbol "R_51R_0402_1_1"
				(pin passive line
					(at 0 0 0)
					(length 0.635)
					(name "~"
						(effects
							(font
								(size 1.27 1.27)
							)
						)
					)
					(number "1"
						(effects
							(font
								(size 1.27 1.27)
							)
						)
					)
				)
				(pin passive line
					(at 5.08 0 180)
					(length 0.635)
					(name "~"
						(effects
							(font
								(size 1.27 1.27)
							)
						)
					)
					(number "2"
						(effects
							(font
								(size 1.27 1.27)
							)
						)
					)
				)
			)
		)
	(symbol "antmicroResistors0402:R_53k6_0402"
			(pin_numbers
				(hide yes)
			)
			(pin_names
				(hide yes)
			)
			(exclude_from_sim no)
			(in_bom yes)
			(on_board yes)
			(property "Reference" "R"
				(at 20.32 -5.08 0)
				(effects
					(font
						(size 1.27 1.27)
						(thickness 0.15)
					)
					(justify left bottom)
				)
			)
			(property "Value" "R_53k6_0402"
				(at 20.32 -12.7 0)
				(effects
					(font
						(size 1.27 1.27)
						(thickness 0.15)
					)
					(justify left bottom)
					(hide yes)
				)
			)
			(property "Footprint" "antmicro-footprints:R_0402_1005Metric"
				(at 20.32 -15.24 0)
				(effects
					(font
						(size 1.27 1.27)
						(thickness 0.15)
					)
					(justify left bottom)
					(hide yes)
				)
			)
			(property "Datasheet" "https://www.bourns.com/docs/product-datasheets/cr.pdf"
				(at 20.32 -17.78 0)
				(effects
					(font
						(size 1.27 1.27)
						(thickness 0.15)
					)
					(justify left bottom)
					(hide yes)
				)
			)
			(property "Description" "SMD Chip Resistor"
				(at 20.32 -30.48 0)
				(effects
					(font
						(size 1.27 1.27)
					)
					(justify left bottom)
					(hide yes)
				)
			)
			(property "MPN" "CR0402-FX-5362GLF"
				(at 20.32 -20.32 0)
				(effects
					(font
						(size 1.27 1.27)
						(thickness 0.15)
					)
					(justify left bottom)
					(hide yes)
				)
			)
			(property "Manufacturer" "Bourns"
				(at 20.32 -22.86 0)
				(effects
					(font
						(size 1.27 1.27)
						(thickness 0.15)
					)
					(justify left bottom)
					(hide yes)
				)
			)
			(property "License" "Apache-2.0"
				(at 20.32 -25.4 0)
				(effects
					(font
						(size 1.27 1.27)
						(thickness 0.15)
					)
					(justify left bottom)
					(hide yes)
				)
			)
			(property "Author" "Antmicro"
				(at 20.32 -27.94 0)
				(effects
					(font
						(size 1.27 1.27)
						(thickness 0.15)
					)
					(justify left bottom)
					(hide yes)
				)
			)
			(property "Val" "53k6"
				(at 20.32 -7.62 0)
				(effects
					(font
						(size 1.27 1.27)
						(thickness 0.15)
					)
					(justify left bottom)
				)
			)
			(property "Tolerance" "1%"
				(at 20.32 -10.16 0)
				(effects
					(font
						(size 1.27 1.27)
					)
					(justify left bottom)
					(hide yes)
				)
			)
			(property "ki_keywords" "0402, SMT, RESISTOR, PASSIVE"
				(at 0 0 0)
				(effects
					(font
						(size 1.27 1.27)
					)
					(hide yes)
				)
			)
			(symbol "R_53k6_0402_0_1"
				(rectangle
					(start 0.635 0.889)
					(end 4.445 -0.889)
					(stroke
						(width 0.254)
						(type default)
					)
					(fill
						(type none)
					)
				)
			)
			(symbol "R_53k6_0402_1_1"
				(pin passive line
					(at 0 0 0)
					(length 0.635)
					(name "~"
						(effects
							(font
								(size 1.27 1.27)
							)
						)
					)
					(number "1"
						(effects
							(font
								(size 1.27 1.27)
							)
						)
					)
				)
				(pin passive line
					(at 5.08 0 180)
					(length 0.635)
					(name "~"
						(effects
							(font
								(size 1.27 1.27)
							)
						)
					)
					(number "2"
						(effects
							(font
								(size 1.27 1.27)
							)
						)
					)
				)
			)
		)
	(symbol "antmicroResistors0402:R_66k5_0402"
			(pin_numbers
				(hide yes)
			)
			(pin_names
				(hide yes)
			)
			(exclude_from_sim no)
			(in_bom yes)
			(on_board yes)
			(property "Reference" "R"
				(at 20.32 -5.08 0)
				(effects
					(font
						(size 1.27 1.27)
						(thickness 0.15)
					)
					(justify left bottom)
				)
			)
			(property "Value" "R_66k5_0402"
				(at 20.32 -12.7 0)
				(effects
					(font
						(size 1.27 1.27)
						(thickness 0.15)
					)
					(justify left bottom)
					(hide yes)
				)
			)
			(property "Footprint" "antmicro-footprints:R_0402_1005Metric"
				(at 20.32 -15.24 0)
				(effects
					(font
						(size 1.27 1.27)
						(thickness 0.15)
					)
					(justify left bottom)
					(hide yes)
				)
			)
			(property "Datasheet" "https://www.bourns.com/docs/product-datasheets/cr.pdf"
				(at 20.32 -17.78 0)
				(effects
					(font
						(size 1.27 1.27)
						(thickness 0.15)
					)
					(justify left bottom)
					(hide yes)
				)
			)
			(property "Description" "SMD Chip Resistor"
				(at 20.32 -30.48 0)
				(effects
					(font
						(size 1.27 1.27)
					)
					(justify left bottom)
					(hide yes)
				)
			)
			(property "MPN" "CR0402-FX-6652GLF"
				(at 20.32 -20.32 0)
				(effects
					(font
						(size 1.27 1.27)
						(thickness 0.15)
					)
					(justify left bottom)
					(hide yes)
				)
			)
			(property "Manufacturer" "Bourns"
				(at 20.32 -22.86 0)
				(effects
					(font
						(size 1.27 1.27)
						(thickness 0.15)
					)
					(justify left bottom)
					(hide yes)
				)
			)
			(property "License" "Apache-2.0"
				(at 20.32 -25.4 0)
				(effects
					(font
						(size 1.27 1.27)
						(thickness 0.15)
					)
					(justify left bottom)
					(hide yes)
				)
			)
			(property "Author" "Antmicro"
				(at 20.32 -27.94 0)
				(effects
					(font
						(size 1.27 1.27)
						(thickness 0.15)
					)
					(justify left bottom)
					(hide yes)
				)
			)
			(property "Val" "66k5"
				(at 20.32 -7.62 0)
				(effects
					(font
						(size 1.27 1.27)
						(thickness 0.15)
					)
					(justify left bottom)
				)
			)
			(property "Tolerance" "1%"
				(at 20.32 -10.16 0)
				(effects
					(font
						(size 1.27 1.27)
					)
					(justify left bottom)
					(hide yes)
				)
			)
			(property "ki_keywords" "0402, SMT, RESISTOR, PASSIVE"
				(at 0 0 0)
				(effects
					(font
						(size 1.27 1.27)
					)
					(hide yes)
				)
			)
			(symbol "R_66k5_0402_0_1"
				(rectangle
					(start 0.635 0.889)
					(end 4.445 -0.889)
					(stroke
						(width 0.254)
						(type default)
					)
					(fill
						(type none)
					)
				)
			)
			(symbol "R_66k5_0402_1_1"
				(pin passive line
					(at 0 0 0)
					(length 0.635)
					(name "~"
						(effects
							(font
								(size 1.27 1.27)
							)
						)
					)
					(number "1"
						(effects
							(font
								(size 1.27 1.27)
							)
						)
					)
				)
				(pin passive line
					(at 5.08 0 180)
					(length 0.635)
					(name "~"
						(effects
							(font
								(size 1.27 1.27)
							)
						)
					)
					(number "2"
						(effects
							(font
								(size 1.27 1.27)
							)
						)
					)
				)
			)
		)
	(symbol "antmicroResistors0603:R_0R_0603"
			(pin_numbers
				(hide yes)
			)
			(pin_names
				(hide yes)
			)
			(exclude_from_sim no)
			(in_bom yes)
			(on_board yes)
			(property "Reference" "R"
				(at 20.32 -5.08 0)
				(effects
					(font
						(size 1.27 1.27)
						(thickness 0.15)
					)
					(justify left bottom)
				)
			)
			(property "Value" "R_0R_0603"
				(at 20.32 -12.7 0)
				(effects
					(font
						(size 1.27 1.27)
						(thickness 0.15)
					)
					(justify left bottom)
					(hide yes)
				)
			)
			(property "Footprint" "antmicro-footprints:R_0603_1608Metric"
				(at 20.32 -15.24 0)
				(effects
					(font
						(size 1.27 1.27)
						(thickness 0.15)
					)
					(justify left bottom)
					(hide yes)
				)
			)
			(property "Datasheet" "https://www.bourns.com/docs/product-datasheets/cr.pdf?sfvrsn=574d41f6_14"
				(at 20.32 -17.78 0)
				(effects
					(font
						(size 1.27 1.27)
						(thickness 0.15)
					)
					(justify left bottom)
					(hide yes)
				)
			)
			(property "Description" "Zero Ohm Resistor, Jumper, 0603 [1608 Metric], Thick Film, 100 mW, 1 A, Surface Mount Device, CR"
				(at 20.32 -33.02 0)
				(effects
					(font
						(size 1.27 1.27)
					)
					(justify left bottom)
					(hide yes)
				)
			)
			(property "MPN" "CR0603-J/-000ELF"
				(at 20.32 -20.32 0)
				(effects
					(font
						(size 1.27 1.27)
						(thickness 0.15)
					)
					(justify left bottom)
					(hide yes)
				)
			)
			(property "Manufacturer" "Bourns"
				(at 20.32 -22.86 0)
				(effects
					(font
						(size 1.27 1.27)
						(thickness 0.15)
					)
					(justify left bottom)
					(hide yes)
				)
			)
			(property "License" "Apache-2.0"
				(at 20.32 -25.4 0)
				(effects
					(font
						(size 1.27 1.27)
						(thickness 0.15)
					)
					(justify left bottom)
					(hide yes)
				)
			)
			(property "Author" "Antmicro"
				(at 20.32 -27.94 0)
				(effects
					(font
						(size 1.27 1.27)
						(thickness 0.15)
					)
					(justify left bottom)
					(hide yes)
				)
			)
			(property "Val" "0R"
				(at 20.32 -7.62 0)
				(effects
					(font
						(size 1.27 1.27)
						(thickness 0.15)
					)
					(justify left bottom)
				)
			)
			(property "Tolerance" "~"
				(at 20.32 -10.16 0)
				(effects
					(font
						(size 1.27 1.27)
					)
					(justify left bottom)
					(hide yes)
				)
			)
			(property "Current" "1A"
				(at 20.32 -30.48 0)
				(effects
					(font
						(size 1.27 1.27)
						(thickness 0.15)
					)
					(justify left bottom)
					(hide yes)
				)
			)
			(property "ki_keywords" "0603, SMT, RESISTOR, PASSIVE"
				(at 0 0 0)
				(effects
					(font
						(size 1.27 1.27)
					)
					(hide yes)
				)
			)
			(symbol "R_0R_0603_0_1"
				(rectangle
					(start 0.635 0.889)
					(end 4.445 -0.889)
					(stroke
						(width 0.254)
						(type default)
					)
					(fill
						(type none)
					)
				)
			)
			(symbol "R_0R_0603_1_1"
				(pin passive line
					(at 0 0 0)
					(length 0.635)
					(name "~"
						(effects
							(font
								(size 1.27 1.27)
							)
						)
					)
					(number "1"
						(effects
							(font
								(size 1.27 1.27)
							)
						)
					)
				)
				(pin passive line
					(at 5.08 0 180)
					(length 0.635)
					(name "~"
						(effects
							(font
								(size 1.27 1.27)
							)
						)
					)
					(number "2"
						(effects
							(font
								(size 1.27 1.27)
							)
						)
					)
				)
			)
		)
	(symbol "antmicroResistorsmisc:R_0R_1206"
			(pin_numbers
				(hide yes)
			)
			(pin_names
				(hide yes)
			)
			(exclude_from_sim no)
			(in_bom yes)
			(on_board yes)
			(property "Reference" "R"
				(at 20.32 -5.08 0)
				(effects
					(font
						(size 1.27 1.27)
						(thickness 0.15)
					)
					(justify left bottom)
				)
			)
			(property "Value" "R_0R_1206"
				(at 20.32 -12.7 0)
				(effects
					(font
						(size 1.27 1.27)
						(thickness 0.15)
					)
					(justify left bottom)
					(hide yes)
				)
			)
			(property "Footprint" "antmicro-footprints:R_1206_3216Metric"
				(at 20.32 -15.24 0)
				(effects
					(font
						(size 1.27 1.27)
						(thickness 0.15)
					)
					(justify left bottom)
					(hide yes)
				)
			)
			(property "Datasheet" "https://www.farnell.com/datasheets/2860635.pdf"
				(at 20.32 -17.78 0)
				(effects
					(font
						(size 1.27 1.27)
						(thickness 0.15)
					)
					(justify left bottom)
					(hide yes)
				)
			)
			(property "Description" "Zero Ohm Resistor, Jumper, 1206 [3216 Metric], Thick Film, 250 mW, 2 A, Surface Mount Device"
				(at 20.32 -33.02 0)
				(effects
					(font
						(size 1.27 1.27)
					)
					(justify left bottom)
					(hide yes)
				)
			)
			(property "MPN" "MCMR12X000_PTL"
				(at 20.32 -20.32 0)
				(effects
					(font
						(size 1.27 1.27)
						(thickness 0.15)
					)
					(justify left bottom)
					(hide yes)
				)
			)
			(property "Manufacturer" "Multicomp Pro"
				(at 20.32 -22.86 0)
				(effects
					(font
						(size 1.27 1.27)
						(thickness 0.15)
					)
					(justify left bottom)
					(hide yes)
				)
			)
			(property "License" "Apache-2.0"
				(at 20.32 -25.4 0)
				(effects
					(font
						(size 1.27 1.27)
						(thickness 0.15)
					)
					(justify left bottom)
					(hide yes)
				)
			)
			(property "Author" "Antmicro"
				(at 20.32 -27.94 0)
				(effects
					(font
						(size 1.27 1.27)
						(thickness 0.15)
					)
					(justify left bottom)
					(hide yes)
				)
			)
			(property "Val" "0R"
				(at 20.32 -7.62 0)
				(effects
					(font
						(size 1.27 1.27)
						(thickness 0.15)
					)
					(justify left bottom)
				)
			)
			(property "Tolerance" "~"
				(at 20.32 -10.16 0)
				(effects
					(font
						(size 1.27 1.27)
					)
					(justify left bottom)
					(hide yes)
				)
			)
			(property "Current" "2A"
				(at 20.32 -30.48 0)
				(effects
					(font
						(size 1.27 1.27)
						(thickness 0.15)
					)
					(justify left bottom)
					(hide yes)
				)
			)
			(property "ki_keywords" "1206, SMT, RESISTOR, PASSIVE"
				(at 0 0 0)
				(effects
					(font
						(size 1.27 1.27)
					)
					(hide yes)
				)
			)
			(symbol "R_0R_1206_0_1"
				(rectangle
					(start 0.635 0.889)
					(end 4.445 -0.889)
					(stroke
						(width 0.254)
						(type default)
					)
					(fill
						(type none)
					)
				)
			)
			(symbol "R_0R_1206_1_1"
				(pin passive line
					(at 0 0 0)
					(length 0.635)
					(name "~"
						(effects
							(font
								(size 1.27 1.27)
							)
						)
					)
					(number "1"
						(effects
							(font
								(size 1.27 1.27)
							)
						)
					)
				)
				(pin passive line
					(at 5.08 0 180)
					(length 0.635)
					(name "~"
						(effects
							(font
								(size 1.27 1.27)
							)
						)
					)
					(number "2"
						(effects
							(font
								(size 1.27 1.27)
							)
						)
					)
				)
			)
		)
	(symbol "antmicroResonators:Resonator_12MHz_ABM8G"
			(pin_names
				(hide yes)
			)
			(exclude_from_sim no)
			(in_bom yes)
			(on_board yes)
			(property "Reference" "Y"
				(at 15.24 -5.08 0)
				(effects
					(font
						(size 1.27 1.27)
						(thickness 0.15)
					)
					(justify left bottom)
				)
			)
			(property "Value" "Resonator_12MHz_ABM8G"
				(at 15.24 -12.7 0)
				(effects
					(font
						(size 1.27 1.27)
						(thickness 0.15)
					)
					(justify left bottom)
					(hide yes)
				)
			)
			(property "Footprint" "antmicro-footprints:Resonator_SMD_Abracon_ABM8G_3.2x2.5mm"
				(at 15.24 -15.24 0)
				(effects
					(font
						(size 1.27 1.27)
						(thickness 0.15)
					)
					(justify left bottom)
					(hide yes)
				)
			)
			(property "Datasheet" "https://abracon.com/Resonators/ABM8G.pdf"
				(at 15.24 -17.78 0)
				(effects
					(font
						(size 1.27 1.27)
						(thickness 0.15)
					)
					(justify left bottom)
					(hide yes)
				)
			)
			(property "Description" "Crystal, 12 MHz, SMT, 3.2mm x 2.5mm, 30 ppm, 18 pF, 20 ppm, ABM8G"
				(at 15.24 -27.94 0)
				(effects
					(font
						(size 1.27 1.27)
					)
					(justify left bottom)
					(hide yes)
				)
			)
			(property "MPN" "ABM8G-12.000MHZ-18-D2Y-T"
				(at 15.24 -7.62 0)
				(effects
					(font
						(size 1.27 1.27)
						(thickness 0.15)
					)
					(justify left bottom)
				)
			)
			(property "Manufacturer" "Abracon"
				(at 15.24 -20.32 0)
				(effects
					(font
						(size 1.27 1.27)
						(thickness 0.15)
					)
					(justify left bottom)
					(hide yes)
				)
			)
			(property "Author" "Antmicro"
				(at 15.24 -22.86 0)
				(effects
					(font
						(size 1.27 1.27)
						(thickness 0.15)
					)
					(justify left bottom)
					(hide yes)
				)
			)
			(property "License" "Apache-2.0"
				(at 15.24 -25.4 0)
				(effects
					(font
						(size 1.27 1.27)
						(thickness 0.15)
					)
					(justify left bottom)
					(hide yes)
				)
			)
			(property "Val" "12 MHz"
				(at 15.24 -10.16 0)
				(effects
					(font
						(size 1.27 1.27)
						(thickness 0.15)
					)
					(justify left bottom)
				)
			)
			(property "ki_keywords" "SMT, CERAMIC, OSCILLATOR"
				(at 0 0 0)
				(effects
					(font
						(size 1.27 1.27)
					)
					(hide yes)
				)
			)
			(symbol "Resonator_12MHz_ABM8G_1_1"
				(polyline
					(pts
						(xy 1.905 1.905) (xy 1.905 2.54) (xy 5.715 2.54) (xy 5.715 1.905)
					)
					(stroke
						(width 0.254)
						(type default)
					)
					(fill
						(type none)
					)
				)
				(polyline
					(pts
						(xy 1.905 -1.905) (xy 1.905 -2.54) (xy 5.715 -2.54) (xy 5.715 -1.905)
					)
					(stroke
						(width 0.254)
						(type default)
					)
					(fill
						(type none)
					)
				)
				(polyline
					(pts
						(xy 2.54 1.27) (xy 2.54 -1.27)
					)
					(stroke
						(width 0.254)
						(type default)
					)
					(fill
						(type background)
					)
				)
				(rectangle
					(start 3.175 1.905)
					(end 4.445 -1.905)
					(stroke
						(width 0.254)
						(type default)
					)
					(fill
						(type background)
					)
				)
				(polyline
					(pts
						(xy 5.08 1.27) (xy 5.08 -1.27)
					)
					(stroke
						(width 0.254)
						(type default)
					)
					(fill
						(type background)
					)
				)
				(pin passive line
					(at 0 0 0)
					(length 2.54)
					(name "~"
						(effects
							(font
								(size 1.27 1.27)
							)
						)
					)
					(number "1"
						(effects
							(font
								(size 1.27 1.27)
							)
						)
					)
				)
				(pin passive line
					(at 3.81 -5.08 90)
					(length 2.54)
					(name "SH"
						(effects
							(font
								(size 1.27 1.27)
							)
						)
					)
					(number "2"
						(effects
							(font
								(size 1.27 1.27)
							)
						)
					)
				)
				(pin passive line
					(at 3.81 -5.08 90)
					(length 2.54)
					(hide yes)
					(name "SH"
						(effects
							(font
								(size 1.27 1.27)
							)
						)
					)
					(number "4"
						(effects
							(font
								(size 1.27 1.27)
							)
						)
					)
				)
				(pin passive line
					(at 7.62 0 180)
					(length 2.54)
					(name "~"
						(effects
							(font
								(size 1.27 1.27)
							)
						)
					)
					(number "3"
						(effects
							(font
								(size 1.27 1.27)
							)
						)
					)
				)
			)
		)
	(symbol "antmicroResonators:Resonator_25MHz_ABM8G"
			(pin_names
				(hide yes)
			)
			(exclude_from_sim no)
			(in_bom yes)
			(on_board yes)
			(property "Reference" "Y"
				(at 15.24 -5.08 0)
				(effects
					(font
						(size 1.27 1.27)
						(thickness 0.15)
					)
					(justify left bottom)
				)
			)
			(property "Value" "Resonator_25MHz_ABM8G"
				(at 15.24 -12.7 0)
				(effects
					(font
						(size 1.27 1.27)
						(thickness 0.15)
					)
					(justify left bottom)
					(hide yes)
				)
			)
			(property "Footprint" "antmicro-footprints:Resonator_SMD_Abracon_ABM8G_3.2x2.5mm"
				(at 15.24 -15.24 0)
				(effects
					(font
						(size 1.27 1.27)
						(thickness 0.15)
					)
					(justify left bottom)
					(hide yes)
				)
			)
			(property "Datasheet" "https://abracon.com/Resonators/ABM8G.pdf"
				(at 15.24 -17.78 0)
				(effects
					(font
						(size 1.27 1.27)
						(thickness 0.15)
					)
					(justify left bottom)
					(hide yes)
				)
			)
			(property "Description" "Crystal, 25 MHz, SMD, 3.2mm x 2.5mm, 30 ppm, 18 pF, 20 ppm, ABM8G"
				(at 15.24 -27.94 0)
				(effects
					(font
						(size 1.27 1.27)
					)
					(justify left bottom)
					(hide yes)
				)
			)
			(property "MPN" "ABM8G-25.000MHZ-18-D2Y-T3"
				(at 15.24 -7.62 0)
				(effects
					(font
						(size 1.27 1.27)
						(thickness 0.15)
					)
					(justify left bottom)
				)
			)
			(property "Manufacturer" "Abracon"
				(at 15.24 -20.32 0)
				(effects
					(font
						(size 1.27 1.27)
						(thickness 0.15)
					)
					(justify left bottom)
					(hide yes)
				)
			)
			(property "Author" "Antmicro"
				(at 15.24 -22.86 0)
				(effects
					(font
						(size 1.27 1.27)
						(thickness 0.15)
					)
					(justify left bottom)
					(hide yes)
				)
			)
			(property "License" "Apache-2.0"
				(at 15.24 -25.4 0)
				(effects
					(font
						(size 1.27 1.27)
						(thickness 0.15)
					)
					(justify left bottom)
					(hide yes)
				)
			)
			(property "Val" "25 MHz"
				(at 15.24 -10.16 0)
				(effects
					(font
						(size 1.27 1.27)
						(thickness 0.15)
					)
					(justify left bottom)
				)
			)
			(property "ki_keywords" "SMT, CERAMIC, OSCILLATOR"
				(at 0 0 0)
				(effects
					(font
						(size 1.27 1.27)
					)
					(hide yes)
				)
			)
			(symbol "Resonator_25MHz_ABM8G_1_1"
				(polyline
					(pts
						(xy 1.905 1.905) (xy 1.905 2.54) (xy 5.715 2.54) (xy 5.715 1.905)
					)
					(stroke
						(width 0.254)
						(type default)
					)
					(fill
						(type none)
					)
				)
				(polyline
					(pts
						(xy 1.905 -1.905) (xy 1.905 -2.54) (xy 5.715 -2.54) (xy 5.715 -1.905)
					)
					(stroke
						(width 0.254)
						(type default)
					)
					(fill
						(type none)
					)
				)
				(polyline
					(pts
						(xy 2.54 1.27) (xy 2.54 -1.27)
					)
					(stroke
						(width 0.254)
						(type default)
					)
					(fill
						(type background)
					)
				)
				(rectangle
					(start 3.175 1.905)
					(end 4.445 -1.905)
					(stroke
						(width 0.254)
						(type default)
					)
					(fill
						(type background)
					)
				)
				(polyline
					(pts
						(xy 5.08 1.27) (xy 5.08 -1.27)
					)
					(stroke
						(width 0.254)
						(type default)
					)
					(fill
						(type background)
					)
				)
				(pin passive line
					(at 0 0 0)
					(length 2.54)
					(name "~"
						(effects
							(font
								(size 1.27 1.27)
							)
						)
					)
					(number "1"
						(effects
							(font
								(size 1.27 1.27)
							)
						)
					)
				)
				(pin passive line
					(at 3.81 -5.08 90)
					(length 2.54)
					(name "SH"
						(effects
							(font
								(size 1.27 1.27)
							)
						)
					)
					(number "2"
						(effects
							(font
								(size 1.27 1.27)
							)
						)
					)
				)
				(pin passive line
					(at 3.81 -5.08 90)
					(length 2.54)
					(hide yes)
					(name "SH"
						(effects
							(font
								(size 1.27 1.27)
							)
						)
					)
					(number "4"
						(effects
							(font
								(size 1.27 1.27)
							)
						)
					)
				)
				(pin passive line
					(at 7.62 0 180)
					(length 2.54)
					(name "~"
						(effects
							(font
								(size 1.27 1.27)
							)
						)
					)
					(number "3"
						(effects
							(font
								(size 1.27 1.27)
							)
						)
					)
				)
			)
		)
	(symbol "antmicroTVSDiodes:SP3011-06UTG"
			(pin_names
				(hide yes)
			)
			(exclude_from_sim no)
			(in_bom yes)
			(on_board yes)
			(property "Reference" "D"
				(at 13.97 -3.81 0)
				(effects
					(font
						(size 1.27 1.27)
						(thickness 0.15)
					)
					(justify left bottom)
				)
			)
			(property "Value" "SP3011-06UTG"
				(at 13.97 -8.89 0)
				(effects
					(font
						(size 1.27 1.27)
						(thickness 0.15)
					)
					(justify left bottom)
					(hide yes)
				)
			)
			(property "Footprint" "antmicro-footprints:USON-14_3.5x1.35_P0.5mm"
				(at 13.97 -11.43 0)
				(effects
					(font
						(size 1.27 1.27)
						(thickness 0.15)
					)
					(justify left bottom)
					(hide yes)
				)
			)
			(property "Datasheet" "https://www.littelfuse.com/media?resourcetype=datasheets&itemid=c9002a97-9994-449b-b722-f45ab5538c7f&filename=littelfuse-tvs-diode-array-sp3011-datasheet"
				(at 13.97 -13.97 0)
				(effects
					(font
						(size 1.27 1.27)
						(thickness 0.15)
					)
					(justify left bottom)
					(hide yes)
				)
			)
			(property "Description" "TVS diode array, 8 kV, USON-14, 6 V, 0.4 pF"
				(at 13.97 -24.13 0)
				(effects
					(font
						(size 1.27 1.27)
					)
					(justify left bottom)
					(hide yes)
				)
			)
			(property "MPN" "SP3011-06UTG"
				(at 13.97 -6.35 0)
				(effects
					(font
						(size 1.27 1.27)
						(thickness 0.15)
					)
					(justify left bottom)
				)
			)
			(property "Manufacturer" "Littelfuse"
				(at 13.97 -16.51 0)
				(effects
					(font
						(size 1.27 1.27)
						(thickness 0.15)
					)
					(justify left bottom)
					(hide yes)
				)
			)
			(property "Author" "Antmicro"
				(at 13.97 -19.05 0)
				(effects
					(font
						(size 1.27 1.27)
						(thickness 0.15)
					)
					(justify left bottom)
					(hide yes)
				)
			)
			(property "License" "Apache-2.0"
				(at 13.97 -21.59 0)
				(effects
					(font
						(size 1.27 1.27)
						(thickness 0.15)
					)
					(justify left bottom)
					(hide yes)
				)
			)
			(property "ki_keywords" "SMT, DIODE, SEMICONDUCTOR, TVS, ESD"
				(at 0 0 0)
				(effects
					(font
						(size 1.27 1.27)
					)
					(hide yes)
				)
			)
			(symbol "SP3011-06UTG_0_0"
				(pin passive line
					(at 0 -5.08 0)
					(length 2.54)
					(name "~"
						(effects
							(font
								(size 1.27 1.27)
							)
						)
					)
					(number "11"
						(effects
							(font
								(size 1.27 1.27)
							)
						)
					)
				)
				(pin passive line
					(at 0 -7.62 0)
					(length 2.54)
					(name "~"
						(effects
							(font
								(size 1.27 1.27)
							)
						)
					)
					(number "12"
						(effects
							(font
								(size 1.27 1.27)
							)
						)
					)
				)
				(pin passive line
					(at 0 -10.16 0)
					(length 2.54)
					(name "~"
						(effects
							(font
								(size 1.27 1.27)
							)
						)
					)
					(number "13"
						(effects
							(font
								(size 1.27 1.27)
							)
						)
					)
				)
				(pin passive line
					(at 0 -12.7 0)
					(length 2.54)
					(name "~"
						(effects
							(font
								(size 1.27 1.27)
							)
						)
					)
					(number "14"
						(effects
							(font
								(size 1.27 1.27)
							)
						)
					)
				)
			)
			(symbol "SP3011-06UTG_1_1"
				(rectangle
					(start 2.54 2.54)
					(end 8.89 -17.78)
					(stroke
						(width 0.254)
						(type default)
					)
					(fill
						(type background)
					)
				)
				(polyline
					(pts
						(xy 2.54 0) (xy 7.62 0)
					)
					(stroke
						(width 0.254)
						(type default)
					)
					(fill
						(type background)
					)
				)
				(polyline
					(pts
						(xy 2.54 -2.54) (xy 7.62 -2.54)
					)
					(stroke
						(width 0.254)
						(type default)
					)
					(fill
						(type background)
					)
				)
				(polyline
					(pts
						(xy 2.54 -5.08) (xy 7.62 -5.08)
					)
					(stroke
						(width 0.254)
						(type default)
					)
					(fill
						(type background)
					)
				)
				(polyline
					(pts
						(xy 2.54 -7.62) (xy 7.62 -7.62)
					)
					(stroke
						(width 0.254)
						(type default)
					)
					(fill
						(type background)
					)
				)
				(polyline
					(pts
						(xy 2.54 -10.16) (xy 7.62 -10.16)
					)
					(stroke
						(width 0.254)
						(type default)
					)
					(fill
						(type background)
					)
				)
				(polyline
					(pts
						(xy 2.54 -12.7) (xy 7.62 -12.7)
					)
					(stroke
						(width 0.254)
						(type default)
					)
					(fill
						(type background)
					)
				)
				(polyline
					(pts
						(xy 4.826 -0.635) (xy 5.08 -0.381) (xy 5.08 0.381) (xy 5.334 0.635)
					)
					(stroke
						(width 0.254)
						(type default)
					)
					(fill
						(type background)
					)
				)
				(polyline
					(pts
						(xy 4.826 -3.175) (xy 5.08 -2.921) (xy 5.08 -2.159) (xy 5.334 -1.905)
					)
					(stroke
						(width 0.254)
						(type default)
					)
					(fill
						(type background)
					)
				)
				(polyline
					(pts
						(xy 4.826 -5.715) (xy 5.08 -5.461) (xy 5.08 -4.699) (xy 5.334 -4.445)
					)
					(stroke
						(width 0.254)
						(type default)
					)
					(fill
						(type background)
					)
				)
				(polyline
					(pts
						(xy 4.826 -8.255) (xy 5.08 -8.001) (xy 5.08 -7.239) (xy 5.334 -6.985)
					)
					(stroke
						(width 0.254)
						(type default)
					)
					(fill
						(type background)
					)
				)
				(polyline
					(pts
						(xy 4.826 -10.795) (xy 5.08 -10.541) (xy 5.08 -9.779) (xy 5.334 -9.525)
					)
					(stroke
						(width 0.254)
						(type default)
					)
					(fill
						(type background)
					)
				)
				(polyline
					(pts
						(xy 4.826 -13.335) (xy 5.08 -13.081) (xy 5.08 -12.319) (xy 5.334 -12.065)
					)
					(stroke
						(width 0.254)
						(type default)
					)
					(fill
						(type background)
					)
				)
				(polyline
					(pts
						(xy 5.08 0) (xy 3.81 -0.635) (xy 3.81 0.635) (xy 5.08 0)
					)
					(stroke
						(width 0.254)
						(type default)
					)
					(fill
						(type background)
					)
				)
				(polyline
					(pts
						(xy 5.08 0) (xy 6.35 -0.635) (xy 6.35 0.635) (xy 5.08 0)
					)
					(stroke
						(width 0.254)
						(type default)
					)
					(fill
						(type background)
					)
				)
				(polyline
					(pts
						(xy 5.08 -2.54) (xy 3.81 -3.175) (xy 3.81 -1.905) (xy 5.08 -2.54)
					)
					(stroke
						(width 0.254)
						(type default)
					)
					(fill
						(type background)
					)
				)
				(polyline
					(pts
						(xy 5.08 -2.54) (xy 6.35 -3.175) (xy 6.35 -1.905) (xy 5.08 -2.54)
					)
					(stroke
						(width 0.254)
						(type default)
					)
					(fill
						(type background)
					)
				)
				(polyline
					(pts
						(xy 5.08 -5.08) (xy 3.81 -5.715) (xy 3.81 -4.445) (xy 5.08 -5.08)
					)
					(stroke
						(width 0.254)
						(type default)
					)
					(fill
						(type background)
					)
				)
				(polyline
					(pts
						(xy 5.08 -5.08) (xy 6.35 -4.445) (xy 6.35 -5.715) (xy 5.08 -5.08)
					)
					(stroke
						(width 0.254)
						(type default)
					)
					(fill
						(type background)
					)
				)
				(polyline
					(pts
						(xy 5.08 -7.62) (xy 3.81 -8.255) (xy 3.81 -6.985) (xy 5.08 -7.62)
					)
					(stroke
						(width 0.254)
						(type default)
					)
					(fill
						(type background)
					)
				)
				(polyline
					(pts
						(xy 5.08 -10.16) (xy 3.81 -10.795) (xy 3.81 -9.525) (xy 5.08 -10.16)
					)
					(stroke
						(width 0.254)
						(type default)
					)
					(fill
						(type background)
					)
				)
				(polyline
					(pts
						(xy 5.08 -10.16) (xy 6.35 -9.525) (xy 6.35 -10.795) (xy 5.08 -10.16)
					)
					(stroke
						(width 0.254)
						(type default)
					)
					(fill
						(type background)
					)
				)
				(polyline
					(pts
						(xy 5.08 -12.7) (xy 3.81 -13.335) (xy 3.81 -12.065) (xy 5.08 -12.7)
					)
					(stroke
						(width 0.254)
						(type default)
					)
					(fill
						(type background)
					)
				)
				(polyline
					(pts
						(xy 6.35 -6.985) (xy 6.35 -8.255) (xy 5.08 -7.62) (xy 6.35 -6.985)
					)
					(stroke
						(width 0.254)
						(type default)
					)
					(fill
						(type background)
					)
				)
				(polyline
					(pts
						(xy 6.35 -12.065) (xy 6.35 -13.335) (xy 5.08 -12.7) (xy 6.35 -12.065)
					)
					(stroke
						(width 0.254)
						(type default)
					)
					(fill
						(type background)
					)
				)
				(polyline
					(pts
						(xy 7.62 0) (xy 7.62 -15.24)
					)
					(stroke
						(width 0.254)
						(type default)
					)
					(fill
						(type background)
					)
				)
				(circle
					(center 7.62 -2.54)
					(radius 0.254)
					(stroke
						(width 0.254)
						(type default)
					)
					(fill
						(type background)
					)
				)
				(circle
					(center 7.62 -5.08)
					(radius 0.254)
					(stroke
						(width 0.254)
						(type default)
					)
					(fill
						(type background)
					)
				)
				(circle
					(center 7.62 -5.08)
					(radius 0.254)
					(stroke
						(width 0.254)
						(type default)
					)
					(fill
						(type background)
					)
				)
				(circle
					(center 7.62 -7.62)
					(radius 0.254)
					(stroke
						(width 0.254)
						(type default)
					)
					(fill
						(type background)
					)
				)
				(circle
					(center 7.62 -10.16)
					(radius 0.254)
					(stroke
						(width 0.254)
						(type default)
					)
					(fill
						(type background)
					)
				)
				(circle
					(center 7.62 -10.16)
					(radius 0.254)
					(stroke
						(width 0.254)
						(type default)
					)
					(fill
						(type background)
					)
				)
				(circle
					(center 7.62 -12.7)
					(radius 0.254)
					(stroke
						(width 0.254)
						(type default)
					)
					(fill
						(type background)
					)
				)
				(polyline
					(pts
						(xy 7.62 -15.24) (xy 2.54 -15.24)
					)
					(stroke
						(width 0.254)
						(type default)
					)
					(fill
						(type background)
					)
				)
				(pin passive line
					(at 0 0 0)
					(length 2.54)
					(hide yes)
					(name "~"
						(effects
							(font
								(size 1.27 1.27)
							)
						)
					)
					(number "7"
						(effects
							(font
								(size 1.27 1.27)
							)
						)
					)
				)
				(pin passive line
					(at 0 0 0)
					(length 2.54)
					(name "~"
						(effects
							(font
								(size 1.27 1.27)
							)
						)
					)
					(number "8"
						(effects
							(font
								(size 1.27 1.27)
							)
						)
					)
				)
				(pin passive line
					(at 0 -2.54 0)
					(length 2.54)
					(hide yes)
					(name "~"
						(effects
							(font
								(size 1.27 1.27)
							)
						)
					)
					(number "6"
						(effects
							(font
								(size 1.27 1.27)
							)
						)
					)
				)
				(pin passive line
					(at 0 -2.54 0)
					(length 2.54)
					(name "~"
						(effects
							(font
								(size 1.27 1.27)
							)
						)
					)
					(number "9"
						(effects
							(font
								(size 1.27 1.27)
							)
						)
					)
				)
				(pin passive line
					(at 0 -5.08 0)
					(length 2.54)
					(hide yes)
					(name "~"
						(effects
							(font
								(size 1.27 1.27)
							)
						)
					)
					(number "4"
						(effects
							(font
								(size 1.27 1.27)
							)
						)
					)
				)
				(pin passive line
					(at 0 -7.62 0)
					(length 2.54)
					(hide yes)
					(name "~"
						(effects
							(font
								(size 1.27 1.27)
							)
						)
					)
					(number "3"
						(effects
							(font
								(size 1.27 1.27)
							)
						)
					)
				)
				(pin passive line
					(at 0 -10.16 0)
					(length 2.54)
					(hide yes)
					(name "~"
						(effects
							(font
								(size 1.27 1.27)
							)
						)
					)
					(number "2"
						(effects
							(font
								(size 1.27 1.27)
							)
						)
					)
				)
				(pin passive line
					(at 0 -12.7 0)
					(length 2.54)
					(hide yes)
					(name "~"
						(effects
							(font
								(size 1.27 1.27)
							)
						)
					)
					(number "1"
						(effects
							(font
								(size 1.27 1.27)
							)
						)
					)
				)
				(pin passive line
					(at 0 -15.24 0)
					(length 2.54)
					(name "~"
						(effects
							(font
								(size 1.27 1.27)
							)
						)
					)
					(number "10"
						(effects
							(font
								(size 1.27 1.27)
							)
						)
					)
				)
				(pin passive line
					(at 0 -15.24 0)
					(length 2.54)
					(hide yes)
					(name "~"
						(effects
							(font
								(size 1.27 1.27)
							)
						)
					)
					(number "5"
						(effects
							(font
								(size 1.27 1.27)
							)
						)
					)
				)
			)
		)
	(symbol "antmicroTVSDiodes:TPD2E009_SOT-9X3"
			(pin_names
				(hide yes)
			)
			(exclude_from_sim no)
			(in_bom yes)
			(on_board yes)
			(property "Reference" "D"
				(at 15.24 0 0)
				(effects
					(font
						(size 1.27 1.27)
						(thickness 0.15)
					)
					(justify left bottom)
				)
			)
			(property "Value" "TPD2E009_SOT-9X3"
				(at 15.24 -10.16 0)
				(effects
					(font
						(size 1.27 1.27)
						(thickness 0.15)
					)
					(justify left bottom)
					(hide yes)
				)
			)
			(property "Footprint" "antmicro-footprints:SOT-723"
				(at 15.24 -5.08 0)
				(effects
					(font
						(size 1.27 1.27)
						(thickness 0.15)
					)
					(justify left bottom)
					(hide yes)
				)
			)
			(property "Datasheet" "https://www.ti.com/lit/ds/symlink/tpd2e009.pdf?ts=1597910439511&ref_url=https%253A%252F%252Fwww.google.com%252F"
				(at 15.24 -7.62 0)
				(effects
					(font
						(size 1.27 1.27)
						(thickness 0.15)
					)
					(justify left bottom)
					(hide yes)
				)
			)
			(property "Description" "TVS diode array, 8 kV, SOT-723, 5.5 V, 0.9 pF"
				(at 15.24 -20.32 0)
				(effects
					(font
						(size 1.27 1.27)
					)
					(justify left bottom)
					(hide yes)
				)
			)
			(property "MPN" "TPD2E009DRTR"
				(at 15.24 -2.54 0)
				(effects
					(font
						(size 1.27 1.27)
						(thickness 0.15)
					)
					(justify left bottom)
				)
			)
			(property "Manufacturer" "Texas Instruments"
				(at 15.24 -12.7 0)
				(effects
					(font
						(size 1.27 1.27)
						(thickness 0.15)
					)
					(justify left bottom)
					(hide yes)
				)
			)
			(property "Author" "Antmicro"
				(at 15.24 -15.24 0)
				(effects
					(font
						(size 1.27 1.27)
						(thickness 0.15)
					)
					(justify left bottom)
					(hide yes)
				)
			)
			(property "License" "Apache-2.0"
				(at 15.24 -17.78 0)
				(effects
					(font
						(size 1.27 1.27)
						(thickness 0.15)
					)
					(justify left bottom)
					(hide yes)
				)
			)
			(property "ki_keywords" "SMT, DIODE, SEMICONDUCTOR, TVS, ESD"
				(at 0 0 0)
				(effects
					(font
						(size 1.27 1.27)
					)
					(hide yes)
				)
			)
			(symbol "TPD2E009_SOT-9X3_1_1"
				(rectangle
					(start 2.54 2.54)
					(end 8.89 -7.62)
					(stroke
						(width 0.254)
						(type default)
					)
					(fill
						(type background)
					)
				)
				(polyline
					(pts
						(xy 2.54 0) (xy 7.62 0)
					)
					(stroke
						(width 0.254)
						(type default)
					)
					(fill
						(type background)
					)
				)
				(polyline
					(pts
						(xy 2.54 -2.54) (xy 7.62 -2.54)
					)
					(stroke
						(width 0.254)
						(type default)
					)
					(fill
						(type background)
					)
				)
				(polyline
					(pts
						(xy 4.826 -0.635) (xy 5.08 -0.381) (xy 5.08 0.381) (xy 5.334 0.635)
					)
					(stroke
						(width 0.254)
						(type default)
					)
					(fill
						(type background)
					)
				)
				(polyline
					(pts
						(xy 4.826 -3.175) (xy 5.08 -2.921) (xy 5.08 -2.159) (xy 5.334 -1.905)
					)
					(stroke
						(width 0.254)
						(type default)
					)
					(fill
						(type background)
					)
				)
				(polyline
					(pts
						(xy 5.08 0) (xy 3.81 -0.635) (xy 3.81 0.635) (xy 5.08 0)
					)
					(stroke
						(width 0.254)
						(type default)
					)
					(fill
						(type background)
					)
				)
				(polyline
					(pts
						(xy 5.08 0) (xy 6.35 0.635) (xy 6.35 -0.635) (xy 5.08 0)
					)
					(stroke
						(width 0.254)
						(type default)
					)
					(fill
						(type background)
					)
				)
				(polyline
					(pts
						(xy 5.08 -2.54) (xy 3.81 -3.175) (xy 3.81 -1.905) (xy 5.08 -2.54)
					)
					(stroke
						(width 0.254)
						(type default)
					)
					(fill
						(type background)
					)
				)
				(polyline
					(pts
						(xy 6.35 -1.905) (xy 6.35 -3.175) (xy 5.08 -2.54) (xy 6.35 -1.905)
					)
					(stroke
						(width 0.254)
						(type default)
					)
					(fill
						(type background)
					)
				)
				(circle
					(center 7.62 -2.54)
					(radius 0.254)
					(stroke
						(width 0.254)
						(type default)
					)
					(fill
						(type background)
					)
				)
				(polyline
					(pts
						(xy 7.62 -5.08) (xy 2.54 -5.08)
					)
					(stroke
						(width 0.254)
						(type default)
					)
					(fill
						(type background)
					)
				)
				(polyline
					(pts
						(xy 7.62 -5.08) (xy 7.62 0)
					)
					(stroke
						(width 0.254)
						(type default)
					)
					(fill
						(type background)
					)
				)
				(pin passive line
					(at 0 0 0)
					(length 2.54)
					(name "1"
						(effects
							(font
								(size 1.27 1.27)
							)
						)
					)
					(number "1"
						(effects
							(font
								(size 1.27 1.27)
							)
						)
					)
				)
				(pin passive line
					(at 0 -2.54 0)
					(length 2.54)
					(name "2"
						(effects
							(font
								(size 1.27 1.27)
							)
						)
					)
					(number "2"
						(effects
							(font
								(size 1.27 1.27)
							)
						)
					)
				)
				(pin passive line
					(at 0 -5.08 0)
					(length 2.54)
					(name "3"
						(effects
							(font
								(size 1.27 1.27)
							)
						)
					)
					(number "3"
						(effects
							(font
								(size 1.27 1.27)
							)
						)
					)
				)
			)
		)
	(symbol "antmicroTestPoints:TP_1mm_SMD"
			(pin_names
				(hide yes)
			)
			(exclude_from_sim no)
			(in_bom no)
			(on_board yes)
			(property "Reference" "TP"
				(at 15.24 -5.08 0)
				(effects
					(font
						(size 1.27 1.27)
						(thickness 0.15)
					)
					(justify left bottom)
				)
			)
			(property "Value" "TP_1mm_SMD"
				(at 15.24 -7.62 0)
				(effects
					(font
						(size 1.27 1.27)
						(thickness 0.15)
					)
					(justify left bottom)
					(hide yes)
				)
			)
			(property "Footprint" "antmicro-footprints:TP_SMD_1mm"
				(at 15.24 -10.16 0)
				(effects
					(font
						(size 1.27 1.27)
						(thickness 0.15)
					)
					(justify left bottom)
					(hide yes)
				)
			)
			(property "Datasheet" ""
				(at 17.78 -12.7 0)
				(effects
					(font
						(size 1.27 1.27)
						(thickness 0.15)
					)
					(justify left bottom)
					(hide yes)
				)
			)
			(property "Description" "Test point 1mm SMD"
				(at 15.24 -20.32 0)
				(effects
					(font
						(size 1.27 1.27)
					)
					(justify left bottom)
					(hide yes)
				)
			)
			(property "MPN" ""
				(at 0 0 0)
				(effects
					(font
						(size 1.27 1.27)
					)
					(hide yes)
				)
			)
			(property "Manufacturer" ""
				(at 0 0 0)
				(effects
					(font
						(size 1.27 1.27)
					)
					(hide yes)
				)
			)
			(property "Author" "Antmicro"
				(at 15.24 -15.24 0)
				(effects
					(font
						(size 1.27 1.27)
						(thickness 0.15)
					)
					(justify left bottom)
					(hide yes)
				)
			)
			(property "License" "Apache-2.0"
				(at 15.24 -17.78 0)
				(effects
					(font
						(size 1.27 1.27)
						(thickness 0.15)
					)
					(justify left bottom)
					(hide yes)
				)
			)
			(property "ki_keywords" "TESTPOINT"
				(at 0 0 0)
				(effects
					(font
						(size 1.27 1.27)
					)
					(hide yes)
				)
			)
			(symbol "TP_1mm_SMD_1_1"
				(circle
					(center 3.175 0)
					(radius 0.635)
					(stroke
						(width 0.254)
						(type default)
					)
					(fill
						(type none)
					)
				)
				(pin passive line
					(at 0 0 0)
					(length 2.54)
					(name "1"
						(effects
							(font
								(size 1.27 1.27)
							)
						)
					)
					(number "1"
						(effects
							(font
								(size 1.27 1.27)
							)
						)
					)
				)
			)
		)
	(symbol "antmicroTransistorsFETsMOSFETsSingle:2N7002_SOT-23-3"
			(pin_names
				(offset 0)
			)
			(exclude_from_sim no)
			(in_bom yes)
			(on_board yes)
			(property "Reference" "Q"
				(at 22.86 -5.08 0)
				(effects
					(font
						(size 1.27 1.27)
						(thickness 0.15)
					)
					(justify left bottom)
				)
			)
			(property "Value" "2N7002_SOT-23-3"
				(at 22.86 -7.62 0)
				(effects
					(font
						(size 1.27 1.27)
						(thickness 0.15)
					)
					(justify left bottom)
					(hide yes)
				)
			)
			(property "Footprint" "antmicro-footprints:SOT-23-3"
				(at 22.86 -10.16 0)
				(effects
					(font
						(size 1.27 1.27)
						(thickness 0.15)
					)
					(justify left bottom)
					(hide yes)
				)
			)
			(property "Datasheet" "https://www.onsemi.com/pub/Collateral/NDS7002A-D.PDF"
				(at 22.86 -12.7 0)
				(effects
					(font
						(size 1.27 1.27)
						(thickness 0.15)
					)
					(justify left bottom)
					(hide yes)
				)
			)
			(property "Description" "Power MOSFET, N Channel, 60 V, 115 mA, 1.2 ohm, SOT-23, Surface Mount"
				(at 22.86 -25.4 0)
				(effects
					(font
						(size 1.27 1.27)
					)
					(justify left bottom)
					(hide yes)
				)
			)
			(property "MPN" "2N7002"
				(at 22.86 -15.24 0)
				(effects
					(font
						(size 1.27 1.27)
						(thickness 0.15)
					)
					(justify left bottom)
				)
			)
			(property "Manufacturer" "ON Semiconductor"
				(at 22.86 -17.78 0)
				(effects
					(font
						(size 1.27 1.27)
						(thickness 0.15)
					)
					(justify left bottom)
					(hide yes)
				)
			)
			(property "Author" "Antmicro"
				(at 22.86 -20.32 0)
				(effects
					(font
						(size 1.27 1.27)
						(thickness 0.15)
					)
					(justify left bottom)
					(hide yes)
				)
			)
			(property "License" "Apache-2.0"
				(at 22.86 -22.86 0)
				(effects
					(font
						(size 1.27 1.27)
						(thickness 0.15)
					)
					(justify left bottom)
					(hide yes)
				)
			)
			(property "ki_keywords" "SMT, TRANSISTOR, SEMICONDUCTOR, NMOS"
				(at 0 0 0)
				(effects
					(font
						(size 1.27 1.27)
					)
					(hide yes)
				)
			)
			(symbol "2N7002_SOT-23-3_1_1"
				(polyline
					(pts
						(xy 2.54 0) (xy 4.572 0) (xy 4.572 3.937)
					)
					(stroke
						(width 0.254)
						(type default)
					)
					(fill
						(type none)
					)
				)
				(polyline
					(pts
						(xy 5.08 4.445) (xy 5.08 3.429)
					)
					(stroke
						(width 0.254)
						(type default)
					)
					(fill
						(type background)
					)
				)
				(polyline
					(pts
						(xy 5.08 2.54) (xy 5.08 3.048)
					)
					(stroke
						(width 0.254)
						(type default)
					)
					(fill
						(type background)
					)
				)
				(polyline
					(pts
						(xy 5.08 2.54) (xy 5.08 2.032)
					)
					(stroke
						(width 0.254)
						(type default)
					)
					(fill
						(type background)
					)
				)
				(polyline
					(pts
						(xy 5.08 2.54) (xy 5.842 3.048) (xy 5.842 2.032) (xy 5.08 2.54)
					)
					(stroke
						(width 0.254)
						(type default)
					)
					(fill
						(type outline)
					)
				)
				(polyline
					(pts
						(xy 5.08 1.143) (xy 5.08 1.651)
					)
					(stroke
						(width 0.254)
						(type default)
					)
					(fill
						(type background)
					)
				)
				(polyline
					(pts
						(xy 5.08 1.143) (xy 5.08 0.635)
					)
					(stroke
						(width 0.254)
						(type default)
					)
					(fill
						(type background)
					)
				)
				(circle
					(center 6.35 2.54)
					(radius 3.302)
					(stroke
						(width 0.254)
						(type default)
					)
					(fill
						(type background)
					)
				)
				(polyline
					(pts
						(xy 7.493 0.635) (xy 8.636 0.635) (xy 8.636 3.937) (xy 8.636 4.445) (xy 7.493 4.445)
					)
					(stroke
						(width 0.254)
						(type default)
					)
					(fill
						(type background)
					)
				)
				(polyline
					(pts
						(xy 7.62 6.35) (xy 7.62 3.937) (xy 5.08 3.937)
					)
					(stroke
						(width 0.254)
						(type default)
					)
					(fill
						(type none)
					)
				)
				(circle
					(center 7.62 4.445)
					(radius 0.127)
					(stroke
						(width 0.254)
						(type default)
					)
					(fill
						(type background)
					)
				)
				(polyline
					(pts
						(xy 7.62 1.143) (xy 5.08 1.143)
					)
					(stroke
						(width 0.254)
						(type default)
					)
					(fill
						(type background)
					)
				)
				(circle
					(center 7.62 1.143)
					(radius 0.127)
					(stroke
						(width 0.254)
						(type default)
					)
					(fill
						(type background)
					)
				)
				(circle
					(center 7.62 0.635)
					(radius 0.127)
					(stroke
						(width 0.254)
						(type default)
					)
					(fill
						(type background)
					)
				)
				(polyline
					(pts
						(xy 7.62 -1.27) (xy 7.62 2.54) (xy 5.08 2.54)
					)
					(stroke
						(width 0.254)
						(type default)
					)
					(fill
						(type none)
					)
				)
				(polyline
					(pts
						(xy 8.636 3.048) (xy 8.128 2.286) (xy 9.144 2.286) (xy 8.636 3.048)
					)
					(stroke
						(width 0.254)
						(type default)
					)
					(fill
						(type outline)
					)
				)
				(polyline
					(pts
						(xy 9.144 3.048) (xy 8.128 3.048)
					)
					(stroke
						(width 0.254)
						(type default)
					)
					(fill
						(type background)
					)
				)
				(pin input line
					(at 0 0 0)
					(length 2.54)
					(name "G"
						(effects
							(font
								(size 1.27 1.27)
							)
						)
					)
					(number "1"
						(effects
							(font
								(size 1.27 1.27)
							)
						)
					)
				)
				(pin passive line
					(at 7.62 8.89 270)
					(length 2.54)
					(name "D"
						(effects
							(font
								(size 1.27 1.27)
							)
						)
					)
					(number "3"
						(effects
							(font
								(size 1.27 1.27)
							)
						)
					)
				)
				(pin passive line
					(at 7.62 -3.81 90)
					(length 2.54)
					(name "S"
						(effects
							(font
								(size 1.27 1.27)
							)
						)
					)
					(number "2"
						(effects
							(font
								(size 1.27 1.27)
							)
						)
					)
				)
			)
		)
	(symbol "antmicroTransistorsFETsMOSFETsSingle:BSS138PW"
			(pin_names
				(offset 0)
			)
			(exclude_from_sim no)
			(in_bom yes)
			(on_board yes)
			(property "Reference" "Q"
				(at 3.81 -6.35 0)
				(effects
					(font
						(size 1.27 1.27)
						(thickness 0.15)
					)
					(justify left bottom)
				)
			)
			(property "Value" "BSS138PW"
				(at 22.86 -8.89 0)
				(effects
					(font
						(size 1.27 1.27)
						(thickness 0.15)
					)
					(justify left bottom)
					(hide yes)
				)
			)
			(property "Footprint" "antmicro-footprints:SC70-3"
				(at 22.86 -11.43 0)
				(effects
					(font
						(size 1.27 1.27)
						(thickness 0.15)
					)
					(justify left bottom)
					(hide yes)
				)
			)
			(property "Datasheet" "https://assets.nexperia.com/documents/data-sheet/BSS138PW.pdf"
				(at 22.86 -13.97 0)
				(effects
					(font
						(size 1.27 1.27)
						(thickness 0.15)
					)
					(justify left bottom)
					(hide yes)
				)
			)
			(property "Description" "Power MOSFET, N Channel, 60 V, 320 mA, 0.9 ohm, SOT-323, Surface Mount"
				(at 22.86 -26.67 0)
				(effects
					(font
						(size 1.27 1.27)
					)
					(justify left bottom)
					(hide yes)
				)
			)
			(property "MPN" "BSS138PW"
				(at 22.86 -16.51 0)
				(effects
					(font
						(size 1.27 1.27)
						(thickness 0.15)
					)
					(justify left bottom)
				)
			)
			(property "Manufacturer" "Nexperia"
				(at 22.86 -19.05 0)
				(effects
					(font
						(size 1.27 1.27)
						(thickness 0.15)
					)
					(justify left bottom)
					(hide yes)
				)
			)
			(property "Author" "Antmicro"
				(at 22.86 -21.59 0)
				(effects
					(font
						(size 1.27 1.27)
						(thickness 0.15)
					)
					(justify left bottom)
					(hide yes)
				)
			)
			(property "License" "Apache-2.0"
				(at 22.86 -24.13 0)
				(effects
					(font
						(size 1.27 1.27)
						(thickness 0.15)
					)
					(justify left bottom)
					(hide yes)
				)
			)
			(property "ki_keywords" "SMT, TRANSISTOR, SEMICONDUCTOR, MOSFET, NMOS"
				(at 0 0 0)
				(effects
					(font
						(size 1.27 1.27)
					)
					(hide yes)
				)
			)
			(symbol "BSS138PW_1_1"
				(polyline
					(pts
						(xy 2.54 0) (xy 4.572 0) (xy 4.572 3.937)
					)
					(stroke
						(width 0.254)
						(type default)
					)
					(fill
						(type none)
					)
				)
				(polyline
					(pts
						(xy 5.08 4.445) (xy 5.08 3.429)
					)
					(stroke
						(width 0.254)
						(type default)
					)
					(fill
						(type background)
					)
				)
				(polyline
					(pts
						(xy 5.08 2.54) (xy 5.08 3.048)
					)
					(stroke
						(width 0.254)
						(type default)
					)
					(fill
						(type background)
					)
				)
				(polyline
					(pts
						(xy 5.08 2.54) (xy 5.08 2.032)
					)
					(stroke
						(width 0.254)
						(type default)
					)
					(fill
						(type background)
					)
				)
				(polyline
					(pts
						(xy 5.08 2.54) (xy 5.842 3.048) (xy 5.842 2.032) (xy 5.08 2.54)
					)
					(stroke
						(width 0.254)
						(type default)
					)
					(fill
						(type outline)
					)
				)
				(polyline
					(pts
						(xy 5.08 1.143) (xy 5.08 1.651)
					)
					(stroke
						(width 0.254)
						(type default)
					)
					(fill
						(type background)
					)
				)
				(polyline
					(pts
						(xy 5.08 1.143) (xy 5.08 0.635)
					)
					(stroke
						(width 0.254)
						(type default)
					)
					(fill
						(type background)
					)
				)
				(circle
					(center 6.35 2.54)
					(radius 3.302)
					(stroke
						(width 0.254)
						(type default)
					)
					(fill
						(type background)
					)
				)
				(polyline
					(pts
						(xy 7.493 0.635) (xy 8.636 0.635) (xy 8.636 3.937) (xy 8.636 4.445) (xy 7.493 4.445)
					)
					(stroke
						(width 0.254)
						(type default)
					)
					(fill
						(type background)
					)
				)
				(polyline
					(pts
						(xy 7.62 6.35) (xy 7.62 3.937) (xy 5.08 3.937)
					)
					(stroke
						(width 0.254)
						(type default)
					)
					(fill
						(type background)
					)
				)
				(circle
					(center 7.62 4.445)
					(radius 0.127)
					(stroke
						(width 0.254)
						(type default)
					)
					(fill
						(type background)
					)
				)
				(polyline
					(pts
						(xy 7.62 1.143) (xy 5.08 1.143)
					)
					(stroke
						(width 0.254)
						(type default)
					)
					(fill
						(type background)
					)
				)
				(circle
					(center 7.62 1.143)
					(radius 0.127)
					(stroke
						(width 0.254)
						(type default)
					)
					(fill
						(type background)
					)
				)
				(circle
					(center 7.62 0.635)
					(radius 0.127)
					(stroke
						(width 0.254)
						(type default)
					)
					(fill
						(type background)
					)
				)
				(polyline
					(pts
						(xy 7.62 -1.27) (xy 7.62 2.54) (xy 5.08 2.54)
					)
					(stroke
						(width 0.254)
						(type default)
					)
					(fill
						(type background)
					)
				)
				(polyline
					(pts
						(xy 8.636 3.048) (xy 8.128 2.286) (xy 9.144 2.286) (xy 8.636 3.048)
					)
					(stroke
						(width 0.254)
						(type default)
					)
					(fill
						(type outline)
					)
				)
				(polyline
					(pts
						(xy 9.144 3.048) (xy 8.128 3.048)
					)
					(stroke
						(width 0.254)
						(type default)
					)
					(fill
						(type background)
					)
				)
				(pin input line
					(at 0 0 0)
					(length 2.54)
					(name "G"
						(effects
							(font
								(size 1.27 1.27)
							)
						)
					)
					(number "1"
						(effects
							(font
								(size 1.27 1.27)
							)
						)
					)
				)
				(pin passive line
					(at 7.62 8.89 270)
					(length 2.54)
					(name "D"
						(effects
							(font
								(size 1.27 1.27)
							)
						)
					)
					(number "3"
						(effects
							(font
								(size 1.27 1.27)
							)
						)
					)
				)
				(pin passive line
					(at 7.62 -3.81 90)
					(length 2.54)
					(name "S"
						(effects
							(font
								(size 1.27 1.27)
							)
						)
					)
					(number "2"
						(effects
							(font
								(size 1.27 1.27)
							)
						)
					)
				)
			)
		)
	(symbol "antmicroUSBConnectors:USB-Micro-B_Amphenol_10118192-0001LF"
			(exclude_from_sim no)
			(in_bom yes)
			(on_board yes)
			(property "Reference" "J"
				(at 33.02 -2.54 0)
				(effects
					(font
						(size 1.27 1.27)
						(thickness 0.15)
					)
					(justify left bottom)
				)
			)
			(property "Value" "USB-Micro-B_Amphenol_10118192-0001LF"
				(at 33.02 -5.08 0)
				(effects
					(font
						(size 1.27 1.27)
						(thickness 0.15)
					)
					(justify left bottom)
					(hide yes)
				)
			)
			(property "Footprint" "antmicro-footprints:USB-Micro-B_Receptacle_Amphenol_10118192"
				(at 33.02 -7.62 0)
				(effects
					(font
						(size 1.27 1.27)
						(thickness 0.15)
					)
					(justify left bottom)
					(hide yes)
				)
			)
			(property "Datasheet" "http://www.amphenol-icc.com/media/wysiwyg/files/drawing/10118192.pdf"
				(at 33.02 -10.16 0)
				(effects
					(font
						(size 1.27 1.27)
						(thickness 0.15)
					)
					(justify left bottom)
					(hide yes)
				)
			)
			(property "Description" "USB - micro B USB 2.0 Receptacle Connector 5 Position Surface Mount, Right Angle"
				(at 33.02 -25.4 0)
				(effects
					(font
						(size 1.27 1.27)
					)
					(justify left bottom)
					(hide yes)
				)
			)
			(property "MPN" "10118192-0001LF"
				(at 33.02 -12.7 0)
				(effects
					(font
						(size 1.27 1.27)
						(thickness 0.15)
					)
					(justify left bottom)
				)
			)
			(property "Manufacturer" "Amphenol"
				(at 33.02 -15.24 0)
				(effects
					(font
						(size 1.27 1.27)
						(thickness 0.15)
					)
					(justify left bottom)
					(hide yes)
				)
			)
			(property "Author" "Antmicro"
				(at 33.02 -20.32 0)
				(effects
					(font
						(size 1.27 1.27)
						(thickness 0.15)
					)
					(justify left bottom)
					(hide yes)
				)
			)
			(property "License" "Apache-2.0"
				(at 33.02 -22.86 0)
				(effects
					(font
						(size 1.27 1.27)
						(thickness 0.15)
					)
					(justify left bottom)
					(hide yes)
				)
			)
			(property "ki_keywords" "USB, MICRO, CONNECTOR, SMT, HORIZONTAL"
				(at 0 0 0)
				(effects
					(font
						(size 1.27 1.27)
					)
					(hide yes)
				)
			)
			(symbol "USB-Micro-B_Amphenol_10118192-0001LF_0_1"
				(polyline
					(pts
						(xy -13.97 -5.715) (xy -15.24 -6.985) (xy -15.24 -12.7)
					)
					(stroke
						(width 0.254)
						(type default)
					)
					(fill
						(type none)
					)
				)
				(polyline
					(pts
						(xy -13.97 -13.97) (xy -15.24 -12.7)
					)
					(stroke
						(width 0.254)
						(type default)
					)
					(fill
						(type none)
					)
				)
				(rectangle
					(start -13.335 -7.366)
					(end -13.97 -12.446)
					(stroke
						(width 0.127)
						(type default)
					)
					(fill
						(type outline)
					)
				)
				(polyline
					(pts
						(xy -12.7 -5.715) (xy -13.97 -5.715)
					)
					(stroke
						(width 0.254)
						(type default)
					)
					(fill
						(type none)
					)
				)
				(polyline
					(pts
						(xy -12.7 -13.97) (xy -13.97 -13.97)
					)
					(stroke
						(width 0.254)
						(type default)
					)
					(fill
						(type none)
					)
				)
				(polyline
					(pts
						(xy -12.7 -13.97) (xy -12.7 -5.715)
					)
					(stroke
						(width 0.254)
						(type default)
					)
					(fill
						(type none)
					)
				)
			)
			(symbol "USB-Micro-B_Amphenol_10118192-0001LF_1_1"
				(rectangle
					(start -21.59 2.54)
					(end -2.54 -22.86)
					(stroke
						(width 0.254)
						(type default)
					)
					(fill
						(type background)
					)
				)
				(circle
					(center -18.796 -10.414)
					(radius 0.284)
					(stroke
						(width 0.254)
						(type default)
					)
					(fill
						(type outline)
					)
				)
				(polyline
					(pts
						(xy -18.542 -8.763) (xy -17.907 -7.62) (xy -17.272 -8.763) (xy -18.542 -8.763)
					)
					(stroke
						(width 0.254)
						(type default)
					)
					(fill
						(type outline)
					)
				)
				(polyline
					(pts
						(xy -17.907 -11.938) (xy -17.018 -11.049) (xy -17.018 -10.414)
					)
					(stroke
						(width 0.254)
						(type default)
					)
					(fill
						(type background)
					)
				)
				(polyline
					(pts
						(xy -17.907 -12.319) (xy -18.796 -11.43) (xy -18.796 -10.795)
					)
					(stroke
						(width 0.254)
						(type default)
					)
					(fill
						(type background)
					)
				)
				(polyline
					(pts
						(xy -17.907 -13.081) (xy -17.907 -8.763)
					)
					(stroke
						(width 0.254)
						(type default)
					)
					(fill
						(type background)
					)
				)
				(circle
					(center -17.907 -13.208)
					(radius 0.5236)
					(stroke
						(width 0.254)
						(type default)
					)
					(fill
						(type outline)
					)
				)
				(rectangle
					(start -17.399 -10.414)
					(end -16.637 -9.652)
					(stroke
						(width 0.254)
						(type default)
					)
					(fill
						(type outline)
					)
				)
				(pin passive line
					(at 0 0 180)
					(length 2.54)
					(name "VBUS"
						(effects
							(font
								(size 1.27 1.27)
							)
						)
					)
					(number "1"
						(effects
							(font
								(size 1.27 1.27)
							)
						)
					)
				)
				(pin bidirectional line
					(at 0 -5.08 180)
					(length 2.54)
					(name "D+"
						(effects
							(font
								(size 1.27 1.27)
							)
						)
					)
					(number "3"
						(effects
							(font
								(size 1.27 1.27)
							)
						)
					)
				)
				(pin bidirectional line
					(at 0 -7.62 180)
					(length 2.54)
					(name "D-"
						(effects
							(font
								(size 1.27 1.27)
							)
						)
					)
					(number "2"
						(effects
							(font
								(size 1.27 1.27)
							)
						)
					)
				)
				(pin bidirectional line
					(at 0 -12.7 180)
					(length 2.54)
					(name "ID"
						(effects
							(font
								(size 1.27 1.27)
							)
						)
					)
					(number "4"
						(effects
							(font
								(size 1.27 1.27)
							)
						)
					)
				)
				(pin power_in line
					(at 0 -17.78 180)
					(length 2.54)
					(name "GND"
						(effects
							(font
								(size 1.27 1.27)
							)
						)
					)
					(number "5"
						(effects
							(font
								(size 1.27 1.27)
							)
						)
					)
				)
				(pin passive line
					(at 0 -20.32 180)
					(length 2.54)
					(name "SHIELD"
						(effects
							(font
								(size 1.27 1.27)
							)
						)
					)
					(number "SH"
						(effects
							(font
								(size 1.27 1.27)
							)
						)
					)
				)
			)
		)
	(symbol "antmicroWire2BoardConnectors:Molex_Pico-Lock_1x2_504050-0291"
			(pin_names
				(hide yes)
			)
			(exclude_from_sim no)
			(in_bom yes)
			(on_board yes)
			(property "Reference" "J"
				(at 8.89 0 0)
				(effects
					(font
						(size 1.27 1.27)
						(thickness 0.15)
					)
					(justify left bottom)
				)
			)
			(property "Value" "Molex_Pico-Lock_1x2_504050-0291"
				(at 8.89 -2.54 0)
				(effects
					(font
						(size 1.27 1.27)
						(thickness 0.15)
					)
					(justify left bottom)
					(hide yes)
				)
			)
			(property "Footprint" "antmicro-footprints:Conn_Molex_Pico-Lock_1x2_504050-0291"
				(at 8.89 -5.08 0)
				(effects
					(font
						(size 1.27 1.27)
						(thickness 0.15)
					)
					(justify left bottom)
					(hide yes)
				)
			)
			(property "Datasheet" "https://www.molex.com/en-us/products/part-detail-pdf/5040500291?display=pdf"
				(at 8.89 -7.62 0)
				(effects
					(font
						(size 1.27 1.27)
						(thickness 0.15)
					)
					(justify left bottom)
					(hide yes)
				)
			)
			(property "Description" "Connector Header Surface Mount, Right Angle 2 position 0.059\" (1.50mm)"
				(at 8.89 -20.32 0)
				(effects
					(font
						(size 1.27 1.27)
					)
					(justify left bottom)
					(hide yes)
				)
			)
			(property "Manufacturer" "Molex"
				(at 8.89 -10.16 0)
				(effects
					(font
						(size 1.27 1.27)
						(thickness 0.15)
					)
					(justify left bottom)
					(hide yes)
				)
			)
			(property "MPN" "504050-0291"
				(at 8.89 -12.7 0)
				(effects
					(font
						(size 1.27 1.27)
						(thickness 0.15)
					)
					(justify left bottom)
				)
			)
			(property "Author" "Antmicro"
				(at 8.89 -15.24 0)
				(effects
					(font
						(size 1.27 1.27)
						(thickness 0.15)
					)
					(justify left bottom)
					(hide yes)
				)
			)
			(property "License" "Apache-2.0"
				(at 8.89 -17.78 0)
				(effects
					(font
						(size 1.27 1.27)
						(thickness 0.15)
					)
					(justify left bottom)
					(hide yes)
				)
			)
			(property "ki_keywords" "CONNECTOR, HEADER, SMT"
				(at 0 0 0)
				(effects
					(font
						(size 1.27 1.27)
					)
					(hide yes)
				)
			)
			(symbol "Molex_Pico-Lock_1x2_504050-0291_1_1"
				(rectangle
					(start 3.81 1.27)
					(end 6.35 -8.89)
					(stroke
						(width 0.254)
						(type default)
					)
					(fill
						(type background)
					)
				)
				(rectangle
					(start 3.81 0.127)
					(end 5.08 -0.127)
					(stroke
						(width 0.254)
						(type default)
					)
					(fill
						(type background)
					)
				)
				(rectangle
					(start 3.81 -2.413)
					(end 5.08 -2.667)
					(stroke
						(width 0.254)
						(type default)
					)
					(fill
						(type background)
					)
				)
				(rectangle
					(start 3.81 -4.953)
					(end 5.08 -5.207)
					(stroke
						(width 0.254)
						(type default)
					)
					(fill
						(type background)
					)
				)
				(rectangle
					(start 3.81 -7.493)
					(end 5.08 -7.747)
					(stroke
						(width 0.254)
						(type default)
					)
					(fill
						(type background)
					)
				)
				(pin passive line
					(at 0 0 0)
					(length 3.81)
					(name "1"
						(effects
							(font
								(size 1.27 1.27)
							)
						)
					)
					(number "1"
						(effects
							(font
								(size 1.27 1.27)
							)
						)
					)
				)
				(pin passive line
					(at 0 -2.54 0)
					(length 3.81)
					(name "2"
						(effects
							(font
								(size 1.27 1.27)
							)
						)
					)
					(number "2"
						(effects
							(font
								(size 1.27 1.27)
							)
						)
					)
				)
				(pin passive line
					(at 0 -5.08 0)
					(length 3.81)
					(name "MP"
						(effects
							(font
								(size 1.27 1.27)
							)
						)
					)
					(number "MP1"
						(effects
							(font
								(size 1.27 1.27)
							)
						)
					)
				)
				(pin passive line
					(at 0 -7.62 0)
					(length 3.81)
					(name "MP2"
						(effects
							(font
								(size 1.27 1.27)
							)
						)
					)
					(number "MP2"
						(effects
							(font
								(size 1.27 1.27)
							)
						)
					)
				)
			)
		)
	(symbol "antmicropower:GND"
			(power)
			(pin_numbers
				(hide yes)
			)
			(pin_names
				(hide yes)
			)
			(exclude_from_sim no)
			(in_bom yes)
			(on_board yes)
			(property "Reference" "#PWR"
				(at 8.89 -2.54 0)
				(effects
					(font
						(size 1.27 1.27)
						(thickness 0.15)
					)
					(justify left bottom)
					(hide yes)
				)
			)
			(property "Value" "GND"
				(at 8.89 -5.08 0)
				(effects
					(font
						(size 1.27 1.27)
						(thickness 0.15)
					)
					(justify left bottom)
				)
			)
			(property "Footprint" ""
				(at 8.89 -7.62 0)
				(effects
					(font
						(size 1.27 1.27)
						(thickness 0.15)
					)
					(justify left bottom)
					(hide yes)
				)
			)
			(property "Datasheet" ""
				(at 8.89 -12.7 0)
				(effects
					(font
						(size 1.27 1.27)
						(thickness 0.15)
					)
					(justify left bottom)
					(hide yes)
				)
			)
			(property "Description" ""
				(at 8.89 -15.24 0)
				(effects
					(font
						(size 1.27 1.27)
					)
					(justify left bottom)
					(hide yes)
				)
			)
			(property "Author" "Antmicro"
				(at 8.89 -7.62 0)
				(effects
					(font
						(size 1.27 1.27)
						(thickness 0.15)
					)
					(justify left bottom)
					(hide yes)
				)
			)
			(property "License" "Apache-2.0"
				(at 8.89 -10.16 0)
				(effects
					(font
						(size 1.27 1.27)
						(thickness 0.15)
					)
					(justify left bottom)
					(hide yes)
				)
			)
			(symbol "GND_1_1"
				(polyline
					(pts
						(xy 0 0) (xy 0 -1.27) (xy 1.27 -1.27) (xy 0 -2.54) (xy -1.27 -1.27) (xy 0 -1.27)
					)
					(stroke
						(width 0)
						(type default)
					)
					(fill
						(type none)
					)
				)
				(pin power_in line
					(at 0 0 270)
					(length 0)
					(name "GND"
						(effects
							(font
								(size 1.27 1.27)
							)
						)
					)
					(number "1"
						(effects
							(font
								(size 1.27 1.27)
							)
						)
					)
				)
			)
		)
	(symbol "antmicropower:PWR_FLAG"
			(power)
			(pin_numbers
				(hide yes)
			)
			(pin_names
				(offset 0)
				(hide yes)
			)
			(exclude_from_sim no)
			(in_bom yes)
			(on_board yes)
			(property "Reference" "#FLG"
				(at 0 1.905 0)
				(effects
					(font
						(size 1.27 1.27)
					)
					(hide yes)
				)
			)
			(property "Value" "PWR_FLAG"
				(at 0 3.81 0)
				(effects
					(font
						(size 1.27 1.27)
					)
				)
			)
			(property "Footprint" ""
				(at 0 0 0)
				(effects
					(font
						(size 1.27 1.27)
					)
					(hide yes)
				)
			)
			(property "Datasheet" ""
				(at 0 0 0)
				(effects
					(font
						(size 1.27 1.27)
					)
					(hide yes)
				)
			)
			(property "Description" ""
				(at 0 -2.54 0)
				(effects
					(font
						(size 1.27 1.27)
					)
					(justify left bottom)
					(hide yes)
				)
			)
			(symbol "PWR_FLAG_0_0"
				(pin power_out line
					(at 0 0 90)
					(length 0)
					(name "pwr"
						(effects
							(font
								(size 1.27 1.27)
							)
						)
					)
					(number "1"
						(effects
							(font
								(size 1.27 1.27)
							)
						)
					)
				)
			)
			(symbol "PWR_FLAG_0_1"
				(polyline
					(pts
						(xy 0 0) (xy 0 1.27) (xy -1.016 1.905) (xy 0 2.54) (xy 1.016 1.905) (xy 0 1.27)
					)
					(stroke
						(width 0)
						(type default)
					)
					(fill
						(type none)
					)
				)
			)
		)
)
